G04 ================== begin FILE IDENTIFICATION RECORD ==================*
G04 Layout Name:  9127_F0T_Expander_BD_F_v02_0110_1240.brd*
G04 Film Name:    gnd5*
G04 File Format:  Gerber RS274X*
G04 File Origin:  Cadence Allegro 17.2-S081*
G04 Origin Date:  Wed Jan 11 16:06:30 2023*
G04 *
G04 Layer:  DRAWING FORMAT/TITLE_BLOCK_A*
G04 Layer:  PIN/SPECIAL_DRILL*
G04 Layer:  VIA CLASS/GND5*
G04 Layer:  PIN/GND5*
G04 Layer:  MANUFACTURING/PHOTOPLOT_OUTLINE*
G04 Layer:  ETCH/GND5*
G04 Layer:  DRAWING FORMAT/TITLE_BLOCK*
G04 Layer:  DRAWING FORMAT/TITLE_DATA_GND5*
G04 *
G04 Offset:    (0.00 0.00)*
G04 Mirror:    No*
G04 Mode:      Negative*
G04 Rotation:  0*
G04 FullContactRelief:  No*
G04 UndefLineWidth:     6.00*
G04 ================== end FILE IDENTIFICATION RECORD ====================*
%FSLAX25Y25*MOIN*%
%IR0*IPPOS*OFA0.00000B0.00000*MIA0B0*SFA1.00000B1.00000*%
%ADD15C,.03*%
%ADD53C,.06*%
%ADD23C,.024*%
%ADD54C,.061*%
%ADD33C,.0322*%
%ADD45C,.071*%
%ADD40C,.026*%
%AMMACRO28*
4,1,36,0.0,.01,
-.001736,.009848,
-.00342,.009397,
-.005,.00866,
-.006428,.00766,
-.00766,.006428,
-.00866,.005,
-.009397,.00342,
-.009848,.001736,
-.01,0.0,
-.009848,-.001736,
-.009397,-.00342,
-.00866,-.005,
-.00766,-.006428,
-.006428,-.00766,
-.005,-.00866,
-.00342,-.009397,
-.001736,-.009848,
0.0,-.01,
.001736,-.009848,
.00342,-.009397,
.005,-.00866,
.006428,-.00766,
.00766,-.006428,
.00866,-.005,
.009397,-.00342,
.009848,-.001736,
.01,0.0,
.009848,.001736,
.009397,.00342,
.00866,.005,
.00766,.006428,
.006428,.00766,
.005,.00866,
.00342,.009397,
.001736,.009848,
0.0,.01,
0.0*
%
%ADD28MACRO28*%
%ADD51C,.082*%
%ADD43C,.028*%
%AMMACRO38*
4,1,20,-.0075,-.05555,
-.0075,-.06273,
-.013677,-.060878,
-.019439,-.057981,
-.024611,-.054127,
-.029034,-.049434,
-.032576,-.044045,
-.035127,-.038122,
-.036612,-.031846,
-.037,-.0265,
-.037,-.0075,
-.03,-.0075,
-.03,-.0265,
-.029544,-.03171,
-.028191,-.036762,
-.02598,-.041502,
-.022981,-.045786,
-.019282,-.049484,
-.014998,-.052484,
-.010258,-.054694,
-.0075,-.05555,
270.*
4,1,20,.0075,-.06273,
.0075,-.05555,
.01243,-.053806,
.016983,-.051232,
.02102,-.047906,
.024418,-.043931,
.027073,-.039425,
.028906,-.034527,
.029861,-.029385,
.03,-.0265,
.03,-.0075,
.037,-.0075,
.037,-.0265,
.036438,-.032925,
.034769,-.039154,
.032043,-.044999,
.028344,-.050282,
.023784,-.054842,
.018501,-.058541,
.012656,-.061266,
.0075,-.06273,
270.*
4,1,20,-.0075,.06273,
-.0075,.05555,
-.01243,.053806,
-.016983,.051232,
-.02102,.047906,
-.024418,.043931,
-.027073,.039425,
-.028906,.034527,
-.029861,.029385,
-.03,.0265,
-.03,.0075,
-.037,.0075,
-.037,.0265,
-.036438,.032925,
-.034769,.039154,
-.032043,.044999,
-.028344,.050282,
-.023784,.054842,
-.018501,.058541,
-.012656,.061266,
-.0075,.06273,
270.*
4,1,20,.0075,.05555,
.0075,.06273,
.013677,.060878,
.019439,.057981,
.024611,.054127,
.029034,.049434,
.032576,.044045,
.035127,.038122,
.036612,.031846,
.037,.0265,
.037,.0075,
.03,.0075,
.03,.0265,
.029544,.03171,
.028191,.036762,
.02598,.041502,
.022981,.045786,
.019282,.049484,
.014998,.052484,
.010258,.054694,
.0075,.05555,
270.*
%
%ADD38MACRO38*%
%AMMACRO30*
4,1,36,.0025,0.0,
.002462,.000434,
.002349,.000855,
.002165,.00125,
.001915,.001607,
.001607,.001915,
.00125,.002165,
.000855,.002349,
.000434,.002462,
0.0,.0025,
-.000434,.002462,
-.000855,.002349,
-.00125,.002165,
-.001607,.001915,
-.001915,.001607,
-.002165,.00125,
-.002349,.000855,
-.002462,.000434,
-.0025,0.0,
-.002462,-.000434,
-.002349,-.000855,
-.002165,-.00125,
-.001915,-.001607,
-.001607,-.001915,
-.00125,-.002165,
-.000855,-.002349,
-.000434,-.002462,
0.0,-.0025,
.000434,-.002462,
.000855,-.002349,
.00125,-.002165,
.001607,-.001915,
.001915,-.001607,
.002165,-.00125,
.002349,-.000855,
.002462,-.000434,
.0025,0.0,
315.*
%
%ADD30MACRO30*%
%AMMACRO14*
4,1,36,.0025,0.0,
.002462,.000434,
.002349,.000855,
.002165,.00125,
.001915,.001607,
.001607,.001915,
.00125,.002165,
.000855,.002349,
.000434,.002462,
0.0,.0025,
-.000434,.002462,
-.000855,.002349,
-.00125,.002165,
-.001607,.001915,
-.001915,.001607,
-.002165,.00125,
-.002349,.000855,
-.002462,.000434,
-.0025,0.0,
-.002462,-.000434,
-.002349,-.000855,
-.002165,-.00125,
-.001915,-.001607,
-.001607,-.001915,
-.00125,-.002165,
-.000855,-.002349,
-.000434,-.002462,
0.0,-.0025,
.000434,-.002462,
.000855,-.002349,
.00125,-.002165,
.001607,-.001915,
.001915,-.001607,
.002165,-.00125,
.002349,-.000855,
.002462,-.000434,
.0025,0.0,
180.*
%
%ADD14MACRO14*%
%AMMACRO10*
4,1,36,.0025,0.0,
.002462,.000434,
.002349,.000855,
.002165,.00125,
.001915,.001607,
.001607,.001915,
.00125,.002165,
.000855,.002349,
.000434,.002462,
0.0,.0025,
-.000434,.002462,
-.000855,.002349,
-.00125,.002165,
-.001607,.001915,
-.001915,.001607,
-.002165,.00125,
-.002349,.000855,
-.002462,.000434,
-.0025,0.0,
-.002462,-.000434,
-.002349,-.000855,
-.002165,-.00125,
-.001915,-.001607,
-.001607,-.001915,
-.00125,-.002165,
-.000855,-.002349,
-.000434,-.002462,
0.0,-.0025,
.000434,-.002462,
.000855,-.002349,
.00125,-.002165,
.001607,-.001915,
.001915,-.001607,
.002165,-.00125,
.002349,-.000855,
.002462,-.000434,
.0025,0.0,
270.*
%
%ADD10MACRO10*%
%AMMACRO46*
4,1,36,-.0025,0.0,
-.002462,.000434,
-.002349,.000855,
-.002165,.00125,
-.001915,.001607,
-.001607,.001915,
-.00125,.002165,
-.000855,.002349,
-.000434,.002462,
0.0,.0025,
.000434,.002462,
.000855,.002349,
.00125,.002165,
.001607,.001915,
.001915,.001607,
.002165,.00125,
.002349,.000855,
.002462,.000434,
.0025,0.0,
.002462,-.000434,
.002349,-.000855,
.002165,-.00125,
.001915,-.001607,
.001607,-.001915,
.00125,-.002165,
.000855,-.002349,
.000434,-.002462,
0.0,-.0025,
-.000434,-.002462,
-.000855,-.002349,
-.00125,-.002165,
-.001607,-.001915,
-.001915,-.001607,
-.002165,-.00125,
-.002349,-.000855,
-.002462,-.000434,
-.0025,0.0,
180.*
%
%ADD46MACRO46*%
%AMMACRO36*
4,1,36,.003,0.0,
.002954,.000521,
.002819,.001026,
.002598,.0015,
.002298,.001928,
.001928,.002298,
.0015,.002598,
.001026,.002819,
.000521,.002954,
0.0,.003,
-.000521,.002954,
-.001026,.002819,
-.0015,.002598,
-.001928,.002298,
-.002298,.001928,
-.002598,.0015,
-.002819,.001026,
-.002954,.000521,
-.003,0.0,
-.002954,-.000521,
-.002819,-.001026,
-.002598,-.0015,
-.002298,-.001928,
-.001928,-.002298,
-.0015,-.002598,
-.001026,-.002819,
-.000521,-.002954,
0.0,-.003,
.000521,-.002954,
.001026,-.002819,
.0015,-.002598,
.001928,-.002298,
.002298,-.001928,
.002598,-.0015,
.002819,-.001026,
.002954,-.000521,
.003,0.0,
270.*
%
%ADD36MACRO36*%
%AMMACRO25*
4,1,36,.003,0.0,
.002954,.000521,
.002819,.001026,
.002598,.0015,
.002298,.001928,
.001928,.002298,
.0015,.002598,
.001026,.002819,
.000521,.002954,
0.0,.003,
-.000521,.002954,
-.001026,.002819,
-.0015,.002598,
-.001928,.002298,
-.002298,.001928,
-.002598,.0015,
-.002819,.001026,
-.002954,.000521,
-.003,0.0,
-.002954,-.000521,
-.002819,-.001026,
-.002598,-.0015,
-.002298,-.001928,
-.001928,-.002298,
-.0015,-.002598,
-.001026,-.002819,
-.000521,-.002954,
0.0,-.003,
.000521,-.002954,
.001026,-.002819,
.0015,-.002598,
.001928,-.002298,
.002298,-.001928,
.002598,-.0015,
.002819,-.001026,
.002954,-.000521,
.003,0.0,
180.*
%
%ADD25MACRO25*%
%ADD22C,.074*%
%AMMACRO42*
4,1,36,-.003,0.0,
-.002954,.000521,
-.002819,.001026,
-.002598,.0015,
-.002298,.001928,
-.001928,.002298,
-.0015,.002598,
-.001026,.002819,
-.000521,.002954,
0.0,.003,
.000521,.002954,
.001026,.002819,
.0015,.002598,
.001928,.002298,
.002298,.001928,
.002598,.0015,
.002819,.001026,
.002954,.000521,
.003,0.0,
.002954,-.000521,
.002819,-.001026,
.002598,-.0015,
.002298,-.001928,
.001928,-.002298,
.0015,-.002598,
.001026,-.002819,
.000521,-.002954,
0.0,-.003,
-.000521,-.002954,
-.001026,-.002819,
-.0015,-.002598,
-.001928,-.002298,
-.002298,-.001928,
-.002598,-.0015,
-.002819,-.001026,
-.002954,-.000521,
-.003,0.0,
180.*
%
%ADD42MACRO42*%
%ADD26C,.0435*%
%ADD34C,.0257*%
%ADD58C,.087*%
%ADD18C,.0277*%
%AMMACRO44*
4,1,18,.09673,.06845,
.107147,.050613,
.114308,.031238,
.117996,.010914,
.118098,-.009741,
.114613,-.030101,
.107644,-.049546,
.097406,-.067485,
.09673,-.06845,
.10175,-.07347,
.112962,-.054685,
.120742,-.034239,
.124853,-.012752,
.125171,.009122,
.121685,.030719,
.114502,.051383,
.10384,.070486,
.10175,.07347,
.09673,.06845,
90.*
4,1,18,.06845,-.09673,
.050613,-.107147,
.031238,-.114308,
.010914,-.117996,
-.009741,-.118098,
-.030101,-.114613,
-.049546,-.107644,
-.067485,-.097406,
-.06845,-.09673,
-.07347,-.10175,
-.054685,-.112962,
-.034239,-.120742,
-.012752,-.124853,
.009122,-.125171,
.030719,-.121685,
.051383,-.114502,
.070486,-.10384,
.07347,-.10175,
.06845,-.09673,
90.*
4,1,18,-.09673,-.06845,
-.107147,-.050613,
-.114308,-.031238,
-.117996,-.010914,
-.118098,.009741,
-.114613,.030101,
-.107644,.049546,
-.097406,.067485,
-.09673,.06845,
-.10175,.07347,
-.112962,.054685,
-.120742,.034239,
-.124853,.012752,
-.125171,-.009122,
-.121685,-.030719,
-.114502,-.051383,
-.10384,-.070486,
-.10175,-.07347,
-.09673,-.06845,
90.*
4,1,18,-.06845,.09673,
-.050613,.107147,
-.031238,.114308,
-.010914,.117996,
.009741,.118098,
.030101,.114613,
.049546,.107644,
.067485,.097406,
.06845,.09673,
.07347,.10175,
.054685,.112962,
.034239,.120742,
.012752,.124853,
-.009122,.125171,
-.030719,.121685,
-.051383,.114502,
-.070486,.10384,
-.07347,.10175,
-.06845,.09673,
90.*
%
%ADD44MACRO44*%
%AMMACRO11*
4,1,15,.06231,.03403,
.067273,.022693,
.070191,.010666,
.070977,-.001684,
.069606,-.013984,
.066121,-.025858,
.06231,-.03403,
.06745,-.03917,
.073227,-.026862,
.076779,-.013739,
.077998,-.000197,
.076848,.01335,
.073362,.026492,
.067647,.038828,
.06745,.03917,
.06231,.03403,
0.0*
4,1,15,.03403,-.06231,
.022693,-.067273,
.010666,-.070191,
-.001684,-.070977,
-.013984,-.069606,
-.025858,-.066121,
-.03403,-.06231,
-.03917,-.06745,
-.026862,-.073227,
-.013739,-.076779,
-.000197,-.077998,
.01335,-.076848,
.026492,-.073362,
.038828,-.067647,
.03917,-.06745,
.03403,-.06231,
0.0*
4,1,15,-.06231,-.03403,
-.067273,-.022693,
-.070191,-.010666,
-.070977,.001684,
-.069606,.013984,
-.066121,.025858,
-.06231,.03403,
-.06745,.03917,
-.073227,.026862,
-.076779,.013739,
-.077998,.000197,
-.076848,-.01335,
-.073362,-.026492,
-.067647,-.038828,
-.06745,-.03917,
-.06231,-.03403,
0.0*
4,1,15,-.03403,.06231,
-.022693,.067273,
-.010666,.070191,
.001684,.070977,
.013984,.069606,
.025858,.066121,
.03403,.06231,
.03917,.06745,
.026862,.073227,
.013739,.076779,
.000197,.077998,
-.01335,.076848,
-.026492,.073362,
-.038828,.067647,
-.03917,.06745,
-.03403,.06231,
0.0*
%
%ADD11MACRO11*%
%ADD20C,.099*%
%AMMACRO19*
4,1,18,.09673,.06845,
.107147,.050613,
.114308,.031238,
.117996,.010914,
.118098,-.009741,
.114613,-.030101,
.107644,-.049546,
.097406,-.067485,
.09673,-.06845,
.10175,-.07347,
.112962,-.054685,
.120742,-.034239,
.124853,-.012752,
.125171,.009122,
.121685,.030719,
.114502,.051383,
.10384,.070486,
.10175,.07347,
.09673,.06845,
0.0*
4,1,18,.06845,-.09673,
.050613,-.107147,
.031238,-.114308,
.010914,-.117996,
-.009741,-.118098,
-.030101,-.114613,
-.049546,-.107644,
-.067485,-.097406,
-.06845,-.09673,
-.07347,-.10175,
-.054685,-.112962,
-.034239,-.120742,
-.012752,-.124853,
.009122,-.125171,
.030719,-.121685,
.051383,-.114502,
.070486,-.10384,
.07347,-.10175,
.06845,-.09673,
0.0*
4,1,18,-.09673,-.06845,
-.107147,-.050613,
-.114308,-.031238,
-.117996,-.010914,
-.118098,.009741,
-.114613,.030101,
-.107644,.049546,
-.097406,.067485,
-.09673,.06845,
-.10175,.07347,
-.112962,.054685,
-.120742,.034239,
-.124853,.012752,
-.125171,-.009122,
-.121685,-.030719,
-.114502,-.051383,
-.10384,-.070486,
-.10175,-.07347,
-.09673,-.06845,
0.0*
4,1,18,-.06845,.09673,
-.050613,.107147,
-.031238,.114308,
-.010914,.117996,
.009741,.118098,
.030101,.114613,
.049546,.107644,
.067485,.097406,
.06845,.09673,
.07347,.10175,
.054685,.112962,
.034239,.120742,
.012752,.124853,
-.009122,.125171,
-.030719,.121685,
-.051383,.114502,
-.070486,.10384,
-.07347,.10175,
-.06845,.09673,
0.0*
%
%ADD19MACRO19*%
%ADD32C,.0299*%
%AMMACRO61*
4,1,19,-.0075,-.03785,
-.011528,-.036185,
-.015205,-.033846,
-.01842,-.030904,
-.021075,-.027448,
-.02309,-.023584,
-.024404,-.019428,
-.024975,-.015108,
-.025,-.014,
-.025,-.0075,
-.018,-.0075,
-.018,-.014,
-.017727,-.017125,
-.016915,-.020155,
-.015589,-.022998,
-.01379,-.025567,
-.011572,-.027785,
-.009002,-.029584,
-.0075,-.03036,
-.0075,-.03785,
180.*
4,1,19,.0075,-.03785,
.0075,-.03036,
.010227,-.02881,
.012643,-.02681,
.014676,-.024421,
.016262,-.021715,
.017355,-.018774,
.017921,-.015689,
.018,-.014,
.018,-.0075,
.025,-.0075,
.025,-.014,
.02462,-.018342,
.023492,-.022551,
.02165,-.026501,
.019151,-.030071,
.016069,-.033153,
.012499,-.035652,
.008549,-.037494,
.0075,-.03785,
180.*
4,1,19,-.025,.0075,
-.025,.014,
-.02462,.018342,
-.023492,.022551,
-.02165,.026501,
-.019151,.030071,
-.016069,.033153,
-.012499,.035652,
-.008549,.037494,
-.0075,.03785,
-.0075,.03036,
-.010227,.02881,
-.012643,.02681,
-.014676,.024421,
-.016262,.021715,
-.017355,.018774,
-.017921,.015689,
-.018,.014,
-.018,.0075,
-.025,.0075,
180.*
4,1,19,.018,.0075,
.018,.014,
.017727,.017125,
.016915,.020155,
.015589,.022998,
.01379,.025567,
.011572,.027785,
.009002,.029584,
.0075,.03036,
.0075,.03785,
.011528,.036185,
.015205,.033846,
.01842,.030904,
.021075,.027448,
.02309,.023584,
.024404,.019428,
.024975,.015108,
.025,.014,
.025,.0075,
.018,.0075,
180.*
%
%ADD61MACRO61*%
%AMMACRO37*
4,1,16,.02584,.01524,
.028094,.010521,
.029494,.005483,
.029998,.000278,
.029591,-.004935,
.028284,-.009999,
.026118,-.014758,
.02584,-.01524,
.03092,-.02032,
.033979,-.014642,
.036005,-.008519,
.036938,-.002138,
.036748,.004309,
.035441,.010625,
.033058,.016618,
.03092,.02032,
.02584,.01524,
0.0*
4,1,16,.01524,-.02584,
.010521,-.028094,
.005483,-.029494,
.000278,-.029998,
-.004935,-.029591,
-.009999,-.028284,
-.014758,-.026118,
-.01524,-.02584,
-.02032,-.03092,
-.014642,-.033979,
-.008519,-.036005,
-.002138,-.036938,
.004309,-.036748,
.010625,-.035441,
.016618,-.033058,
.02032,-.03092,
.01524,-.02584,
0.0*
4,1,16,-.02584,-.01524,
-.028094,-.010521,
-.029494,-.005483,
-.029998,-.000278,
-.029591,.004935,
-.028284,.009999,
-.026118,.014758,
-.02584,.01524,
-.03092,.02032,
-.033979,.014642,
-.036005,.008519,
-.036938,.002138,
-.036748,-.004309,
-.035441,-.010625,
-.033058,-.016618,
-.03092,-.02032,
-.02584,-.01524,
0.0*
4,1,16,-.01524,.02584,
-.010521,.028094,
-.005483,.029494,
-.000278,.029998,
.004935,.029591,
.009999,.028284,
.014758,.026118,
.01524,.02584,
.02032,.03092,
.014642,.033979,
.008519,.036005,
.002138,.036938,
-.004309,.036748,
-.010625,.035441,
-.016618,.033058,
-.02032,.03092,
-.01524,.02584,
0.0*
%
%ADD37MACRO37*%
%AMMACRO50*
4,1,15,.02142,.01082,
.022973,.006936,
.023829,.002841,
.02396,-.00134,
.023364,-.00548,
.022057,-.009454,
.02142,-.01082,
.02657,-.01597,
.02894,-.011114,
.03043,-.005919,
.030995,-.000545,
.030619,.004845,
.029313,.010088,
.027115,.015025,
.02657,.01597,
.02142,.01082,
90.*
4,1,15,.01082,-.02142,
.006936,-.022973,
.002841,-.023829,
-.00134,-.02396,
-.00548,-.023364,
-.009454,-.022057,
-.01082,-.02142,
-.01597,-.02657,
-.011114,-.02894,
-.005919,-.03043,
-.000545,-.030995,
.004845,-.030619,
.010088,-.029313,
.015025,-.027115,
.01597,-.02657,
.01082,-.02142,
90.*
4,1,15,-.02142,-.01082,
-.022973,-.006936,
-.023829,-.002841,
-.02396,.00134,
-.023364,.00548,
-.022057,.009454,
-.02142,.01082,
-.02657,.01597,
-.02894,.011114,
-.03043,.005919,
-.030995,.000545,
-.030619,-.004845,
-.029313,-.010088,
-.027115,-.015025,
-.02657,-.01597,
-.02142,-.01082,
90.*
4,1,15,-.01082,.02142,
-.006936,.022973,
-.002841,.023829,
.00134,.02396,
.00548,.023364,
.009454,.022057,
.01082,.02142,
.01597,.02657,
.011114,.02894,
.005919,.03043,
.000545,.030995,
-.004845,.030619,
-.010088,.029313,
-.015025,.027115,
-.01597,.02657,
-.01082,.02142,
90.*
%
%ADD50MACRO50*%
%AMMACRO48*
4,1,18,.07103,.05689,
.07983,.043691,
.086204,.029165,
.089959,.013753,
.09098,-.002077,
.089237,-.017844,
.084783,-.033069,
.077753,-.047289,
.07103,-.05689,
.07601,-.06186,
.085597,-.047721,
.092583,-.032132,
.096757,-.015567,
.09799,.001471,
.096246,.018464,
.091577,.034897,
.084126,.050269,
.07601,.06186,
.07103,.05689,
90.*
4,1,18,.05689,-.07103,
.043691,-.07983,
.029165,-.086204,
.013753,-.089959,
-.002077,-.09098,
-.017844,-.089237,
-.033069,-.084783,
-.047289,-.077753,
-.05689,-.07103,
-.06186,-.07601,
-.047721,-.085597,
-.032132,-.092583,
-.015567,-.096757,
.001471,-.09799,
.018464,-.096246,
.034897,-.091577,
.050269,-.084126,
.06186,-.07601,
.05689,-.07103,
90.*
4,1,18,-.07103,-.05689,
-.07983,-.043691,
-.086204,-.029165,
-.089959,-.013753,
-.09098,.002077,
-.089237,.017844,
-.084783,.033069,
-.077753,.047289,
-.07103,.05689,
-.07601,.06186,
-.085597,.047721,
-.092583,.032132,
-.096757,.015567,
-.09799,-.001471,
-.096246,-.018464,
-.091577,-.034897,
-.084126,-.050269,
-.07601,-.06186,
-.07103,-.05689,
90.*
4,1,18,-.05689,.07103,
-.043691,.07983,
-.029165,.086204,
-.013753,.089959,
.002077,.09098,
.017844,.089237,
.033069,.084783,
.047289,.077753,
.05689,.07103,
.06186,.07601,
.047721,.085597,
.032132,.092583,
.015567,.096757,
-.001471,.09799,
-.018464,.096246,
-.034897,.091577,
-.050269,.084126,
-.06186,.07601,
-.05689,.07103,
90.*
%
%ADD48MACRO48*%
%AMMACRO62*
4,1,19,-.0075,-.04535,
-.011528,-.043685,
-.015205,-.041346,
-.01842,-.038404,
-.021075,-.034948,
-.02309,-.031084,
-.024404,-.026928,
-.024975,-.022608,
-.025,-.0215,
-.025,-.0075,
-.018,-.0075,
-.018,-.0215,
-.017727,-.024625,
-.016915,-.027655,
-.015589,-.030498,
-.01379,-.033067,
-.011572,-.035285,
-.009002,-.037084,
-.0075,-.03786,
-.0075,-.04535,
180.*
4,1,19,.0075,-.04535,
.0075,-.03786,
.010227,-.03631,
.012643,-.03431,
.014676,-.031921,
.016262,-.029215,
.017355,-.026274,
.017921,-.023189,
.018,-.0215,
.018,-.0075,
.025,-.0075,
.025,-.0215,
.02462,-.025842,
.023492,-.030051,
.02165,-.034001,
.019151,-.037571,
.016069,-.040653,
.012499,-.043152,
.008549,-.044994,
.0075,-.04535,
180.*
4,1,19,-.025,.0075,
-.025,.0215,
-.02462,.025842,
-.023492,.030051,
-.02165,.034001,
-.019151,.037571,
-.016069,.040653,
-.012499,.043152,
-.008549,.044994,
-.0075,.04535,
-.0075,.03786,
-.010227,.03631,
-.012643,.03431,
-.014676,.031921,
-.016262,.029215,
-.017355,.026274,
-.017921,.023189,
-.018,.0215,
-.018,.0075,
-.025,.0075,
180.*
4,1,19,.018,.0075,
.018,.0215,
.017727,.024625,
.016915,.027655,
.015589,.030498,
.01379,.033067,
.011572,.035285,
.009002,.037084,
.0075,.03786,
.0075,.04535,
.011528,.043685,
.015205,.041346,
.01842,.038404,
.021075,.034948,
.02309,.031084,
.024404,.026928,
.024975,.022608,
.025,.0215,
.025,.0075,
.018,.0075,
180.*
%
%ADD62MACRO62*%
%AMMACRO55*
4,1,15,.02475,.01414,
.026829,.009627,
.028094,.004822,
.028504,-.000129,
.028049,-.005077,
.026741,-.009871,
.02475,-.01414,
.02984,-.01923,
.032726,-.013756,
.034617,-.007864,
.035457,-.001734,
.03522,.00445,
.033912,.010498,
.031574,.016227,
.02984,.01923,
.02475,.01414,
0.0*
4,1,15,.01414,-.02475,
.009627,-.026829,
.004822,-.028094,
-.000129,-.028504,
-.005077,-.028049,
-.009871,-.026741,
-.01414,-.02475,
-.01923,-.02984,
-.013756,-.032726,
-.007864,-.034617,
-.001734,-.035457,
.00445,-.03522,
.010498,-.033912,
.016227,-.031574,
.01923,-.02984,
.01414,-.02475,
0.0*
4,1,15,-.02475,-.01414,
-.026829,-.009627,
-.028094,-.004822,
-.028504,.000129,
-.028049,.005077,
-.026741,.009871,
-.02475,.01414,
-.02984,.01923,
-.032726,.013756,
-.034617,.007864,
-.035457,.001734,
-.03522,-.00445,
-.033912,-.010498,
-.031574,-.016227,
-.02984,-.01923,
-.02475,-.01414,
0.0*
4,1,15,-.01414,.02475,
-.009627,.026829,
-.004822,.028094,
.000129,.028504,
.005077,.028049,
.009871,.026741,
.01414,.02475,
.01923,.02984,
.013756,.032726,
.007864,.034617,
.001734,.035457,
-.00445,.03522,
-.010498,.033912,
-.016227,.031574,
-.01923,.02984,
-.01414,.02475,
0.0*
%
%ADD55MACRO55*%
%AMMACRO59*
4,1,15,.03682,.01914,
.039584,.012455,
.041146,.005393,
.041457,-.001834,
.040509,-.009005,
.03833,-.015903,
.03682,-.01914,
.04197,-.0243,
.045552,-.016643,
.04775,-.00848,
.048497,-.000059,
.047771,.008363,
.045593,.016531,
.042029,.024197,
.04197,.0243,
.03682,.01914,
90.*
4,1,15,.01914,-.03682,
.012455,-.039584,
.005393,-.041146,
-.001834,-.041457,
-.009005,-.040509,
-.015903,-.03833,
-.01914,-.03682,
-.0243,-.04197,
-.016643,-.045552,
-.00848,-.04775,
-.000059,-.048497,
.008363,-.047771,
.016531,-.045593,
.024197,-.042029,
.0243,-.04197,
.01914,-.03682,
90.*
4,1,15,-.03682,-.01914,
-.039584,-.012455,
-.041146,-.005393,
-.041457,.001834,
-.040509,.009005,
-.03833,.015903,
-.03682,.01914,
-.04197,.0243,
-.045552,.016643,
-.04775,.00848,
-.048497,.000059,
-.047771,-.008363,
-.045593,-.016531,
-.042029,-.024197,
-.04197,-.0243,
-.03682,-.01914,
90.*
4,1,15,-.01914,.03682,
-.012455,.039584,
-.005393,.041146,
.001834,.041457,
.009005,.040509,
.015903,.03833,
.01914,.03682,
.0243,.04197,
.016643,.045552,
.00848,.04775,
.000059,.048497,
-.008363,.047771,
-.016531,.045593,
-.024197,.042029,
-.0243,.04197,
-.01914,.03682,
90.*
%
%ADD59MACRO59*%
%AMMACRO60*
4,1,15,-.03682,.01914,
-.039584,.012455,
-.041146,.005393,
-.041457,-.001834,
-.040509,-.009005,
-.03833,-.015903,
-.03682,-.01914,
-.04197,-.0243,
-.045552,-.016643,
-.04775,-.00848,
-.048497,-.000059,
-.047771,.008363,
-.045593,.016531,
-.042029,.024197,
-.04197,.0243,
-.03682,.01914,
90.*
4,1,15,-.01914,-.03682,
-.012455,-.039584,
-.005393,-.041146,
.001834,-.041457,
.009005,-.040509,
.015903,-.03833,
.01914,-.03682,
.0243,-.04197,
.016643,-.045552,
.00848,-.04775,
.000059,-.048497,
-.008363,-.047771,
-.016531,-.045593,
-.024197,-.042029,
-.0243,-.04197,
-.01914,-.03682,
90.*
4,1,15,.03682,-.01914,
.039584,-.012455,
.041146,-.005393,
.041457,.001834,
.040509,.009005,
.03833,.015903,
.03682,.01914,
.04197,.0243,
.045552,.016643,
.04775,.00848,
.048497,.000059,
.047771,-.008363,
.045593,-.016531,
.042029,-.024197,
.04197,-.0243,
.03682,-.01914,
90.*
4,1,15,.01914,.03682,
.012455,.039584,
.005393,.041146,
-.001834,.041457,
-.009005,.040509,
-.015903,.03833,
-.01914,.03682,
-.0243,.04197,
-.016643,.045552,
-.00848,.04775,
-.000059,.048497,
.008363,.047771,
.016531,.045593,
.024197,.042029,
.0243,.04197,
.01914,.03682,
90.*
%
%ADD60MACRO60*%
%ADD63C,.142*%
%ADD13C,.125*%
%ADD29C,.208*%
%ADD47C,.164*%
%ADD17C,.155*%
%ADD39C,.256*%
%AMMACRO31*
4,1,36,0.0,.0085,
.001476,.008371,
.002907,.007987,
.00425,.007361,
.005464,.006511,
.006511,.005464,
.007361,.00425,
.007987,.002907,
.008371,.001476,
.0085,0.0,
.008371,-.001476,
.007987,-.002907,
.007361,-.00425,
.006511,-.005464,
.005464,-.006511,
.00425,-.007361,
.002907,-.007987,
.001476,-.008371,
0.0,-.0085,
-.001476,-.008371,
-.002907,-.007987,
-.00425,-.007361,
-.005464,-.006511,
-.006511,-.005464,
-.007361,-.00425,
-.007987,-.002907,
-.008371,-.001476,
-.0085,0.0,
-.008371,.001476,
-.007987,.002907,
-.007361,.00425,
-.006511,.005464,
-.005464,.006511,
-.00425,.007361,
-.002907,.007987,
-.001476,.008371,
0.0,.0085,
180.*
%
%ADD31MACRO31*%
%AMMACRO49*
4,1,36,0.0,.0185,
-.003212,.018219,
-.006327,.017384,
-.00925,.016021,
-.011892,.014172,
-.014172,.011892,
-.016021,.00925,
-.017384,.006327,
-.018219,.003212,
-.0185,0.0,
-.018219,-.003212,
-.017384,-.006327,
-.016021,-.00925,
-.014172,-.011892,
-.011892,-.014172,
-.00925,-.016021,
-.006327,-.017384,
-.003212,-.018219,
0.0,-.0185,
.003212,-.018219,
.006327,-.017384,
.00925,-.016021,
.011892,-.014172,
.014172,-.011892,
.016021,-.00925,
.017384,-.006327,
.018219,-.003212,
.0185,0.0,
.018219,.003212,
.017384,.006327,
.016021,.00925,
.014172,.011892,
.011892,.014172,
.00925,.016021,
.006327,.017384,
.003212,.018219,
0.0,.0185,
270.*
%
%ADD49MACRO49*%
%AMMACRO21*
4,1,20,-.0075,-.05555,
-.0075,-.06273,
-.013677,-.060878,
-.019439,-.057981,
-.024611,-.054127,
-.029034,-.049434,
-.032576,-.044045,
-.035127,-.038122,
-.036612,-.031846,
-.037,-.0265,
-.037,-.0075,
-.03,-.0075,
-.03,-.0265,
-.029544,-.03171,
-.028191,-.036762,
-.02598,-.041502,
-.022981,-.045786,
-.019282,-.049484,
-.014998,-.052484,
-.010258,-.054694,
-.0075,-.05555,
90.*
4,1,20,.0075,-.06273,
.0075,-.05555,
.01243,-.053806,
.016983,-.051232,
.02102,-.047906,
.024418,-.043931,
.027073,-.039425,
.028906,-.034527,
.029861,-.029385,
.03,-.0265,
.03,-.0075,
.037,-.0075,
.037,-.0265,
.036438,-.032925,
.034769,-.039154,
.032043,-.044999,
.028344,-.050282,
.023784,-.054842,
.018501,-.058541,
.012656,-.061266,
.0075,-.06273,
90.*
4,1,20,-.0075,.06273,
-.0075,.05555,
-.01243,.053806,
-.016983,.051232,
-.02102,.047906,
-.024418,.043931,
-.027073,.039425,
-.028906,.034527,
-.029861,.029385,
-.03,.0265,
-.03,.0075,
-.037,.0075,
-.037,.0265,
-.036438,.032925,
-.034769,.039154,
-.032043,.044999,
-.028344,.050282,
-.023784,.054842,
-.018501,.058541,
-.012656,.061266,
-.0075,.06273,
90.*
4,1,20,.0075,.05555,
.0075,.06273,
.013677,.060878,
.019439,.057981,
.024611,.054127,
.029034,.049434,
.032576,.044045,
.035127,.038122,
.036612,.031846,
.037,.0265,
.037,.0075,
.03,.0075,
.03,.0265,
.029544,.03171,
.028191,.036762,
.02598,.041502,
.022981,.045786,
.019282,.049484,
.014998,.052484,
.010258,.054694,
.0075,.05555,
90.*
%
%ADD21MACRO21*%
%AMMACRO16*
4,1,36,.0025,0.0,
.002462,.000434,
.002349,.000855,
.002165,.00125,
.001915,.001607,
.001607,.001915,
.00125,.002165,
.000855,.002349,
.000434,.002462,
0.0,.0025,
-.000434,.002462,
-.000855,.002349,
-.00125,.002165,
-.001607,.001915,
-.001915,.001607,
-.002165,.00125,
-.002349,.000855,
-.002462,.000434,
-.0025,0.0,
-.002462,-.000434,
-.002349,-.000855,
-.002165,-.00125,
-.001915,-.001607,
-.001607,-.001915,
-.00125,-.002165,
-.000855,-.002349,
-.000434,-.002462,
0.0,-.0025,
.000434,-.002462,
.000855,-.002349,
.00125,-.002165,
.001607,-.001915,
.001915,-.001607,
.002165,-.00125,
.002349,-.000855,
.002462,-.000434,
.0025,0.0,
90.*
%
%ADD16MACRO16*%
%AMMACRO35*
4,1,36,.003,0.0,
.002954,.000521,
.002819,.001026,
.002598,.0015,
.002298,.001928,
.001928,.002298,
.0015,.002598,
.001026,.002819,
.000521,.002954,
0.0,.003,
-.000521,.002954,
-.001026,.002819,
-.0015,.002598,
-.001928,.002298,
-.002298,.001928,
-.002598,.0015,
-.002819,.001026,
-.002954,.000521,
-.003,0.0,
-.002954,-.000521,
-.002819,-.001026,
-.002598,-.0015,
-.002298,-.001928,
-.001928,-.002298,
-.0015,-.002598,
-.001026,-.002819,
-.000521,-.002954,
0.0,-.003,
.000521,-.002954,
.001026,-.002819,
.0015,-.002598,
.001928,-.002298,
.002298,-.001928,
.002598,-.0015,
.002819,-.001026,
.002954,-.000521,
.003,0.0,
90.*
%
%ADD35MACRO35*%
%AMMACRO12*
4,1,36,.0025,0.0,
.002462,.000434,
.002349,.000855,
.002165,.00125,
.001915,.001607,
.001607,.001915,
.00125,.002165,
.000855,.002349,
.000434,.002462,
0.0,.0025,
-.000434,.002462,
-.000855,.002349,
-.00125,.002165,
-.001607,.001915,
-.001915,.001607,
-.002165,.00125,
-.002349,.000855,
-.002462,.000434,
-.0025,0.0,
-.002462,-.000434,
-.002349,-.000855,
-.002165,-.00125,
-.001915,-.001607,
-.001607,-.001915,
-.00125,-.002165,
-.000855,-.002349,
-.000434,-.002462,
0.0,-.0025,
.000434,-.002462,
.000855,-.002349,
.00125,-.002165,
.001607,-.001915,
.001915,-.001607,
.002165,-.00125,
.002349,-.000855,
.002462,-.000434,
.0025,0.0,
0.0*
%
%ADD12MACRO12*%
%AMMACRO52*
4,1,36,-.0025,0.0,
-.002462,.000434,
-.002349,.000855,
-.002165,.00125,
-.001915,.001607,
-.001607,.001915,
-.00125,.002165,
-.000855,.002349,
-.000434,.002462,
0.0,.0025,
.000434,.002462,
.000855,.002349,
.00125,.002165,
.001607,.001915,
.001915,.001607,
.002165,.00125,
.002349,.000855,
.002462,.000434,
.0025,0.0,
.002462,-.000434,
.002349,-.000855,
.002165,-.00125,
.001915,-.001607,
.001607,-.001915,
.00125,-.002165,
.000855,-.002349,
.000434,-.002462,
0.0,-.0025,
-.000434,-.002462,
-.000855,-.002349,
-.00125,-.002165,
-.001607,-.001915,
-.001915,-.001607,
-.002165,-.00125,
-.002349,-.000855,
-.002462,-.000434,
-.0025,0.0,
0.0*
%
%ADD52MACRO52*%
%AMMACRO27*
4,1,36,.003,0.0,
.002954,.000521,
.002819,.001026,
.002598,.0015,
.002298,.001928,
.001928,.002298,
.0015,.002598,
.001026,.002819,
.000521,.002954,
0.0,.003,
-.000521,.002954,
-.001026,.002819,
-.0015,.002598,
-.001928,.002298,
-.002298,.001928,
-.002598,.0015,
-.002819,.001026,
-.002954,.000521,
-.003,0.0,
-.002954,-.000521,
-.002819,-.001026,
-.002598,-.0015,
-.002298,-.001928,
-.001928,-.002298,
-.0015,-.002598,
-.001026,-.002819,
-.000521,-.002954,
0.0,-.003,
.000521,-.002954,
.001026,-.002819,
.0015,-.002598,
.001928,-.002298,
.002298,-.001928,
.002598,-.0015,
.002819,-.001026,
.002954,-.000521,
.003,0.0,
0.0*
%
%ADD27MACRO27*%
%AMMACRO24*
4,1,36,-.003,0.0,
-.002954,.000521,
-.002819,.001026,
-.002598,.0015,
-.002298,.001928,
-.001928,.002298,
-.0015,.002598,
-.001026,.002819,
-.000521,.002954,
0.0,.003,
.000521,.002954,
.001026,.002819,
.0015,.002598,
.001928,.002298,
.002298,.001928,
.002598,.0015,
.002819,.001026,
.002954,.000521,
.003,0.0,
.002954,-.000521,
.002819,-.001026,
.002598,-.0015,
.002298,-.001928,
.001928,-.002298,
.0015,-.002598,
.001026,-.002819,
.000521,-.002954,
0.0,-.003,
-.000521,-.002954,
-.001026,-.002819,
-.0015,-.002598,
-.001928,-.002298,
-.002298,-.001928,
-.002598,-.0015,
-.002819,-.001026,
-.002954,-.000521,
-.003,0.0,
0.0*
%
%ADD24MACRO24*%
%AMMACRO41*
4,1,16,.02584,.01524,
.028094,.010521,
.029494,.005483,
.029998,.000278,
.029591,-.004935,
.028284,-.009999,
.026118,-.014758,
.02584,-.01524,
.03092,-.02032,
.033979,-.014642,
.036005,-.008519,
.036938,-.002138,
.036748,.004309,
.035441,.010625,
.033058,.016618,
.03092,.02032,
.02584,.01524,
180.*
4,1,16,.01524,-.02584,
.010521,-.028094,
.005483,-.029494,
.000278,-.029998,
-.004935,-.029591,
-.009999,-.028284,
-.014758,-.026118,
-.01524,-.02584,
-.02032,-.03092,
-.014642,-.033979,
-.008519,-.036005,
-.002138,-.036938,
.004309,-.036748,
.010625,-.035441,
.016618,-.033058,
.02032,-.03092,
.01524,-.02584,
180.*
4,1,16,-.02584,-.01524,
-.028094,-.010521,
-.029494,-.005483,
-.029998,-.000278,
-.029591,.004935,
-.028284,.009999,
-.026118,.014758,
-.02584,.01524,
-.03092,.02032,
-.033979,.014642,
-.036005,.008519,
-.036938,.002138,
-.036748,-.004309,
-.035441,-.010625,
-.033058,-.016618,
-.03092,-.02032,
-.02584,-.01524,
180.*
4,1,16,-.01524,.02584,
-.010521,.028094,
-.005483,.029494,
-.000278,.029998,
.004935,.029591,
.009999,.028284,
.014758,.026118,
.01524,.02584,
.02032,.03092,
.014642,.033979,
.008519,.036005,
.002138,.036938,
-.004309,.036748,
-.010625,.035441,
-.016618,.033058,
-.02032,.03092,
-.01524,.02584,
180.*
%
%ADD41MACRO41*%
%AMMACRO56*
4,1,15,.03682,.01914,
.039584,.012455,
.041146,.005393,
.041457,-.001834,
.040509,-.009005,
.03833,-.015903,
.03682,-.01914,
.04197,-.0243,
.045552,-.016643,
.04775,-.00848,
.048497,-.000059,
.047771,.008363,
.045593,.016531,
.042029,.024197,
.04197,.0243,
.03682,.01914,
270.*
4,1,15,.01914,-.03682,
.012455,-.039584,
.005393,-.041146,
-.001834,-.041457,
-.009005,-.040509,
-.015903,-.03833,
-.01914,-.03682,
-.0243,-.04197,
-.016643,-.045552,
-.00848,-.04775,
-.000059,-.048497,
.008363,-.047771,
.016531,-.045593,
.024197,-.042029,
.0243,-.04197,
.01914,-.03682,
270.*
4,1,15,-.03682,-.01914,
-.039584,-.012455,
-.041146,-.005393,
-.041457,.001834,
-.040509,.009005,
-.03833,.015903,
-.03682,.01914,
-.04197,.0243,
-.045552,.016643,
-.04775,.00848,
-.048497,.000059,
-.047771,-.008363,
-.045593,-.016531,
-.042029,-.024197,
-.04197,-.0243,
-.03682,-.01914,
270.*
4,1,15,-.01914,.03682,
-.012455,.039584,
-.005393,.041146,
.001834,.041457,
.009005,.040509,
.015903,.03833,
.01914,.03682,
.0243,.04197,
.016643,.045552,
.00848,.04775,
.000059,.048497,
-.008363,.047771,
-.016531,.045593,
-.024197,.042029,
-.0243,.04197,
-.01914,.03682,
270.*
%
%ADD56MACRO56*%
%AMMACRO57*
4,1,15,-.03682,.01914,
-.039584,.012455,
-.041146,.005393,
-.041457,-.001834,
-.040509,-.009005,
-.03833,-.015903,
-.03682,-.01914,
-.04197,-.0243,
-.045552,-.016643,
-.04775,-.00848,
-.048497,-.000059,
-.047771,.008363,
-.045593,.016531,
-.042029,.024197,
-.04197,.0243,
-.03682,.01914,
270.*
4,1,15,-.01914,-.03682,
-.012455,-.039584,
-.005393,-.041146,
.001834,-.041457,
.009005,-.040509,
.015903,-.03833,
.01914,-.03682,
.0243,-.04197,
.016643,-.045552,
.00848,-.04775,
.000059,-.048497,
-.008363,-.047771,
-.016531,-.045593,
-.024197,-.042029,
-.0243,-.04197,
-.01914,-.03682,
270.*
4,1,15,.03682,-.01914,
.039584,-.012455,
.041146,-.005393,
.041457,.001834,
.040509,.009005,
.03833,.015903,
.03682,.01914,
.04197,.0243,
.045552,.016643,
.04775,.00848,
.048497,.000059,
.047771,-.008363,
.045593,-.016531,
.042029,-.024197,
.04197,-.0243,
.03682,-.01914,
270.*
4,1,15,.01914,.03682,
.012455,.039584,
.005393,.041146,
-.001834,.041457,
-.009005,.040509,
-.015903,.03833,
-.01914,.03682,
-.0243,.04197,
-.016643,.045552,
-.00848,.04775,
-.000059,.048497,
.008363,.047771,
.016531,.045593,
.024197,.042029,
.0243,.04197,
.01914,.03682,
270.*
%
%ADD57MACRO57*%
%ADD64C,.006*%
%ADD76C,.03006*%
%ADD82C,.02404*%
%ADD80C,.07005*%
%ADD73C,.08404*%
%ADD66C,.07306*%
%ADD79C,.09208*%
%ADD74C,.07606*%
%ADD72C,.08408*%
%ADD78C,.07608*%
%ADD71C,.08409*%
%ADD70O,.1621X.2251*%
%ADD69O,.03604X.07004*%
%ADD67O,.03006X.06406*%
%ADD81C,.16206*%
%ADD68O,.03606X.07006*%
%ADD77C,.17406*%
%ADD65C,.16506*%
%ADD75C,.21786*%
G75*
%LPD*%
G75*
G36*
G01X-1490433Y-1677216D02*
X4496476D01*
Y3837819D01*
X-1490433D01*
Y-1677216D01*
G37*
%LPC*%
G75*
G36*
G01X630370Y-100983D02*
G02X624496Y-95109I0J5874D01*
G01Y-32983D01*
G03X614622Y-23109I-9874J0D01*
G01X68874D01*
G03X59000Y-32983I0J-9874D01*
G01Y-95109D01*
G02X53126Y-100983I-5874J0D01*
G01X7874D01*
G02X2000Y-95109I0J5874D01*
G01Y-15748D01*
G02X7874Y-9874I5874J0D01*
G01X31358D01*
G03X41232Y0I0J9874D01*
G01Y34843D01*
G02X47106Y40717I5874J0D01*
G01X54980D01*
G02X60854Y34843I0J-5874D01*
G01Y0D01*
G03X70728Y-9874I9874J0D01*
G01X133720D01*
G03X143594Y0I0J9874D01*
G01Y34843D01*
G02X149468Y40717I5874J0D01*
G01X157343D01*
G02X163217Y34843I0J-5874D01*
G01Y0D01*
G03X173091Y-9874I9874J0D01*
G01X236083D01*
G03X245957Y0I0J9874D01*
G01Y34843D01*
G02X251831Y40717I5874J0D01*
G01X259705D01*
G02X265579Y34843I0J-5874D01*
G01Y0D01*
G03X275453Y-9874I9874J0D01*
G01X338445D01*
G03X348319Y0I0J9874D01*
G01Y34843D01*
G02X354193Y40717I5874J0D01*
G01X362067D01*
G02X367941Y34843I0J-5874D01*
G01Y0D01*
G03X377815Y-9874I9874J0D01*
G01X488445D01*
G03X498319Y0I0J9874D01*
G01Y34843D01*
G02X504193Y40717I5874J0D01*
G01X512067D01*
G02X517941Y34843I0J-5874D01*
G01Y0D01*
G03X527815Y-9874I9874J0D01*
G01X590807D01*
G03X600681Y0I0J9874D01*
G01Y34843D01*
G02X606555Y40717I5874J0D01*
G01X614429D01*
G02X620303Y34843I0J-5874D01*
G01Y0D01*
G03X630177Y-9874I9874J0D01*
G01X693169D01*
G03X703043Y0I0J9874D01*
G01Y34843D01*
G02X708917Y40717I5874J0D01*
G01X716791D01*
G02X722665Y34843I0J-5874D01*
G01Y0D01*
G03X732539Y-9874I9874J0D01*
G01X795531D01*
G03X805405Y0I0J9874D01*
G01Y34843D01*
G02X811279Y40717I5874J0D01*
G01X819154D01*
G02X825028Y34843I0J-5874D01*
G01Y0D01*
G03X834902Y-9874I9874J0D01*
G01X945531D01*
G03X955405Y0I0J9874D01*
G01Y34843D01*
G02X961279Y40717I5874J0D01*
G01X969154D01*
G02X975028Y34843I0J-5874D01*
G01Y0D01*
G03X984902Y-9874I9874J0D01*
G01X1047894D01*
G03X1057768Y0I0J9874D01*
G01Y34843D01*
G02X1063642Y40717I5874J0D01*
G01X1071516D01*
G02X1077390Y34843I0J-5874D01*
G01Y0D01*
G03X1087264Y-9874I9874J0D01*
G01X1150256D01*
G03X1160130Y0I0J9874D01*
G01Y34843D01*
G02X1166004Y40717I5874J0D01*
G01X1173878D01*
G02X1179752Y34843I0J-5874D01*
G01Y0D01*
G03X1189626Y-9874I9874J0D01*
G01X1252618D01*
G03X1262492Y0I0J9874D01*
G01Y34843D01*
G02X1268366Y40717I5874J0D01*
G01X1276240D01*
G02X1282114Y34843I0J-5874D01*
G01Y0D01*
G03X1291988Y-9874I9874J0D01*
G01X1402618D01*
G03X1412492Y0I0J9874D01*
G01Y34843D01*
G02X1418366Y40717I5874J0D01*
G01X1426240D01*
G02X1432114Y34843I0J-5874D01*
G01Y0D01*
G03X1441988Y-9874I9874J0D01*
G01X1504980D01*
G03X1514854Y0I0J9874D01*
G01Y34843D01*
G02X1520728Y40717I5874J0D01*
G01X1528602D01*
G02X1534476Y34843I0J-5874D01*
G01Y0D01*
G03X1544350Y-9874I9874J0D01*
G01X1607343D01*
G03X1617217Y0I0J9874D01*
G01Y34843D01*
G02X1623091Y40717I5874J0D01*
G01X1630965D01*
G02X1636839Y34843I0J-5874D01*
G01Y0D01*
G03X1646713Y-9874I9874J0D01*
G01X1709705D01*
G03X1719579Y0I0J9874D01*
G01Y34843D01*
G02X1725453Y40717I5874J0D01*
G01X1733327D01*
G02X1739201Y34843I0J-5874D01*
G01Y0D01*
G03X1749075Y-9874I9874J0D01*
G01X1833071D01*
G02X1838945Y-15748I0J-5874D01*
G01Y-95109D01*
G02X1833071Y-100983I-5874J0D01*
G01X630370D01*
G37*
G36*
G01X1833071Y1645992D02*
G02X1838945Y1640118I0J-5874D01*
G01Y970425D01*
G02X1837225Y966273I-5874J1D01*
G01X1826876Y955925D01*
G03X1823984Y948943I6982J-6982D01*
G01Y344836D01*
G03X1826876Y337855I9873J0D01*
G01X1837225Y327506D01*
G02X1838945Y323354I-4153J-4153D01*
G01Y7874D01*
G02X1833071Y2000I-5874J0D01*
G01X1756949D01*
G02X1751075Y7874I0J5874D01*
G01Y46654D01*
G03X1745138Y52591I-5937J0D01*
G01X1713642D01*
G03X1707705Y46654I0J-5937D01*
G01Y7874D01*
G02X1701831Y2000I-5874J0D01*
G01X1654587D01*
G02X1648713Y7874I0J5874D01*
G01Y46654D01*
G03X1642776Y52591I-5937J0D01*
G01X1611280D01*
G03X1605343Y46654I0J-5937D01*
G01Y7874D01*
G02X1599469Y2000I-5874J0D01*
G01X1552224D01*
G02X1546350Y7874I0J5874D01*
G01Y46654D01*
G03X1540413Y52591I-5937J0D01*
G01X1508917D01*
G03X1502980Y46654I0J-5937D01*
G01Y7874D01*
G02X1497106Y2000I-5874J0D01*
G01X1449862D01*
G02X1443988Y7874I0J5874D01*
G01Y46654D01*
G03X1438051Y52591I-5937J0D01*
G01X1406555D01*
G03X1400618Y46654I0J-5937D01*
G01Y7874D01*
G02X1394744Y2000I-5874J0D01*
G01X1299862D01*
G02X1293988Y7874I0J5874D01*
G01Y46654D01*
G03X1288051Y52591I-5937J0D01*
G01X1256555D01*
G03X1250618Y46654I0J-5937D01*
G01Y7874D01*
G02X1244744Y2000I-5874J0D01*
G01X1197500D01*
G02X1191626Y7874I0J5874D01*
G01Y46654D01*
G03X1185689Y52591I-5937J0D01*
G01X1154193D01*
G03X1148256Y46654I0J-5937D01*
G01Y7874D01*
G02X1142382Y2000I-5874J0D01*
G01X1095138D01*
G02X1089264Y7874I0J5874D01*
G01Y46654D01*
G03X1083327Y52591I-5937J0D01*
G01X1051831D01*
G03X1045894Y46654I0J-5937D01*
G01Y7874D01*
G02X1040020Y2000I-5874J0D01*
G01X992776D01*
G02X986902Y7874I0J5874D01*
G01Y46654D01*
G03X980965Y52591I-5937J0D01*
G01X949468D01*
G03X943531Y46654I0J-5937D01*
G01Y7874D01*
G02X937657Y2000I-5874J0D01*
G01X842776D01*
G02X836902Y7874I0J5874D01*
G01Y46654D01*
G03X830965Y52591I-5937J0D01*
G01X799468D01*
G03X793531Y46654I0J-5937D01*
G01Y7874D01*
G02X787657Y2000I-5874J0D01*
G01X740413D01*
G02X734539Y7874I0J5874D01*
G01Y46654D01*
G03X728602Y52591I-5937J0D01*
G01X697106D01*
G03X691169Y46654I0J-5937D01*
G01Y7874D01*
G02X685295Y2000I-5874J0D01*
G01X638051D01*
G02X632177Y7874I0J5874D01*
G01Y46654D01*
G03X626240Y52591I-5937J0D01*
G01X594744D01*
G03X588807Y46654I0J-5937D01*
G01Y7874D01*
G02X582933Y2000I-5874J0D01*
G01X535689D01*
G02X529815Y7874I0J5874D01*
G01Y46654D01*
G03X523878Y52591I-5937J0D01*
G01X492382D01*
G03X486445Y46654I0J-5937D01*
G01Y7874D01*
G02X480571Y2000I-5874J0D01*
G01X385689D01*
G02X379815Y7874I0J5874D01*
G01Y46654D01*
G03X373878Y52591I-5937J0D01*
G01X342382D01*
G03X336445Y46654I0J-5937D01*
G01Y7874D01*
G02X330571Y2000I-5874J0D01*
G01X283327D01*
G02X277453Y7874I0J5874D01*
G01Y46654D01*
G03X271516Y52591I-5937J0D01*
G01X240020D01*
G03X234083Y46654I0J-5937D01*
G01Y7874D01*
G02X228209Y2000I-5874J0D01*
G01X180965D01*
G02X175091Y7874I0J5874D01*
G01Y46654D01*
G03X169154Y52591I-5937J0D01*
G01X137657D01*
G03X131720Y46654I0J-5937D01*
G01Y7874D01*
G02X125846Y2000I-5874J0D01*
G01X78602D01*
G02X72728Y7874I0J5874D01*
G01Y46654D01*
G03X66791Y52591I-5937J0D01*
G01X35295D01*
G03X29358Y46654I0J-5937D01*
G01Y7874D01*
G02X23484Y2000I-5874J0D01*
G01X7874D01*
G02X2000Y7874I0J5874D01*
G01Y323354D01*
G02X3720Y327506I5873J-1D01*
G01X14068Y337855D01*
G03X16961Y344836I-6980J6983D01*
G01Y948943D01*
G03X14068Y955925I-9875J-1D01*
G01X3720Y966273D01*
G02X2000Y970425I4154J4153D01*
G01Y1640118D01*
G02X7874Y1645992I5874J0D01*
G01X789298D01*
G02X793649Y1644063I-1J-5873D01*
G03X800966Y1640819I7317J6631D01*
G01X1070058D01*
G03X1077374Y1644063I-1J9873D01*
G02X1081725Y1645992I4352J-3945D01*
G01X1833071D01*
G37*
G36*
G01Y1818880D02*
G02X1838945Y1813006I0J-5874D01*
G01Y1663740D01*
G02X1833071Y1657866I-5874J0D01*
G01X1763543D01*
G02X1757669Y1663740I0J5874D01*
G01Y1689331D01*
G03X1747795Y1699205I-9874J0D01*
G01X1461575D01*
G03X1451701Y1689331I0J-9874D01*
G01Y1663740D01*
G02X1445827Y1657866I-5874J0D01*
G01X1417087D01*
G02X1411213Y1663740I0J5874D01*
G01Y1689331D01*
G03X1401339Y1699205I-9874J0D01*
G01X1115118D01*
G03X1105244Y1689331I0J-9874D01*
G01Y1663740D01*
G02X1099370Y1657866I-5874J0D01*
G01X1090079D01*
G02X1084205Y1663740I0J5874D01*
G01Y1695110D01*
G03X1074331Y1704984I-9874J0D01*
G01X796693D01*
G03X786819Y1695110I0J-9874D01*
G01Y1663740D01*
G02X780945Y1657866I-5874J0D01*
G01X741575D01*
G02X735701Y1663740I0J5874D01*
G01Y1689331D01*
G03X725827Y1699205I-9874J0D01*
G01X439607D01*
G03X429733Y1689331I0J-9874D01*
G01Y1663740D01*
G02X423859Y1657866I-5874J0D01*
G01X395118D01*
G02X389244Y1663740I0J5874D01*
G01Y1689331D01*
G03X379370Y1699205I-9874J0D01*
G01X93150D01*
G03X83276Y1689331I0J-9874D01*
G01Y1663740D01*
G02X77402Y1657866I-5874J0D01*
G01X7874D01*
G02X2000Y1663740I0J5874D01*
G01Y1813006D01*
G02X7874Y1818880I5874J0D01*
G01X1833071D01*
G37*
%LPD*%
G75*
G36*
G01X607977Y1552080D02*
X555513D01*
G02X555210Y1552383I0J303D01*
G01Y1643194D01*
G02X555513Y1643498I303J1D01*
G01X608266D01*
G02X608570Y1643194I0J-304D01*
G01Y1552672D01*
X607977Y1552080D01*
G37*
G36*
G01X208954Y1643834D02*
G02X209256Y1644136I302J0D01*
G01X261611D01*
G02X261912Y1643834I-1J-302D01*
G01Y1642872D01*
Y1552470D01*
X261722Y1552280D01*
X208952D01*
Y1642872D01*
X208954D01*
Y1643834D01*
G37*
G36*
G01X1232576D02*
G02X1232878Y1644136I302J0D01*
G01X1285233D01*
G02X1285534Y1643834I-1J-302D01*
G01Y1643226D01*
Y1552461D01*
X1285353Y1552280D01*
X1232574D01*
Y1643226D01*
X1232576D01*
Y1643834D01*
G37*
G36*
G01X1579032D02*
G02X1579335Y1644136I303J-1D01*
G01X1631688D01*
G02X1631990Y1643834I0J-302D01*
G01Y1643174D01*
X1631992D01*
Y1552573D01*
X1631698Y1552280D01*
X1579032D01*
Y1643174D01*
Y1643834D01*
G37*
G36*
G01X177763Y1512216D02*
X180583D01*
G02X180786Y1512014I1J-202D01*
G01Y1511392D01*
G03X180836Y1511260I200J0D01*
G02Y1508348I-1664J-1456D01*
G03X180786Y1508216I150J-132D01*
G01Y1506273D01*
G03X180836Y1506141I200J0D01*
G02Y1503229I-1664J-1456D01*
G03X180786Y1503097I150J-132D01*
G01Y1502476D01*
G02X180583Y1502274I-203J1D01*
G01X177763D01*
G02X177560Y1502476I-1J202D01*
G01Y1503097D01*
G03X177510Y1503229I-200J0D01*
G02Y1506141I1664J1456D01*
G03X177560Y1506273I-150J132D01*
G01Y1508216D01*
G03X177510Y1508348I-200J0D01*
G02Y1511260I1664J1456D01*
G03X177560Y1511392I-150J132D01*
G01Y1512014D01*
G02X177763Y1512216I203J-1D01*
G37*
G36*
G01X350991D02*
X353811D01*
G02X354014Y1512014I1J-202D01*
G01Y1511392D01*
G03X354064Y1511260I200J0D01*
G02Y1508348I-1664J-1456D01*
G03X354014Y1508216I150J-132D01*
G01Y1506273D01*
G03X354064Y1506141I200J0D01*
G02Y1503229I-1664J-1456D01*
G03X354014Y1503097I150J-132D01*
G01Y1502476D01*
G02X353811Y1502274I-203J1D01*
G01X350991D01*
G02X350788Y1502476I-1J202D01*
G01Y1503097D01*
G03X350738Y1503229I-200J0D01*
G02Y1506141I1664J1456D01*
G03X350788Y1506273I-150J132D01*
G01Y1508216D01*
G03X350738Y1508348I-200J0D01*
G02Y1511260I1664J1456D01*
G03X350788Y1511392I-150J132D01*
G01Y1512014D01*
G02X350991Y1512216I203J-1D01*
G37*
G36*
G01X186425Y1516546D02*
X189245D01*
G02X189448Y1516344I1J-202D01*
G01Y1515722D01*
G03X189498Y1515590I200J0D01*
G02Y1512678I-1664J-1456D01*
G03X189448Y1512546I150J-132D01*
G01Y1510604D01*
G03X189498Y1510472I200J0D01*
G02Y1507560I-1664J-1456D01*
G03X189448Y1507428I150J-132D01*
G01Y1506806D01*
G02X189245Y1506604I-203J1D01*
G01X186425D01*
G02X186222Y1506806I-1J202D01*
G01Y1507428D01*
G03X186172Y1507560I-200J0D01*
G02Y1510472I1664J1456D01*
G03X186222Y1510604I-150J132D01*
G01Y1512546D01*
G03X186172Y1512678I-200J0D01*
G02Y1515590I1664J1456D01*
G03X186222Y1515722I-150J132D01*
G01Y1516344D01*
G02X186425Y1516546I203J-1D01*
G37*
G36*
G01X359653D02*
X362473D01*
G02X362676Y1516344I1J-202D01*
G01Y1515722D01*
G03X362726Y1515590I200J0D01*
G02Y1512678I-1664J-1456D01*
G03X362676Y1512546I150J-132D01*
G01Y1510604D01*
G03X362726Y1510472I200J0D01*
G02Y1507560I-1664J-1456D01*
G03X362676Y1507428I150J-132D01*
G01Y1506806D01*
G02X362473Y1506604I-203J1D01*
G01X359653D01*
G02X359450Y1506806I-1J202D01*
G01Y1507428D01*
G03X359400Y1507560I-200J0D01*
G02Y1510472I1664J1456D01*
G03X359450Y1510604I-150J132D01*
G01Y1512546D01*
G03X359400Y1512678I-200J0D01*
G02Y1515590I1664J1456D01*
G03X359450Y1515722I-150J132D01*
G01Y1516344D01*
G02X359653Y1516546I203J-1D01*
G37*
G36*
G01X177763Y1568516D02*
X180583D01*
G02X180786Y1568313I0J-203D01*
G01Y1567691D01*
G03X180836Y1567559I200J0D01*
G02Y1564647I-1664J-1456D01*
G03X180786Y1564515I150J-132D01*
G01Y1562573D01*
G03X180836Y1562441I200J0D01*
G02Y1559529I-1664J-1456D01*
G03X180786Y1559397I150J-132D01*
G01Y1558775D01*
G02X180583Y1558572I-203J0D01*
G01X177763D01*
G02X177560Y1558775I0J203D01*
G01Y1559397D01*
G03X177510Y1559529I-200J0D01*
G02Y1562441I1664J1456D01*
G03X177560Y1562573I-150J132D01*
G01Y1564515D01*
G03X177510Y1564647I-200J0D01*
G02Y1567559I1664J1456D01*
G03X177560Y1567691I-150J132D01*
G01Y1568313D01*
G02X177763Y1568516I203J0D01*
G37*
G36*
G01X350991D02*
X353811D01*
G02X354014Y1568313I0J-203D01*
G01Y1567691D01*
G03X354064Y1567559I200J0D01*
G02Y1564647I-1664J-1456D01*
G03X354014Y1564515I150J-132D01*
G01Y1562573D01*
G03X354064Y1562441I200J0D01*
G02Y1559529I-1664J-1456D01*
G03X354014Y1559397I150J-132D01*
G01Y1558775D01*
G02X353811Y1558572I-203J0D01*
G01X350991D01*
G02X350788Y1558775I0J203D01*
G01Y1559397D01*
G03X350738Y1559529I-200J0D01*
G02Y1562441I1664J1456D01*
G03X350788Y1562573I-150J132D01*
G01Y1564515D01*
G03X350738Y1564647I-200J0D01*
G02Y1567559I1664J1456D01*
G03X350788Y1567691I-150J132D01*
G01Y1568313D01*
G02X350991Y1568516I203J0D01*
G37*
G36*
G01X186425Y1572846D02*
X189245D01*
G02X189448Y1572644I1J-202D01*
G01Y1572022D01*
G03X189498Y1571890I200J0D01*
G02Y1568978I-1664J-1456D01*
G03X189448Y1568846I150J-132D01*
G01Y1566903D01*
G03X189498Y1566771I200J0D01*
G02Y1563859I-1664J-1456D01*
G03X189448Y1563727I150J-132D01*
G01Y1563106D01*
G02X189245Y1562904I-203J1D01*
G01X186425D01*
G02X186222Y1563106I-1J202D01*
G01Y1563727D01*
G03X186172Y1563859I-200J0D01*
G02Y1566771I1664J1456D01*
G03X186222Y1566903I-150J132D01*
G01Y1568846D01*
G03X186172Y1568978I-200J0D01*
G02Y1571890I1664J1456D01*
G03X186222Y1572022I-150J132D01*
G01Y1572644D01*
G02X186425Y1572846I203J-1D01*
G37*
G36*
G01X359653D02*
X362473D01*
G02X362676Y1572644I1J-202D01*
G01Y1572022D01*
G03X362726Y1571890I200J0D01*
G02Y1568978I-1664J-1456D01*
G03X362676Y1568846I150J-132D01*
G01Y1566903D01*
G03X362726Y1566771I200J0D01*
G02Y1563859I-1664J-1456D01*
G03X362676Y1563727I150J-132D01*
G01Y1563106D01*
G02X362473Y1562904I-203J1D01*
G01X359653D01*
G02X359450Y1563106I-1J202D01*
G01Y1563727D01*
G03X359400Y1563859I-200J0D01*
G02Y1566771I1664J1456D01*
G03X359450Y1566903I-150J132D01*
G01Y1568846D01*
G03X359400Y1568978I-200J0D01*
G02Y1571890I1664J1456D01*
G03X359450Y1572022I-150J132D01*
G01Y1572644D01*
G02X359653Y1572846I203J-1D01*
G37*
G36*
G01X177763Y1583870D02*
X180583D01*
G02X180786Y1583667I0J-203D01*
G01Y1583045D01*
G03X180836Y1582913I200J0D01*
G02Y1580001I-1664J-1456D01*
G03X180786Y1579869I150J-132D01*
G01Y1577927D01*
G03X180836Y1577795I200J0D01*
G02Y1574883I-1664J-1456D01*
G03X180786Y1574751I150J-132D01*
G01Y1574129D01*
G02X180583Y1573926I-203J0D01*
G01X177763D01*
G02X177560Y1574129I0J203D01*
G01Y1574751D01*
G03X177510Y1574883I-200J0D01*
G02Y1577795I1664J1456D01*
G03X177560Y1577927I-150J132D01*
G01Y1579869D01*
G03X177510Y1580001I-200J0D01*
G02Y1582913I1664J1456D01*
G03X177560Y1583045I-150J132D01*
G01Y1583667D01*
G02X177763Y1583870I203J0D01*
G37*
G36*
G01X952704Y1482405D02*
X953818Y1481291D01*
G03X953834Y1481276I178J174D01*
G01X954122Y1481036D01*
G02X954194Y1480882I-128J-154D01*
G01Y1451027D01*
G02X954135Y1450885I-200J0D01*
G01X953083Y1449833D01*
G02X952941Y1449774I-142J141D01*
G01X930177D01*
G02X930035Y1449833I0J200D01*
G01X928619Y1451249D01*
G02X928560Y1451391I141J142D01*
G01Y1481306D01*
G02X928619Y1481448I200J0D01*
G01X930003Y1482831D01*
G02X930145Y1482890I142J-141D01*
G01X952269D01*
G02X952435Y1482801I0J-200D01*
G01X952673Y1482443D01*
G03X952703Y1482406I207J137D01*
G01X952704Y1482405D01*
G37*
G36*
G01X1047661Y1451746D02*
X1045748Y1449833D01*
G02X1045606Y1449774I-142J141D01*
G01X955889D01*
G02X955747Y1449833I0J200D01*
G01X954749Y1450831D01*
G02X954690Y1450973I141J142D01*
G01Y1485726D01*
G02X954749Y1485868I200J0D01*
G01X956753Y1487871D01*
G02X956895Y1487930I142J-141D01*
G01X1046147D01*
G02X1046289Y1487871I0J-200D01*
G01X1047661Y1486500D01*
G02X1047720Y1486358I-141J-142D01*
G01Y1451888D01*
G02X1047661Y1451746I-200J0D01*
G37*
G36*
G01X933247Y1585829D02*
X940733Y1578343D01*
G03X940735Y1578341I142J140D01*
G03X940910Y1578270I174J178D01*
G01X956757D01*
G02X956899Y1578211I0J-200D01*
G01X960831Y1574278D01*
G02X960890Y1574136I-141J-142D01*
G01Y1543680D01*
G03X960963Y1543504I249J0D01*
G01X965002Y1539465D01*
G03X965004Y1539463I142J140D01*
G03X965179Y1539392I174J178D01*
G01X1020321D01*
G02X1020463Y1539333I0J-200D01*
G01X1032517Y1527279D01*
G02X1032576Y1527137I-141J-142D01*
G01Y1492489D01*
G02X1032517Y1492347I-200J0D01*
G01X1031783Y1491613D01*
G02X1031641Y1491554I-142J141D01*
G01X946768D01*
G02X946626Y1491613I0J200D01*
G01X944169Y1494071D01*
G03X944167Y1494073I-142J-140D01*
G03X943992Y1494144I-174J-178D01*
G01X933579D01*
G03X933404Y1494073I-1J-249D01*
G03X933402Y1494071I140J-142D01*
G01X917849Y1478518D01*
G03X917776Y1478342I176J-176D01*
G01Y1464605D01*
G02X917717Y1464463I-200J0D01*
G01X914897Y1461643D01*
G03X914895Y1461641I140J-142D01*
G03X914824Y1461466I178J-174D01*
G01Y1460513D01*
G02X914765Y1460371I-200J0D01*
G01X914235Y1459842D01*
G03X914162Y1459666I176J-176D01*
G01Y1446033D01*
G02X914104Y1445891I-200J-1D01*
G01X913370Y1445157D01*
G02X913228Y1445098I-142J141D01*
G01X900144D01*
G02X900002Y1445157I0J200D01*
G01X899268Y1445891D01*
G02X899210Y1446033I142J141D01*
G01Y1459640D01*
G03X899137Y1459816I-249J0D01*
G01X898531Y1460422D01*
G02X898472Y1460564I141J142D01*
G01Y1462024D01*
G03X898399Y1462200I-249J0D01*
G01X893401Y1467197D01*
G02X893342Y1467339I141J142D01*
G01Y1473096D01*
G03X893271Y1473271I-249J1D01*
G03X893269Y1473273I-142J-140D01*
G01X888245Y1478297D01*
G03X888069Y1478370I-176J-176D01*
G01X880504D01*
G03X880328Y1478297I0J-249D01*
G01X872973Y1470942D01*
G03X872900Y1470766I176J-176D01*
G01Y1460576D01*
G02X872841Y1460434I-200J0D01*
G01X872211Y1459804D01*
G03X872209Y1459802I140J-142D01*
G03X872138Y1459627I178J-174D01*
G01Y1446008D01*
G02X872079Y1445866I-200J0D01*
G01X871383Y1445170D01*
G02X871241Y1445112I-141J142D01*
G01X858287D01*
G02X858145Y1445171I0J200D01*
G01X857137Y1446178D01*
G02X857078Y1446320I141J142D01*
G01Y1459524D01*
G03X857007Y1459699I-249J1D01*
G03X857005Y1459701I-142J-140D01*
G01X852953Y1463753D01*
G03X852951Y1463755I-142J-140D01*
G03X852776Y1463826I-174J-178D01*
G01X828441D01*
G03X828266Y1463755I-1J-249D01*
G03X828264Y1463753I140J-142D01*
G01X827747Y1463236D01*
G03X827674Y1463060I176J-176D01*
G01Y1461432D01*
G02X827615Y1461290I-200J0D01*
G01X826986Y1460661D01*
G02X826844Y1460602I-142J141D01*
G01X825036D01*
G03X824860Y1460529I0J-249D01*
G01X821948Y1457617D01*
G02X821806Y1457558I-142J141D01*
G01X820451D01*
G03X820275Y1457485I0J-249D01*
G01X820069Y1457279D01*
G03X820067Y1457277I140J-142D01*
G03X819996Y1457102I178J-174D01*
G01Y1446047D01*
G02X819937Y1445905I-200J0D01*
G01X819241Y1445209D01*
G02X819099Y1445150I-142J141D01*
G01X805978D01*
G02X805836Y1445209I0J200D01*
G01X805061Y1445984D01*
G02X805002Y1446126I141J142D01*
G01Y1460243D01*
G02X805061Y1460385I200J0D01*
G01X805487Y1460810D01*
G03X805560Y1460986I-176J176D01*
G01Y1474724D01*
G02X805619Y1474866I200J0D01*
G01X805875Y1475122D01*
G03X805877Y1475124I-140J142D01*
G03X805948Y1475299I-178J174D01*
G01Y1524130D01*
G02X806007Y1524272I200J0D01*
G01X816121Y1534385D01*
G03X816123Y1534387I-140J142D01*
G03X816194Y1534562I-178J174D01*
G01Y1621268D01*
G02X816253Y1621410I200J0D01*
G01X822113Y1627269D01*
G02X822255Y1627328I142J-141D01*
G01X927980D01*
G02X928122Y1627269I0J-200D01*
G01X933115Y1622276D01*
G02X933174Y1622134I-141J-142D01*
G01Y1586005D01*
G03X933247Y1585829I249J0D01*
G37*
G36*
G01X404759Y1350874D02*
X408159D01*
G02Y1347270I0J-1802D01*
G01X404759D01*
G02Y1350874I0J1802D01*
G37*
G36*
G01X402489Y1419078D02*
X405889D01*
G02Y1415472I0J-1803D01*
G01X402489D01*
G02Y1419078I0J1803D01*
G37*
G36*
G01X1443660Y1308896D02*
X1440260D01*
G02Y1312500I0J1802D01*
G01X1443660D01*
G02Y1308896I0J-1802D01*
G37*
G36*
G01X970197Y665850D02*
X966797D01*
G02Y669456I0J1803D01*
G01X970197D01*
G02Y665850I0J-1803D01*
G37*
G36*
G01X501495Y772260D02*
X504895D01*
G02Y768654I0J-1803D01*
G01X501495D01*
G02Y772260I0J1803D01*
G37*
G36*
G01X909508Y623418D02*
X912908D01*
G02Y619814I0J-1802D01*
G01X909508D01*
G02Y623418I0J1802D01*
G37*
G36*
G01X900676Y623338D02*
X904076D01*
G02Y619734I0J-1802D01*
G01X900676D01*
G02Y623338I0J1802D01*
G37*
G36*
G01X526264Y665858D02*
X529664D01*
G02Y662254I0J-1802D01*
G01X526264D01*
G02Y665858I0J1802D01*
G37*
G36*
G01X534264Y663358D02*
X537664D01*
G02Y659754I0J-1802D01*
G01X534264D01*
G02Y663358I0J1802D01*
G37*
G36*
G01X538985Y734790D02*
X535585D01*
G02Y738396I0J1803D01*
G01X538985D01*
G02Y734790I0J-1803D01*
G37*
G36*
G01X530985Y739790D02*
X527585D01*
G02Y743396I0J1803D01*
G01X530985D01*
G02Y739790I0J-1803D01*
G37*
G36*
G01X517731Y742874D02*
X521131D01*
G02Y739268I0J-1803D01*
G01X517731D01*
G02Y742874I0J1803D01*
G37*
G36*
G01X511724Y739232D02*
X508324D01*
G02Y742838I0J1803D01*
G01X511724D01*
G02Y739232I0J-1803D01*
G37*
G36*
G01X415777Y306272D02*
X419177D01*
G02Y302668I0J-1802D01*
G01X415777D01*
G02Y306272I0J1802D01*
G37*
G36*
G01X423651Y309272D02*
X427051D01*
G02Y305668I0J-1802D01*
G01X423651D01*
G02Y309272I0J1802D01*
G37*
G36*
G01X431525Y306272D02*
X434925D01*
G02Y302668I0J-1802D01*
G01X431525D01*
G02Y306272I0J1802D01*
G37*
G36*
G01X434924Y368506D02*
X431524D01*
G02Y372112I0J1803D01*
G01X434924D01*
G02Y368506I0J-1803D01*
G37*
G36*
G01X26772Y1559218D02*
X20472D01*
G02Y1575428I0J8105D01*
G01X26772D01*
G02Y1559218I0J-8105D01*
G37*
G36*
G01X216125Y1441832D02*
X219525D01*
G02Y1438226I0J-1803D01*
G01X216125D01*
G02Y1441832I0J1803D01*
G37*
G36*
G01X413753Y1518690D02*
X417153D01*
G02Y1515084I0J-1803D01*
G01X413753D01*
G02Y1518690I0J1803D01*
G37*
G36*
G01X417334Y1475298D02*
X413934D01*
G02Y1478902I0J1802D01*
G01X417334D01*
G02Y1475298I0J-1802D01*
G37*
G36*
G01X919628Y334530D02*
X916228D01*
G02Y338136I0J1803D01*
G01X919628D01*
G02Y334530I0J-1803D01*
G37*
G36*
G01X905899Y304150D02*
X909299D01*
G02Y300544I0J-1803D01*
G01X905899D01*
G02Y304150I0J1803D01*
G37*
G36*
G01X1033891Y298096D02*
X1037291D01*
G02Y294490I0J-1803D01*
G01X1033891D01*
G02Y298096I0J1803D01*
G37*
G36*
G01X1318363Y312364D02*
X1321763D01*
G02Y308760I0J-1802D01*
G01X1318363D01*
G02Y312364I0J1802D01*
G37*
G36*
G01X1337508Y371598D02*
X1334108D01*
G02Y375204I0J1803D01*
G01X1337508D01*
G02Y371598I0J-1803D01*
G37*
G36*
G01X1326237Y309364D02*
X1329637D01*
G02Y305760I0J-1802D01*
G01X1326237D01*
G02Y309364I0J1802D01*
G37*
G36*
G01X1334111Y312364D02*
X1337511D01*
G02Y308760I0J-1802D01*
G01X1334111D01*
G02Y312364I0J1802D01*
G37*
G36*
G01X1518207Y1176748D02*
X1514467D01*
G02Y1179354I0J1303D01*
G01X1518207D01*
G02Y1176748I0J-1303D01*
G37*
G36*
G01Y1169268D02*
X1514467D01*
G02Y1171872I0J1302D01*
G01X1518207D01*
G02Y1169268I0J-1302D01*
G37*
G36*
G01X1513926Y907148D02*
X1510526D01*
G02Y910754I0J1803D01*
G01X1513926D01*
G02Y907148I0J-1803D01*
G37*
G36*
G01X1531299Y1174878D02*
X1527559D01*
G02Y1177482I0J1302D01*
G01X1531299D01*
G02Y1174878I0J-1302D01*
G37*
G36*
G01X146947Y1176748D02*
X143207D01*
G02Y1179354I0J1303D01*
G01X146947D01*
G02Y1176748I0J-1303D01*
G37*
G36*
G01Y1169268D02*
X143207D01*
G02Y1171872I0J1302D01*
G01X146947D01*
G02Y1169268I0J-1302D01*
G37*
G36*
G01X160039Y1174878D02*
X156299D01*
G02Y1177482I0J1302D01*
G01X160039D01*
G02Y1174878I0J-1302D01*
G37*
G36*
G01X604034Y1176748D02*
X600294D01*
G02Y1179354I0J1303D01*
G01X604034D01*
G02Y1176748I0J-1303D01*
G37*
G36*
G01Y1169268D02*
X600294D01*
G02Y1171872I0J1302D01*
G01X604034D01*
G02Y1169268I0J-1302D01*
G37*
G36*
G01X605733Y942940D02*
X609133D01*
G02Y939336I0J-1802D01*
G01X605733D01*
G02Y942940I0J1802D01*
G37*
G36*
G01X615256Y1176748D02*
X611516D01*
G02Y1179354I0J1303D01*
G01X615256D01*
G02Y1176748I0J-1303D01*
G37*
G36*
G01X1061120D02*
X1057380D01*
G02Y1179354I0J1303D01*
G01X1061120D01*
G02Y1176748I0J-1303D01*
G37*
G36*
G01Y1169268D02*
X1057380D01*
G02Y1171872I0J1302D01*
G01X1061120D01*
G02Y1169268I0J-1302D01*
G37*
G36*
G01X1769063Y921922D02*
X1765663D01*
G02Y925526I0J1802D01*
G01X1769063D01*
G02Y921922I0J-1802D01*
G37*
G36*
G01X1072342Y1176748D02*
X1068602D01*
G02Y1179354I0J1303D01*
G01X1072342D01*
G02Y1176748I0J-1303D01*
G37*
G36*
G01X647411Y379065D02*
X647412D01*
G02Y370659I0J-4203D01*
G01X647411D01*
G02Y379065I0J4203D01*
G37*
G36*
G01X111494Y1456412D02*
G02X111292Y1456210I-202J0D01*
G01X108472D01*
G02X108270Y1456413I1J203D01*
G01Y1457032D01*
G03X108220Y1457164I-200J0D01*
G02Y1460080I1661J1458D01*
G03X108270Y1460212I-150J132D01*
G01Y1462151D01*
G03X108220Y1462283I-200J0D01*
G02Y1465199I1661J1458D01*
G03X108270Y1465331I-150J132D01*
G01Y1465952D01*
G02X108472Y1466154I202J0D01*
G01X111292D01*
G02X111494Y1465951I-1J-203D01*
G01Y1465331D01*
G03X111544Y1465199I200J0D01*
G02Y1462283I-1661J-1458D01*
G03X111494Y1462151I150J-132D01*
G01Y1460212D01*
G03X111544Y1460080I200J0D01*
G02Y1457164I-1661J-1458D01*
G03X111494Y1457032I150J-132D01*
G01Y1456412D01*
G37*
G36*
G01X319368D02*
G02X319166Y1456210I-202J0D01*
G01X316346D01*
G02X316144Y1456413I1J203D01*
G01Y1457032D01*
G03X316094Y1457164I-200J0D01*
G02Y1460080I1661J1458D01*
G03X316144Y1460212I-150J132D01*
G01Y1462151D01*
G03X316094Y1462283I-200J0D01*
G02Y1465199I1661J1458D01*
G03X316144Y1465331I-150J132D01*
G01Y1465952D01*
G02X316346Y1466154I202J0D01*
G01X319166D01*
G02X319368Y1465951I-1J-203D01*
G01Y1465331D01*
G03X319418Y1465199I200J0D01*
G02Y1462283I-1661J-1458D01*
G03X319368Y1462151I150J-132D01*
G01Y1460212D01*
G03X319418Y1460080I200J0D01*
G02Y1457164I-1661J-1458D01*
G03X319368Y1457032I150J-132D01*
G01Y1456412D01*
G37*
G36*
G01X336690D02*
G02X336488Y1456210I-202J0D01*
G01X333668D01*
G02X333466Y1456413I1J203D01*
G01Y1457032D01*
G03X333416Y1457164I-200J0D01*
G02Y1460080I1661J1458D01*
G03X333466Y1460212I-150J132D01*
G01Y1462151D01*
G03X333416Y1462283I-200J0D01*
G02Y1465199I1661J1458D01*
G03X333466Y1465331I-150J132D01*
G01Y1465952D01*
G02X333668Y1466154I202J0D01*
G01X336488D01*
G02X336690Y1465951I-1J-203D01*
G01Y1465331D01*
G03X336740Y1465199I200J0D01*
G02Y1462283I-1661J-1458D01*
G03X336690Y1462151I150J-132D01*
G01Y1460212D01*
G03X336740Y1460080I200J0D01*
G02Y1457164I-1661J-1458D01*
G03X336690Y1457032I150J-132D01*
G01Y1456412D01*
G37*
G36*
G01X628157Y1466154D02*
X630977D01*
G02X631180Y1465951I0J-203D01*
G01Y1465329D01*
G03X631230Y1465197I200J0D01*
G02Y1462285I-1664J-1456D01*
G03X631180Y1462153I150J-132D01*
G01Y1460210D01*
G03X631230Y1460078I200J0D01*
G02Y1457166I-1664J-1456D01*
G03X631180Y1457034I150J-132D01*
G01Y1456413D01*
G02X630977Y1456210I-203J0D01*
G01X628157D01*
G02X627954Y1456413I0J203D01*
G01Y1457034D01*
G03X627904Y1457166I-200J0D01*
G02Y1460078I1664J1456D01*
G03X627954Y1460210I-150J132D01*
G01Y1462153D01*
G03X627904Y1462285I-200J0D01*
G02Y1465197I1664J1456D01*
G03X627954Y1465329I-150J132D01*
G01Y1465951D01*
G02X628157Y1466154I203J0D01*
G37*
G36*
G01X1133462Y1456412D02*
G02X1133260Y1456210I-202J0D01*
G01X1130440D01*
G02X1130238Y1456413I1J203D01*
G01Y1457032D01*
G03X1130188Y1457164I-200J0D01*
G02Y1460080I1661J1458D01*
G03X1130238Y1460212I-150J132D01*
G01Y1462151D01*
G03X1130188Y1462283I-200J0D01*
G02Y1465199I1661J1458D01*
G03X1130238Y1465331I-150J132D01*
G01Y1465952D01*
G02X1130440Y1466154I202J0D01*
G01X1133260D01*
G02X1133462Y1465951I-1J-203D01*
G01Y1465331D01*
G03X1133512Y1465199I200J0D01*
G02Y1462283I-1661J-1458D01*
G03X1133462Y1462151I150J-132D01*
G01Y1460212D01*
G03X1133512Y1460080I200J0D01*
G02Y1457164I-1661J-1458D01*
G03X1133462Y1457032I150J-132D01*
G01Y1456412D01*
G37*
G36*
G01X1147763Y1466154D02*
X1150583D01*
G02X1150786Y1465951I0J-203D01*
G01Y1465329D01*
G03X1150836Y1465197I200J0D01*
G02Y1462285I-1664J-1456D01*
G03X1150786Y1462153I150J-132D01*
G01Y1460210D01*
G03X1150836Y1460078I200J0D01*
G02Y1457166I-1664J-1456D01*
G03X1150786Y1457034I150J-132D01*
G01Y1456413D01*
G02X1150583Y1456210I-203J0D01*
G01X1147763D01*
G02X1147560Y1456413I0J203D01*
G01Y1457034D01*
G03X1147510Y1457166I-200J0D01*
G02Y1460078I1664J1456D01*
G03X1147560Y1460210I-150J132D01*
G01Y1462153D01*
G03X1147510Y1462285I-200J0D01*
G02Y1465197I1664J1456D01*
G03X1147560Y1465329I-150J132D01*
G01Y1465951D01*
G02X1147763Y1466154I203J0D01*
G37*
G36*
G01X1650125D02*
X1652945D01*
G02X1653148Y1465951I0J-203D01*
G01Y1465329D01*
G03X1653198Y1465197I200J0D01*
G02Y1462285I-1664J-1456D01*
G03X1653148Y1462153I150J-132D01*
G01Y1460210D01*
G03X1653198Y1460078I200J0D01*
G02Y1457166I-1664J-1456D01*
G03X1653148Y1457034I150J-132D01*
G01Y1456413D01*
G02X1652945Y1456210I-203J0D01*
G01X1650125D01*
G02X1649922Y1456413I0J203D01*
G01Y1457034D01*
G03X1649872Y1457166I-200J0D01*
G02Y1460078I1664J1456D01*
G03X1649922Y1460210I-150J132D01*
G01Y1462153D01*
G03X1649872Y1462285I-200J0D01*
G02Y1465197I1664J1456D01*
G03X1649922Y1465329I-150J132D01*
G01Y1465951D01*
G02X1650125Y1466154I203J0D01*
G37*
G36*
G01X1670470Y1456412D02*
G02X1670268Y1456210I-202J0D01*
G01X1667448D01*
G02X1667246Y1456413I1J203D01*
G01Y1457032D01*
G03X1667196Y1457164I-200J0D01*
G02Y1460080I1661J1458D01*
G03X1667246Y1460212I-150J132D01*
G01Y1462151D01*
G03X1667196Y1462283I-200J0D01*
G02Y1465199I1661J1458D01*
G03X1667246Y1465331I-150J132D01*
G01Y1465952D01*
G02X1667448Y1466154I202J0D01*
G01X1670268D01*
G02X1670470Y1465951I-1J-203D01*
G01Y1465331D01*
G03X1670520Y1465199I200J0D01*
G02Y1462283I-1661J-1458D01*
G03X1670470Y1462151I150J-132D01*
G01Y1460212D01*
G03X1670520Y1460080I200J0D01*
G02Y1457164I-1661J-1458D01*
G03X1670470Y1457032I150J-132D01*
G01Y1456412D01*
G37*
G36*
G01X117133Y1470484D02*
X119953D01*
G02X120156Y1470281I0J-203D01*
G01Y1469659D01*
G03X120206Y1469527I200J0D01*
G02Y1466615I-1664J-1456D01*
G03X120156Y1466483I150J-132D01*
G01Y1464541D01*
G03X120206Y1464409I200J0D01*
G02Y1461497I-1664J-1456D01*
G03X120156Y1461365I150J-132D01*
G01Y1460743D01*
G02X119953Y1460540I-203J0D01*
G01X117133D01*
G02X116930Y1460743I0J203D01*
G01Y1461365D01*
G03X116880Y1461497I-200J0D01*
G02Y1464409I1664J1456D01*
G03X116930Y1464541I-150J132D01*
G01Y1466483D01*
G03X116880Y1466615I-200J0D01*
G02Y1469527I1664J1456D01*
G03X116930Y1469659I-150J132D01*
G01Y1470281D01*
G02X117133Y1470484I203J0D01*
G37*
G36*
G01X310706Y1460742D02*
G02X310504Y1460540I-202J0D01*
G01X307684D01*
G02X307482Y1460743I1J203D01*
G01Y1461363D01*
G03X307432Y1461495I-200J0D01*
G02Y1464411I1661J1458D01*
G03X307482Y1464543I-150J132D01*
G01Y1466481D01*
G03X307432Y1466613I-200J0D01*
G02Y1469529I1661J1458D01*
G03X307482Y1469661I-150J132D01*
G01Y1470282D01*
G02X307684Y1470484I202J0D01*
G01X310504D01*
G02X310706Y1470281I-1J-203D01*
G01Y1469661D01*
G03X310756Y1469529I200J0D01*
G02Y1466613I-1661J-1458D01*
G03X310706Y1466481I150J-132D01*
G01Y1464543D01*
G03X310756Y1464411I200J0D01*
G02Y1461495I-1661J-1458D01*
G03X310706Y1461363I150J-132D01*
G01Y1460742D01*
G37*
G36*
G01X325007Y1470484D02*
X327827D01*
G02X328030Y1470281I0J-203D01*
G01Y1469659D01*
G03X328080Y1469527I200J0D01*
G02Y1466615I-1664J-1456D01*
G03X328030Y1466483I150J-132D01*
G01Y1464541D01*
G03X328080Y1464409I200J0D01*
G02Y1461497I-1664J-1456D01*
G03X328030Y1461365I150J-132D01*
G01Y1460743D01*
G02X327827Y1460540I-203J0D01*
G01X325007D01*
G02X324804Y1460743I0J203D01*
G01Y1461365D01*
G03X324754Y1461497I-200J0D01*
G02Y1464409I1664J1456D01*
G03X324804Y1464541I-150J132D01*
G01Y1466483D01*
G03X324754Y1466615I-200J0D01*
G02Y1469527I1664J1456D01*
G03X324804Y1469659I-150J132D01*
G01Y1470281D01*
G02X325007Y1470484I203J0D01*
G37*
G36*
G01X345352Y1460742D02*
G02X345150Y1460540I-202J0D01*
G01X342330D01*
G02X342128Y1460743I1J203D01*
G01Y1461363D01*
G03X342078Y1461495I-200J0D01*
G02Y1464411I1661J1458D01*
G03X342128Y1464543I-150J132D01*
G01Y1466481D01*
G03X342078Y1466613I-200J0D01*
G02Y1469529I1661J1458D01*
G03X342128Y1469661I-150J132D01*
G01Y1470282D01*
G02X342330Y1470484I202J0D01*
G01X345150D01*
G02X345352Y1470281I-1J-203D01*
G01Y1469661D01*
G03X345402Y1469529I200J0D01*
G02Y1466613I-1661J-1458D01*
G03X345352Y1466481I150J-132D01*
G01Y1464543D01*
G03X345402Y1464411I200J0D01*
G02Y1461495I-1661J-1458D01*
G03X345352Y1461363I150J-132D01*
G01Y1460742D01*
G37*
G36*
G01X639840D02*
G02X639638Y1460540I-202J0D01*
G01X636818D01*
G02X636616Y1460743I1J203D01*
G01Y1461363D01*
G03X636566Y1461495I-200J0D01*
G02Y1464411I1661J1458D01*
G03X636616Y1464543I-150J132D01*
G01Y1466481D01*
G03X636566Y1466613I-200J0D01*
G02Y1469529I1661J1458D01*
G03X636616Y1469661I-150J132D01*
G01Y1470282D01*
G02X636818Y1470484I202J0D01*
G01X639638D01*
G02X639840Y1470281I-1J-203D01*
G01Y1469661D01*
G03X639890Y1469529I200J0D01*
G02Y1466613I-1661J-1458D01*
G03X639840Y1466481I150J-132D01*
G01Y1464543D01*
G03X639890Y1464411I200J0D01*
G02Y1461495I-1661J-1458D01*
G03X639840Y1461363I150J-132D01*
G01Y1460742D01*
G37*
G36*
G01X1139101Y1470484D02*
X1141921D01*
G02X1142124Y1470281I0J-203D01*
G01Y1469659D01*
G03X1142174Y1469527I200J0D01*
G02Y1466615I-1664J-1456D01*
G03X1142124Y1466483I150J-132D01*
G01Y1464541D01*
G03X1142174Y1464409I200J0D01*
G02Y1461497I-1664J-1456D01*
G03X1142124Y1461365I150J-132D01*
G01Y1460743D01*
G02X1141921Y1460540I-203J0D01*
G01X1139101D01*
G02X1138898Y1460743I0J203D01*
G01Y1461365D01*
G03X1138848Y1461497I-200J0D01*
G02Y1464409I1664J1456D01*
G03X1138898Y1464541I-150J132D01*
G01Y1466483D01*
G03X1138848Y1466615I-200J0D01*
G02Y1469527I1664J1456D01*
G03X1138898Y1469659I-150J132D01*
G01Y1470281D01*
G02X1139101Y1470484I203J0D01*
G37*
G36*
G01X1159446Y1460742D02*
G02X1159244Y1460540I-202J0D01*
G01X1156424D01*
G02X1156222Y1460743I1J203D01*
G01Y1461363D01*
G03X1156172Y1461495I-200J0D01*
G02Y1464411I1661J1458D01*
G03X1156222Y1464543I-150J132D01*
G01Y1466481D01*
G03X1156172Y1466613I-200J0D01*
G02Y1469529I1661J1458D01*
G03X1156222Y1469661I-150J132D01*
G01Y1470282D01*
G02X1156424Y1470484I202J0D01*
G01X1159244D01*
G02X1159446Y1470281I-1J-203D01*
G01Y1469661D01*
G03X1159496Y1469529I200J0D01*
G02Y1466613I-1661J-1458D01*
G03X1159446Y1466481I150J-132D01*
G01Y1464543D01*
G03X1159496Y1464411I200J0D01*
G02Y1461495I-1661J-1458D01*
G03X1159446Y1461363I150J-132D01*
G01Y1460742D01*
G37*
G36*
G01X1661808D02*
G02X1661606Y1460540I-202J0D01*
G01X1658786D01*
G02X1658584Y1460743I1J203D01*
G01Y1461363D01*
G03X1658534Y1461495I-200J0D01*
G02Y1464411I1661J1458D01*
G03X1658584Y1464543I-150J132D01*
G01Y1466481D01*
G03X1658534Y1466613I-200J0D01*
G02Y1469529I1661J1458D01*
G03X1658584Y1469661I-150J132D01*
G01Y1470282D01*
G02X1658786Y1470484I202J0D01*
G01X1661606D01*
G02X1661808Y1470281I-1J-203D01*
G01Y1469661D01*
G03X1661858Y1469529I200J0D01*
G02Y1466613I-1661J-1458D01*
G03X1661808Y1466481I150J-132D01*
G01Y1464543D01*
G03X1661858Y1464411I200J0D01*
G02Y1461495I-1661J-1458D01*
G03X1661808Y1461363I150J-132D01*
G01Y1460742D01*
G37*
G36*
G01X1676109Y1470484D02*
X1678929D01*
G02X1679132Y1470281I0J-203D01*
G01Y1469659D01*
G03X1679182Y1469527I200J0D01*
G02Y1466615I-1664J-1456D01*
G03X1679132Y1466483I150J-132D01*
G01Y1464541D01*
G03X1679182Y1464409I200J0D01*
G02Y1461497I-1664J-1456D01*
G03X1679132Y1461365I150J-132D01*
G01Y1460743D01*
G02X1678929Y1460540I-203J0D01*
G01X1676109D01*
G02X1675906Y1460743I0J203D01*
G01Y1461365D01*
G03X1675856Y1461497I-200J0D01*
G02Y1464409I1664J1456D01*
G03X1675906Y1464541I-150J132D01*
G01Y1466483D01*
G03X1675856Y1466615I-200J0D01*
G02Y1469527I1664J1456D01*
G03X1675906Y1469659I-150J132D01*
G01Y1470281D01*
G02X1676109Y1470484I203J0D01*
G37*
G36*
G01X111494Y1471766D02*
G02X111292Y1471564I-202J0D01*
G01X108472D01*
G02X108270Y1471767I1J203D01*
G01Y1472387D01*
G03X108220Y1472519I-200J0D01*
G02Y1475435I1661J1458D01*
G03X108270Y1475567I-150J132D01*
G01Y1477505D01*
G03X108220Y1477637I-200J0D01*
G02Y1480553I1661J1458D01*
G03X108270Y1480685I-150J132D01*
G01Y1481306D01*
G02X108472Y1481508I202J0D01*
G01X111292D01*
G02X111494Y1481305I-1J-203D01*
G01Y1480685D01*
G03X111544Y1480553I200J0D01*
G02Y1477637I-1661J-1458D01*
G03X111494Y1477505I150J-132D01*
G01Y1475567D01*
G03X111544Y1475435I200J0D01*
G02Y1472519I-1661J-1458D01*
G03X111494Y1472387I150J-132D01*
G01Y1471766D01*
G37*
G36*
G01X319368D02*
G02X319166Y1471564I-202J0D01*
G01X316346D01*
G02X316144Y1471767I1J203D01*
G01Y1472387D01*
G03X316094Y1472519I-200J0D01*
G02Y1475435I1661J1458D01*
G03X316144Y1475567I-150J132D01*
G01Y1477505D01*
G03X316094Y1477637I-200J0D01*
G02Y1480553I1661J1458D01*
G03X316144Y1480685I-150J132D01*
G01Y1481306D01*
G02X316346Y1481508I202J0D01*
G01X319166D01*
G02X319368Y1481305I-1J-203D01*
G01Y1480685D01*
G03X319418Y1480553I200J0D01*
G02Y1477637I-1661J-1458D01*
G03X319368Y1477505I150J-132D01*
G01Y1475567D01*
G03X319418Y1475435I200J0D01*
G02Y1472519I-1661J-1458D01*
G03X319368Y1472387I150J-132D01*
G01Y1471766D01*
G37*
G36*
G01X336690D02*
G02X336488Y1471564I-202J0D01*
G01X333668D01*
G02X333466Y1471767I1J203D01*
G01Y1472387D01*
G03X333416Y1472519I-200J0D01*
G02Y1475435I1661J1458D01*
G03X333466Y1475567I-150J132D01*
G01Y1477505D01*
G03X333416Y1477637I-200J0D01*
G02Y1480553I1661J1458D01*
G03X333466Y1480685I-150J132D01*
G01Y1481306D01*
G02X333668Y1481508I202J0D01*
G01X336488D01*
G02X336690Y1481305I-1J-203D01*
G01Y1480685D01*
G03X336740Y1480553I200J0D01*
G02Y1477637I-1661J-1458D01*
G03X336690Y1477505I150J-132D01*
G01Y1475567D01*
G03X336740Y1475435I200J0D01*
G02Y1472519I-1661J-1458D01*
G03X336690Y1472387I150J-132D01*
G01Y1471766D01*
G37*
G36*
G01X628157Y1481508D02*
X630977D01*
G02X631180Y1481305I0J-203D01*
G01Y1480683D01*
G03X631230Y1480551I200J0D01*
G02Y1477639I-1664J-1456D01*
G03X631180Y1477507I150J-132D01*
G01Y1475565D01*
G03X631230Y1475433I200J0D01*
G02Y1472521I-1664J-1456D01*
G03X631180Y1472389I150J-132D01*
G01Y1471767D01*
G02X630977Y1471564I-203J0D01*
G01X628157D01*
G02X627954Y1471767I0J203D01*
G01Y1472389D01*
G03X627904Y1472521I-200J0D01*
G02Y1475433I1664J1456D01*
G03X627954Y1475565I-150J132D01*
G01Y1477507D01*
G03X627904Y1477639I-200J0D01*
G02Y1480551I1664J1456D01*
G03X627954Y1480683I-150J132D01*
G01Y1481305D01*
G02X628157Y1481508I203J0D01*
G37*
G36*
G01X1133462Y1471766D02*
G02X1133260Y1471564I-202J0D01*
G01X1130440D01*
G02X1130238Y1471767I1J203D01*
G01Y1472387D01*
G03X1130188Y1472519I-200J0D01*
G02Y1475435I1661J1458D01*
G03X1130238Y1475567I-150J132D01*
G01Y1477505D01*
G03X1130188Y1477637I-200J0D01*
G02Y1480553I1661J1458D01*
G03X1130238Y1480685I-150J132D01*
G01Y1481306D01*
G02X1130440Y1481508I202J0D01*
G01X1133260D01*
G02X1133462Y1481305I-1J-203D01*
G01Y1480685D01*
G03X1133512Y1480553I200J0D01*
G02Y1477637I-1661J-1458D01*
G03X1133462Y1477505I150J-132D01*
G01Y1475567D01*
G03X1133512Y1475435I200J0D01*
G02Y1472519I-1661J-1458D01*
G03X1133462Y1472387I150J-132D01*
G01Y1471766D01*
G37*
G36*
G01X1147763Y1481508D02*
X1150583D01*
G02X1150786Y1481305I0J-203D01*
G01Y1480683D01*
G03X1150836Y1480551I200J0D01*
G02Y1477639I-1664J-1456D01*
G03X1150786Y1477507I150J-132D01*
G01Y1475565D01*
G03X1150836Y1475433I200J0D01*
G02Y1472521I-1664J-1456D01*
G03X1150786Y1472389I150J-132D01*
G01Y1471767D01*
G02X1150583Y1471564I-203J0D01*
G01X1147763D01*
G02X1147560Y1471767I0J203D01*
G01Y1472389D01*
G03X1147510Y1472521I-200J0D01*
G02Y1475433I1664J1456D01*
G03X1147560Y1475565I-150J132D01*
G01Y1477507D01*
G03X1147510Y1477639I-200J0D01*
G02Y1480551I1664J1456D01*
G03X1147560Y1480683I-150J132D01*
G01Y1481305D01*
G02X1147763Y1481508I203J0D01*
G37*
G36*
G01X1650125D02*
X1652945D01*
G02X1653148Y1481305I0J-203D01*
G01Y1480683D01*
G03X1653198Y1480551I200J0D01*
G02Y1477639I-1664J-1456D01*
G03X1653148Y1477507I150J-132D01*
G01Y1475565D01*
G03X1653198Y1475433I200J0D01*
G02Y1472521I-1664J-1456D01*
G03X1653148Y1472389I150J-132D01*
G01Y1471767D01*
G02X1652945Y1471564I-203J0D01*
G01X1650125D01*
G02X1649922Y1471767I0J203D01*
G01Y1472389D01*
G03X1649872Y1472521I-200J0D01*
G02Y1475433I1664J1456D01*
G03X1649922Y1475565I-150J132D01*
G01Y1477507D01*
G03X1649872Y1477639I-200J0D01*
G02Y1480551I1664J1456D01*
G03X1649922Y1480683I-150J132D01*
G01Y1481305D01*
G02X1650125Y1481508I203J0D01*
G37*
G36*
G01X1670470Y1471766D02*
G02X1670268Y1471564I-202J0D01*
G01X1667448D01*
G02X1667246Y1471767I1J203D01*
G01Y1472387D01*
G03X1667196Y1472519I-200J0D01*
G02Y1475435I1661J1458D01*
G03X1667246Y1475567I-150J132D01*
G01Y1477505D01*
G03X1667196Y1477637I-200J0D01*
G02Y1480553I1661J1458D01*
G03X1667246Y1480685I-150J132D01*
G01Y1481306D01*
G02X1667448Y1481508I202J0D01*
G01X1670268D01*
G02X1670470Y1481305I-1J-203D01*
G01Y1480685D01*
G03X1670520Y1480553I200J0D01*
G02Y1477637I-1661J-1458D01*
G03X1670470Y1477505I150J-132D01*
G01Y1475567D01*
G03X1670520Y1475435I200J0D01*
G02Y1472519I-1661J-1458D01*
G03X1670470Y1472387I150J-132D01*
G01Y1471766D01*
G37*
G36*
G01X117133Y1485838D02*
X119953D01*
G02X120156Y1485635I0J-203D01*
G01Y1485014D01*
G03X120206Y1484882I200J0D01*
G02Y1481970I-1664J-1456D01*
G03X120156Y1481838I150J-132D01*
G01Y1479896D01*
G03X120206Y1479764I200J0D01*
G02Y1476852I-1664J-1456D01*
G03X120156Y1476720I150J-132D01*
G01Y1476097D01*
G02X119953Y1475894I-203J0D01*
G01X117133D01*
G02X116930Y1476097I0J203D01*
G01Y1476720D01*
G03X116880Y1476852I-200J0D01*
G02Y1479764I1664J1456D01*
G03X116930Y1479896I-150J132D01*
G01Y1481838D01*
G03X116880Y1481970I-200J0D01*
G02Y1484882I1664J1456D01*
G03X116930Y1485014I-150J132D01*
G01Y1485635D01*
G02X117133Y1485838I203J0D01*
G37*
G36*
G01X310706Y1476096D02*
G02X310504Y1475894I-202J0D01*
G01X307684D01*
G02X307482Y1476097I1J203D01*
G01Y1476718D01*
G03X307432Y1476850I-200J0D01*
G02Y1479766I1661J1458D01*
G03X307482Y1479898I-150J132D01*
G01Y1481836D01*
G03X307432Y1481968I-200J0D01*
G02Y1484884I1661J1458D01*
G03X307482Y1485016I-150J132D01*
G01Y1485636D01*
G02X307684Y1485838I202J0D01*
G01X310504D01*
G02X310706Y1485635I-1J-203D01*
G01Y1485016D01*
G03X310756Y1484884I200J0D01*
G02Y1481968I-1661J-1458D01*
G03X310706Y1481836I150J-132D01*
G01Y1479898D01*
G03X310756Y1479766I200J0D01*
G02Y1476850I-1661J-1458D01*
G03X310706Y1476718I150J-132D01*
G01Y1476096D01*
G37*
G36*
G01X325007Y1485838D02*
X327827D01*
G02X328030Y1485635I0J-203D01*
G01Y1485014D01*
G03X328080Y1484882I200J0D01*
G02Y1481970I-1664J-1456D01*
G03X328030Y1481838I150J-132D01*
G01Y1479896D01*
G03X328080Y1479764I200J0D01*
G02Y1476852I-1664J-1456D01*
G03X328030Y1476720I150J-132D01*
G01Y1476097D01*
G02X327827Y1475894I-203J0D01*
G01X325007D01*
G02X324804Y1476097I0J203D01*
G01Y1476720D01*
G03X324754Y1476852I-200J0D01*
G02Y1479764I1664J1456D01*
G03X324804Y1479896I-150J132D01*
G01Y1481838D01*
G03X324754Y1481970I-200J0D01*
G02Y1484882I1664J1456D01*
G03X324804Y1485014I-150J132D01*
G01Y1485635D01*
G02X325007Y1485838I203J0D01*
G37*
G36*
G01X345352Y1476096D02*
G02X345150Y1475894I-202J0D01*
G01X342330D01*
G02X342128Y1476097I1J203D01*
G01Y1476718D01*
G03X342078Y1476850I-200J0D01*
G02Y1479766I1661J1458D01*
G03X342128Y1479898I-150J132D01*
G01Y1481836D01*
G03X342078Y1481968I-200J0D01*
G02Y1484884I1661J1458D01*
G03X342128Y1485016I-150J132D01*
G01Y1485636D01*
G02X342330Y1485838I202J0D01*
G01X345150D01*
G02X345352Y1485635I-1J-203D01*
G01Y1485016D01*
G03X345402Y1484884I200J0D01*
G02Y1481968I-1661J-1458D01*
G03X345352Y1481836I150J-132D01*
G01Y1479898D01*
G03X345402Y1479766I200J0D01*
G02Y1476850I-1661J-1458D01*
G03X345352Y1476718I150J-132D01*
G01Y1476096D01*
G37*
G36*
G01X639840D02*
G02X639638Y1475894I-202J0D01*
G01X636818D01*
G02X636616Y1476097I1J203D01*
G01Y1476718D01*
G03X636566Y1476850I-200J0D01*
G02Y1479766I1661J1458D01*
G03X636616Y1479898I-150J132D01*
G01Y1481836D01*
G03X636566Y1481968I-200J0D01*
G02Y1484884I1661J1458D01*
G03X636616Y1485016I-150J132D01*
G01Y1485636D01*
G02X636818Y1485838I202J0D01*
G01X639638D01*
G02X639840Y1485635I-1J-203D01*
G01Y1485016D01*
G03X639890Y1484884I200J0D01*
G02Y1481968I-1661J-1458D01*
G03X639840Y1481836I150J-132D01*
G01Y1479898D01*
G03X639890Y1479766I200J0D01*
G02Y1476850I-1661J-1458D01*
G03X639840Y1476718I150J-132D01*
G01Y1476096D01*
G37*
G36*
G01X1139101Y1485838D02*
X1141921D01*
G02X1142124Y1485635I0J-203D01*
G01Y1485014D01*
G03X1142174Y1484882I200J0D01*
G02Y1481970I-1664J-1456D01*
G03X1142124Y1481838I150J-132D01*
G01Y1479896D01*
G03X1142174Y1479764I200J0D01*
G02Y1476852I-1664J-1456D01*
G03X1142124Y1476720I150J-132D01*
G01Y1476097D01*
G02X1141921Y1475894I-203J0D01*
G01X1139101D01*
G02X1138898Y1476097I0J203D01*
G01Y1476720D01*
G03X1138848Y1476852I-200J0D01*
G02Y1479764I1664J1456D01*
G03X1138898Y1479896I-150J132D01*
G01Y1481838D01*
G03X1138848Y1481970I-200J0D01*
G02Y1484882I1664J1456D01*
G03X1138898Y1485014I-150J132D01*
G01Y1485635D01*
G02X1139101Y1485838I203J0D01*
G37*
G36*
G01X1159446Y1476096D02*
G02X1159244Y1475894I-202J0D01*
G01X1156424D01*
G02X1156222Y1476097I1J203D01*
G01Y1476718D01*
G03X1156172Y1476850I-200J0D01*
G02Y1479766I1661J1458D01*
G03X1156222Y1479898I-150J132D01*
G01Y1481836D01*
G03X1156172Y1481968I-200J0D01*
G02Y1484884I1661J1458D01*
G03X1156222Y1485016I-150J132D01*
G01Y1485636D01*
G02X1156424Y1485838I202J0D01*
G01X1159244D01*
G02X1159446Y1485635I-1J-203D01*
G01Y1485016D01*
G03X1159496Y1484884I200J0D01*
G02Y1481968I-1661J-1458D01*
G03X1159446Y1481836I150J-132D01*
G01Y1479898D01*
G03X1159496Y1479766I200J0D01*
G02Y1476850I-1661J-1458D01*
G03X1159446Y1476718I150J-132D01*
G01Y1476096D01*
G37*
G36*
G01X1661808D02*
G02X1661606Y1475894I-202J0D01*
G01X1658786D01*
G02X1658584Y1476097I1J203D01*
G01Y1476718D01*
G03X1658534Y1476850I-200J0D01*
G02Y1479766I1661J1458D01*
G03X1658584Y1479898I-150J132D01*
G01Y1481836D01*
G03X1658534Y1481968I-200J0D01*
G02Y1484884I1661J1458D01*
G03X1658584Y1485016I-150J132D01*
G01Y1485636D01*
G02X1658786Y1485838I202J0D01*
G01X1661606D01*
G02X1661808Y1485635I-1J-203D01*
G01Y1485016D01*
G03X1661858Y1484884I200J0D01*
G02Y1481968I-1661J-1458D01*
G03X1661808Y1481836I150J-132D01*
G01Y1479898D01*
G03X1661858Y1479766I200J0D01*
G02Y1476850I-1661J-1458D01*
G03X1661808Y1476718I150J-132D01*
G01Y1476096D01*
G37*
G36*
G01X1676109Y1485838D02*
X1678929D01*
G02X1679132Y1485635I0J-203D01*
G01Y1485014D01*
G03X1679182Y1484882I200J0D01*
G02Y1481970I-1664J-1456D01*
G03X1679132Y1481838I150J-132D01*
G01Y1479896D01*
G03X1679182Y1479764I200J0D01*
G02Y1476852I-1664J-1456D01*
G03X1679132Y1476720I150J-132D01*
G01Y1476097D01*
G02X1678929Y1475894I-203J0D01*
G01X1676109D01*
G02X1675906Y1476097I0J203D01*
G01Y1476720D01*
G03X1675856Y1476852I-200J0D01*
G02Y1479764I1664J1456D01*
G03X1675906Y1479896I-150J132D01*
G01Y1481838D01*
G03X1675856Y1481970I-200J0D01*
G02Y1484882I1664J1456D01*
G03X1675906Y1485014I-150J132D01*
G01Y1485635D01*
G02X1676109Y1485838I203J0D01*
G37*
G36*
G01X111494Y1487120D02*
G02X111292Y1486918I-202J0D01*
G01X108472D01*
G02X108270Y1487121I1J203D01*
G01Y1487741D01*
G03X108220Y1487873I-200J0D01*
G02Y1490789I1661J1458D01*
G03X108270Y1490921I-150J132D01*
G01Y1492859D01*
G03X108220Y1492991I-200J0D01*
G02Y1495907I1661J1458D01*
G03X108270Y1496039I-150J132D01*
G01Y1496660D01*
G02X108472Y1496862I202J0D01*
G01X111292D01*
G02X111494Y1496659I-1J-203D01*
G01Y1496039D01*
G03X111544Y1495907I200J0D01*
G02Y1492991I-1661J-1458D01*
G03X111494Y1492859I150J-132D01*
G01Y1490921D01*
G03X111544Y1490789I200J0D01*
G02Y1487873I-1661J-1458D01*
G03X111494Y1487741I150J-132D01*
G01Y1487120D01*
G37*
G36*
G01X319368D02*
G02X319166Y1486918I-202J0D01*
G01X316346D01*
G02X316144Y1487121I1J203D01*
G01Y1487741D01*
G03X316094Y1487873I-200J0D01*
G02Y1490789I1661J1458D01*
G03X316144Y1490921I-150J132D01*
G01Y1492859D01*
G03X316094Y1492991I-200J0D01*
G02Y1495907I1661J1458D01*
G03X316144Y1496039I-150J132D01*
G01Y1496660D01*
G02X316346Y1496862I202J0D01*
G01X319166D01*
G02X319368Y1496659I-1J-203D01*
G01Y1496039D01*
G03X319418Y1495907I200J0D01*
G02Y1492991I-1661J-1458D01*
G03X319368Y1492859I150J-132D01*
G01Y1490921D01*
G03X319418Y1490789I200J0D01*
G02Y1487873I-1661J-1458D01*
G03X319368Y1487741I150J-132D01*
G01Y1487120D01*
G37*
G36*
G01X336690D02*
G02X336488Y1486918I-202J0D01*
G01X333668D01*
G02X333466Y1487121I1J203D01*
G01Y1487741D01*
G03X333416Y1487873I-200J0D01*
G02Y1490789I1661J1458D01*
G03X333466Y1490921I-150J132D01*
G01Y1492859D01*
G03X333416Y1492991I-200J0D01*
G02Y1495907I1661J1458D01*
G03X333466Y1496039I-150J132D01*
G01Y1496660D01*
G02X333668Y1496862I202J0D01*
G01X336488D01*
G02X336690Y1496659I-1J-203D01*
G01Y1496039D01*
G03X336740Y1495907I200J0D01*
G02Y1492991I-1661J-1458D01*
G03X336690Y1492859I150J-132D01*
G01Y1490921D01*
G03X336740Y1490789I200J0D01*
G02Y1487873I-1661J-1458D01*
G03X336690Y1487741I150J-132D01*
G01Y1487120D01*
G37*
G36*
G01X628157Y1496862D02*
X630977D01*
G02X631180Y1496659I0J-203D01*
G01Y1496037D01*
G03X631230Y1495905I200J0D01*
G02Y1492993I-1664J-1456D01*
G03X631180Y1492861I150J-132D01*
G01Y1490919D01*
G03X631230Y1490787I200J0D01*
G02Y1487875I-1664J-1456D01*
G03X631180Y1487743I150J-132D01*
G01Y1487121D01*
G02X630977Y1486918I-203J0D01*
G01X628157D01*
G02X627954Y1487121I0J203D01*
G01Y1487743D01*
G03X627904Y1487875I-200J0D01*
G02Y1490787I1664J1456D01*
G03X627954Y1490919I-150J132D01*
G01Y1492861D01*
G03X627904Y1492993I-200J0D01*
G02Y1495905I1664J1456D01*
G03X627954Y1496037I-150J132D01*
G01Y1496659D01*
G02X628157Y1496862I203J0D01*
G37*
G36*
G01X1133462Y1487120D02*
G02X1133260Y1486918I-202J0D01*
G01X1130440D01*
G02X1130238Y1487121I1J203D01*
G01Y1487741D01*
G03X1130188Y1487873I-200J0D01*
G02Y1490789I1661J1458D01*
G03X1130238Y1490921I-150J132D01*
G01Y1492859D01*
G03X1130188Y1492991I-200J0D01*
G02Y1495907I1661J1458D01*
G03X1130238Y1496039I-150J132D01*
G01Y1496660D01*
G02X1130440Y1496862I202J0D01*
G01X1133260D01*
G02X1133462Y1496659I-1J-203D01*
G01Y1496039D01*
G03X1133512Y1495907I200J0D01*
G02Y1492991I-1661J-1458D01*
G03X1133462Y1492859I150J-132D01*
G01Y1490921D01*
G03X1133512Y1490789I200J0D01*
G02Y1487873I-1661J-1458D01*
G03X1133462Y1487741I150J-132D01*
G01Y1487120D01*
G37*
G36*
G01X1147763Y1496862D02*
X1150583D01*
G02X1150786Y1496659I0J-203D01*
G01Y1496037D01*
G03X1150836Y1495905I200J0D01*
G02Y1492993I-1664J-1456D01*
G03X1150786Y1492861I150J-132D01*
G01Y1490919D01*
G03X1150836Y1490787I200J0D01*
G02Y1487875I-1664J-1456D01*
G03X1150786Y1487743I150J-132D01*
G01Y1487121D01*
G02X1150583Y1486918I-203J0D01*
G01X1147763D01*
G02X1147560Y1487121I0J203D01*
G01Y1487743D01*
G03X1147510Y1487875I-200J0D01*
G02Y1490787I1664J1456D01*
G03X1147560Y1490919I-150J132D01*
G01Y1492861D01*
G03X1147510Y1492993I-200J0D01*
G02Y1495905I1664J1456D01*
G03X1147560Y1496037I-150J132D01*
G01Y1496659D01*
G02X1147763Y1496862I203J0D01*
G37*
G36*
G01X1650125D02*
X1652945D01*
G02X1653148Y1496659I0J-203D01*
G01Y1496037D01*
G03X1653198Y1495905I200J0D01*
G02Y1492993I-1664J-1456D01*
G03X1653148Y1492861I150J-132D01*
G01Y1490919D01*
G03X1653198Y1490787I200J0D01*
G02Y1487875I-1664J-1456D01*
G03X1653148Y1487743I150J-132D01*
G01Y1487121D01*
G02X1652945Y1486918I-203J0D01*
G01X1650125D01*
G02X1649922Y1487121I0J203D01*
G01Y1487743D01*
G03X1649872Y1487875I-200J0D01*
G02Y1490787I1664J1456D01*
G03X1649922Y1490919I-150J132D01*
G01Y1492861D01*
G03X1649872Y1492993I-200J0D01*
G02Y1495905I1664J1456D01*
G03X1649922Y1496037I-150J132D01*
G01Y1496659D01*
G02X1650125Y1496862I203J0D01*
G37*
G36*
G01X1670470Y1487120D02*
G02X1670268Y1486918I-202J0D01*
G01X1667448D01*
G02X1667246Y1487121I1J203D01*
G01Y1487741D01*
G03X1667196Y1487873I-200J0D01*
G02Y1490789I1661J1458D01*
G03X1667246Y1490921I-150J132D01*
G01Y1492859D01*
G03X1667196Y1492991I-200J0D01*
G02Y1495907I1661J1458D01*
G03X1667246Y1496039I-150J132D01*
G01Y1496660D01*
G02X1667448Y1496862I202J0D01*
G01X1670268D01*
G02X1670470Y1496659I-1J-203D01*
G01Y1496039D01*
G03X1670520Y1495907I200J0D01*
G02Y1492991I-1661J-1458D01*
G03X1670470Y1492859I150J-132D01*
G01Y1490921D01*
G03X1670520Y1490789I200J0D01*
G02Y1487873I-1661J-1458D01*
G03X1670470Y1487741I150J-132D01*
G01Y1487120D01*
G37*
G36*
G01X117133Y1501192D02*
X119953D01*
G02X120156Y1500989I0J-203D01*
G01Y1500368D01*
G03X120206Y1500236I200J0D01*
G02Y1497324I-1664J-1456D01*
G03X120156Y1497192I150J-132D01*
G01Y1495250D01*
G03X120206Y1495118I200J0D01*
G02Y1492206I-1664J-1456D01*
G03X120156Y1492074I150J-132D01*
G01Y1491451D01*
G02X119953Y1491248I-203J0D01*
G01X117133D01*
G02X116930Y1491451I0J203D01*
G01Y1492074D01*
G03X116880Y1492206I-200J0D01*
G02Y1495118I1664J1456D01*
G03X116930Y1495250I-150J132D01*
G01Y1497192D01*
G03X116880Y1497324I-200J0D01*
G02Y1500236I1664J1456D01*
G03X116930Y1500368I-150J132D01*
G01Y1500989D01*
G02X117133Y1501192I203J0D01*
G37*
G36*
G01X310706Y1491450D02*
G02X310504Y1491248I-202J0D01*
G01X307684D01*
G02X307482Y1491451I1J203D01*
G01Y1492072D01*
G03X307432Y1492204I-200J0D01*
G02Y1495120I1661J1458D01*
G03X307482Y1495252I-150J132D01*
G01Y1497190D01*
G03X307432Y1497322I-200J0D01*
G02Y1500238I1661J1458D01*
G03X307482Y1500370I-150J132D01*
G01Y1500990D01*
G02X307684Y1501192I202J0D01*
G01X310504D01*
G02X310706Y1500989I-1J-203D01*
G01Y1500370D01*
G03X310756Y1500238I200J0D01*
G02Y1497322I-1661J-1458D01*
G03X310706Y1497190I150J-132D01*
G01Y1495252D01*
G03X310756Y1495120I200J0D01*
G02Y1492204I-1661J-1458D01*
G03X310706Y1492072I150J-132D01*
G01Y1491450D01*
G37*
G36*
G01X325007Y1501192D02*
X327827D01*
G02X328030Y1500989I0J-203D01*
G01Y1500368D01*
G03X328080Y1500236I200J0D01*
G02Y1497324I-1664J-1456D01*
G03X328030Y1497192I150J-132D01*
G01Y1495250D01*
G03X328080Y1495118I200J0D01*
G02Y1492206I-1664J-1456D01*
G03X328030Y1492074I150J-132D01*
G01Y1491451D01*
G02X327827Y1491248I-203J0D01*
G01X325007D01*
G02X324804Y1491451I0J203D01*
G01Y1492074D01*
G03X324754Y1492206I-200J0D01*
G02Y1495118I1664J1456D01*
G03X324804Y1495250I-150J132D01*
G01Y1497192D01*
G03X324754Y1497324I-200J0D01*
G02Y1500236I1664J1456D01*
G03X324804Y1500368I-150J132D01*
G01Y1500989D01*
G02X325007Y1501192I203J0D01*
G37*
G36*
G01X345352Y1491450D02*
G02X345150Y1491248I-202J0D01*
G01X342330D01*
G02X342128Y1491451I1J203D01*
G01Y1492072D01*
G03X342078Y1492204I-200J0D01*
G02Y1495120I1661J1458D01*
G03X342128Y1495252I-150J132D01*
G01Y1497190D01*
G03X342078Y1497322I-200J0D01*
G02Y1500238I1661J1458D01*
G03X342128Y1500370I-150J132D01*
G01Y1500990D01*
G02X342330Y1501192I202J0D01*
G01X345150D01*
G02X345352Y1500989I-1J-203D01*
G01Y1500370D01*
G03X345402Y1500238I200J0D01*
G02Y1497322I-1661J-1458D01*
G03X345352Y1497190I150J-132D01*
G01Y1495252D01*
G03X345402Y1495120I200J0D01*
G02Y1492204I-1661J-1458D01*
G03X345352Y1492072I150J-132D01*
G01Y1491450D01*
G37*
G36*
G01X639840D02*
G02X639638Y1491248I-202J0D01*
G01X636818D01*
G02X636616Y1491451I1J203D01*
G01Y1492072D01*
G03X636566Y1492204I-200J0D01*
G02Y1495120I1661J1458D01*
G03X636616Y1495252I-150J132D01*
G01Y1497190D01*
G03X636566Y1497322I-200J0D01*
G02Y1500238I1661J1458D01*
G03X636616Y1500370I-150J132D01*
G01Y1500990D01*
G02X636818Y1501192I202J0D01*
G01X639638D01*
G02X639840Y1500989I-1J-203D01*
G01Y1500370D01*
G03X639890Y1500238I200J0D01*
G02Y1497322I-1661J-1458D01*
G03X639840Y1497190I150J-132D01*
G01Y1495252D01*
G03X639890Y1495120I200J0D01*
G02Y1492204I-1661J-1458D01*
G03X639840Y1492072I150J-132D01*
G01Y1491450D01*
G37*
G36*
G01X1139101Y1501192D02*
X1141921D01*
G02X1142124Y1500989I0J-203D01*
G01Y1500368D01*
G03X1142174Y1500236I200J0D01*
G02Y1497324I-1664J-1456D01*
G03X1142124Y1497192I150J-132D01*
G01Y1495250D01*
G03X1142174Y1495118I200J0D01*
G02Y1492206I-1664J-1456D01*
G03X1142124Y1492074I150J-132D01*
G01Y1491451D01*
G02X1141921Y1491248I-203J0D01*
G01X1139101D01*
G02X1138898Y1491451I0J203D01*
G01Y1492074D01*
G03X1138848Y1492206I-200J0D01*
G02Y1495118I1664J1456D01*
G03X1138898Y1495250I-150J132D01*
G01Y1497192D01*
G03X1138848Y1497324I-200J0D01*
G02Y1500236I1664J1456D01*
G03X1138898Y1500368I-150J132D01*
G01Y1500989D01*
G02X1139101Y1501192I203J0D01*
G37*
G36*
G01X1159446Y1491450D02*
G02X1159244Y1491248I-202J0D01*
G01X1156424D01*
G02X1156222Y1491451I1J203D01*
G01Y1492072D01*
G03X1156172Y1492204I-200J0D01*
G02Y1495120I1661J1458D01*
G03X1156222Y1495252I-150J132D01*
G01Y1497190D01*
G03X1156172Y1497322I-200J0D01*
G02Y1500238I1661J1458D01*
G03X1156222Y1500370I-150J132D01*
G01Y1500990D01*
G02X1156424Y1501192I202J0D01*
G01X1159244D01*
G02X1159446Y1500989I-1J-203D01*
G01Y1500370D01*
G03X1159496Y1500238I200J0D01*
G02Y1497322I-1661J-1458D01*
G03X1159446Y1497190I150J-132D01*
G01Y1495252D01*
G03X1159496Y1495120I200J0D01*
G02Y1492204I-1661J-1458D01*
G03X1159446Y1492072I150J-132D01*
G01Y1491450D01*
G37*
G36*
G01X1661808D02*
G02X1661606Y1491248I-202J0D01*
G01X1658786D01*
G02X1658584Y1491451I1J203D01*
G01Y1492072D01*
G03X1658534Y1492204I-200J0D01*
G02Y1495120I1661J1458D01*
G03X1658584Y1495252I-150J132D01*
G01Y1497190D01*
G03X1658534Y1497322I-200J0D01*
G02Y1500238I1661J1458D01*
G03X1658584Y1500370I-150J132D01*
G01Y1500990D01*
G02X1658786Y1501192I202J0D01*
G01X1661606D01*
G02X1661808Y1500989I-1J-203D01*
G01Y1500370D01*
G03X1661858Y1500238I200J0D01*
G02Y1497322I-1661J-1458D01*
G03X1661808Y1497190I150J-132D01*
G01Y1495252D01*
G03X1661858Y1495120I200J0D01*
G02Y1492204I-1661J-1458D01*
G03X1661808Y1492072I150J-132D01*
G01Y1491450D01*
G37*
G36*
G01X1676109Y1501192D02*
X1678929D01*
G02X1679132Y1500989I0J-203D01*
G01Y1500368D01*
G03X1679182Y1500236I200J0D01*
G02Y1497324I-1664J-1456D01*
G03X1679132Y1497192I150J-132D01*
G01Y1495250D01*
G03X1679182Y1495118I200J0D01*
G02Y1492206I-1664J-1456D01*
G03X1679132Y1492074I150J-132D01*
G01Y1491451D01*
G02X1678929Y1491248I-203J0D01*
G01X1676109D01*
G02X1675906Y1491451I0J203D01*
G01Y1492074D01*
G03X1675856Y1492206I-200J0D01*
G02Y1495118I1664J1456D01*
G03X1675906Y1495250I-150J132D01*
G01Y1497192D01*
G03X1675856Y1497324I-200J0D01*
G02Y1500236I1664J1456D01*
G03X1675906Y1500368I-150J132D01*
G01Y1500989D01*
G02X1676109Y1501192I203J0D01*
G37*
G36*
G01X108472Y1512216D02*
X111292D01*
G02X111494Y1512014I0J-202D01*
G01Y1511394D01*
G03X111544Y1511262I200J0D01*
G02Y1508346I-1661J-1458D01*
G03X111494Y1508214I150J-132D01*
G01Y1506275D01*
G03X111544Y1506143I200J0D01*
G02Y1503227I-1661J-1458D01*
G03X111494Y1503095I150J-132D01*
G01Y1502476D01*
G02X111292Y1502274I-202J0D01*
G01X108472D01*
G02X108270Y1502476I0J202D01*
G01Y1503095D01*
G03X108220Y1503227I-200J0D01*
G02Y1506143I1661J1458D01*
G03X108270Y1506275I-150J132D01*
G01Y1508214D01*
G03X108220Y1508346I-200J0D01*
G02Y1511262I1661J1458D01*
G03X108270Y1511394I-150J132D01*
G01Y1512014D01*
G02X108472Y1512216I202J0D01*
G37*
G36*
G01X316346D02*
X319166D01*
G02X319368Y1512014I0J-202D01*
G01Y1511394D01*
G03X319418Y1511262I200J0D01*
G02Y1508346I-1661J-1458D01*
G03X319368Y1508214I150J-132D01*
G01Y1506275D01*
G03X319418Y1506143I200J0D01*
G02Y1503227I-1661J-1458D01*
G03X319368Y1503095I150J-132D01*
G01Y1502476D01*
G02X319166Y1502274I-202J0D01*
G01X316346D01*
G02X316144Y1502476I0J202D01*
G01Y1503095D01*
G03X316094Y1503227I-200J0D01*
G02Y1506143I1661J1458D01*
G03X316144Y1506275I-150J132D01*
G01Y1508214D01*
G03X316094Y1508346I-200J0D01*
G02Y1511262I1661J1458D01*
G03X316144Y1511394I-150J132D01*
G01Y1512014D01*
G02X316346Y1512216I202J0D01*
G37*
G36*
G01X333668D02*
X336488D01*
G02X336690Y1512014I0J-202D01*
G01Y1511394D01*
G03X336740Y1511262I200J0D01*
G02Y1508346I-1661J-1458D01*
G03X336690Y1508214I150J-132D01*
G01Y1506275D01*
G03X336740Y1506143I200J0D01*
G02Y1503227I-1661J-1458D01*
G03X336690Y1503095I150J-132D01*
G01Y1502476D01*
G02X336488Y1502274I-202J0D01*
G01X333668D01*
G02X333466Y1502476I0J202D01*
G01Y1503095D01*
G03X333416Y1503227I-200J0D01*
G02Y1506143I1661J1458D01*
G03X333466Y1506275I-150J132D01*
G01Y1508214D01*
G03X333416Y1508346I-200J0D01*
G02Y1511262I1661J1458D01*
G03X333466Y1511394I-150J132D01*
G01Y1512014D01*
G02X333668Y1512216I202J0D01*
G37*
G36*
G01X1130440D02*
X1133260D01*
G02X1133462Y1512014I0J-202D01*
G01Y1511394D01*
G03X1133512Y1511262I200J0D01*
G02Y1508346I-1661J-1458D01*
G03X1133462Y1508214I150J-132D01*
G01Y1506275D01*
G03X1133512Y1506143I200J0D01*
G02Y1503227I-1661J-1458D01*
G03X1133462Y1503095I150J-132D01*
G01Y1502476D01*
G02X1133260Y1502274I-202J0D01*
G01X1130440D01*
G02X1130238Y1502476I0J202D01*
G01Y1503095D01*
G03X1130188Y1503227I-200J0D01*
G02Y1506143I1661J1458D01*
G03X1130238Y1506275I-150J132D01*
G01Y1508214D01*
G03X1130188Y1508346I-200J0D01*
G02Y1511262I1661J1458D01*
G03X1130238Y1511394I-150J132D01*
G01Y1512014D01*
G02X1130440Y1512216I202J0D01*
G37*
G36*
G01X1667448D02*
X1670268D01*
G02X1670470Y1512014I0J-202D01*
G01Y1511394D01*
G03X1670520Y1511262I200J0D01*
G02Y1508346I-1661J-1458D01*
G03X1670470Y1508214I150J-132D01*
G01Y1506275D01*
G03X1670520Y1506143I200J0D01*
G02Y1503227I-1661J-1458D01*
G03X1670470Y1503095I150J-132D01*
G01Y1502476D01*
G02X1670268Y1502274I-202J0D01*
G01X1667448D01*
G02X1667246Y1502476I0J202D01*
G01Y1503095D01*
G03X1667196Y1503227I-200J0D01*
G02Y1506143I1661J1458D01*
G03X1667246Y1506275I-150J132D01*
G01Y1508214D01*
G03X1667196Y1508346I-200J0D01*
G02Y1511262I1661J1458D01*
G03X1667246Y1511394I-150J132D01*
G01Y1512014D01*
G02X1667448Y1512216I202J0D01*
G37*
G36*
G01X628156Y1502274D02*
G02X627954Y1502476I0J202D01*
G01Y1503097D01*
G03X627904Y1503229I-200J0D01*
G02Y1506141I1664J1456D01*
G03X627954Y1506273I-150J132D01*
G01Y1508216D01*
G03X627904Y1508348I-200J0D01*
G02Y1511260I1664J1456D01*
G03X627954Y1511392I-150J132D01*
G01Y1512014D01*
G02X628157Y1512216I203J-1D01*
G01X630978D01*
G02X631180Y1512014I0J-202D01*
G01Y1511392D01*
G03X631230Y1511260I200J0D01*
G02Y1508348I-1664J-1456D01*
G03X631180Y1508216I150J-132D01*
G01Y1506273D01*
G03X631230Y1506141I200J0D01*
G02Y1503229I-1664J-1456D01*
G03X631180Y1503097I150J-132D01*
G01Y1502476D01*
G02X630977Y1502274I-203J1D01*
G01X628156D01*
G37*
G36*
G01X1147762D02*
G02X1147560Y1502476I0J202D01*
G01Y1503097D01*
G03X1147510Y1503229I-200J0D01*
G02Y1506141I1664J1456D01*
G03X1147560Y1506273I-150J132D01*
G01Y1508216D01*
G03X1147510Y1508348I-200J0D01*
G02Y1511260I1664J1456D01*
G03X1147560Y1511392I-150J132D01*
G01Y1512014D01*
G02X1147763Y1512216I203J-1D01*
G01X1150584D01*
G02X1150786Y1512014I0J-202D01*
G01Y1511392D01*
G03X1150836Y1511260I200J0D01*
G02Y1508348I-1664J-1456D01*
G03X1150786Y1508216I150J-132D01*
G01Y1506273D01*
G03X1150836Y1506141I200J0D01*
G02Y1503229I-1664J-1456D01*
G03X1150786Y1503097I150J-132D01*
G01Y1502476D01*
G02X1150583Y1502274I-203J1D01*
G01X1147762D01*
G37*
G36*
G01X1650124D02*
G02X1649922Y1502476I0J202D01*
G01Y1503097D01*
G03X1649872Y1503229I-200J0D01*
G02Y1506141I1664J1456D01*
G03X1649922Y1506273I-150J132D01*
G01Y1508216D01*
G03X1649872Y1508348I-200J0D01*
G02Y1511260I1664J1456D01*
G03X1649922Y1511392I-150J132D01*
G01Y1512014D01*
G02X1650125Y1512216I203J-1D01*
G01X1652946D01*
G02X1653148Y1512014I0J-202D01*
G01Y1511392D01*
G03X1653198Y1511260I200J0D01*
G02Y1508348I-1664J-1456D01*
G03X1653148Y1508216I150J-132D01*
G01Y1506273D01*
G03X1653198Y1506141I200J0D01*
G02Y1503229I-1664J-1456D01*
G03X1653148Y1503097I150J-132D01*
G01Y1502476D01*
G02X1652945Y1502274I-203J1D01*
G01X1650124D01*
G37*
G36*
G01X307684Y1516546D02*
X310504D01*
G02X310706Y1516344I0J-202D01*
G01Y1515724D01*
G03X310756Y1515592I200J0D01*
G02Y1512676I-1661J-1458D01*
G03X310706Y1512544I150J-132D01*
G01Y1510606D01*
G03X310756Y1510474I200J0D01*
G02Y1507558I-1661J-1458D01*
G03X310706Y1507426I150J-132D01*
G01Y1506806D01*
G02X310504Y1506604I-202J0D01*
G01X307684D01*
G02X307482Y1506806I0J202D01*
G01Y1507426D01*
G03X307432Y1507558I-200J0D01*
G02Y1510474I1661J1458D01*
G03X307482Y1510606I-150J132D01*
G01Y1512544D01*
G03X307432Y1512676I-200J0D01*
G02Y1515592I1661J1458D01*
G03X307482Y1515724I-150J132D01*
G01Y1516344D01*
G02X307684Y1516546I202J0D01*
G37*
G36*
G01X342330D02*
X345150D01*
G02X345352Y1516344I0J-202D01*
G01Y1515724D01*
G03X345402Y1515592I200J0D01*
G02Y1512676I-1661J-1458D01*
G03X345352Y1512544I150J-132D01*
G01Y1510606D01*
G03X345402Y1510474I200J0D01*
G02Y1507558I-1661J-1458D01*
G03X345352Y1507426I150J-132D01*
G01Y1506806D01*
G02X345150Y1506604I-202J0D01*
G01X342330D01*
G02X342128Y1506806I0J202D01*
G01Y1507426D01*
G03X342078Y1507558I-200J0D01*
G02Y1510474I1661J1458D01*
G03X342128Y1510606I-150J132D01*
G01Y1512544D01*
G03X342078Y1512676I-200J0D01*
G02Y1515592I1661J1458D01*
G03X342128Y1515724I-150J132D01*
G01Y1516344D01*
G02X342330Y1516546I202J0D01*
G37*
G36*
G01X636818D02*
X639638D01*
G02X639840Y1516344I0J-202D01*
G01Y1515724D01*
G03X639890Y1515592I200J0D01*
G02Y1512676I-1661J-1458D01*
G03X639840Y1512544I150J-132D01*
G01Y1510606D01*
G03X639890Y1510474I200J0D01*
G02Y1507558I-1661J-1458D01*
G03X639840Y1507426I150J-132D01*
G01Y1506806D01*
G02X639638Y1506604I-202J0D01*
G01X636818D01*
G02X636616Y1506806I0J202D01*
G01Y1507426D01*
G03X636566Y1507558I-200J0D01*
G02Y1510474I1661J1458D01*
G03X636616Y1510606I-150J132D01*
G01Y1512544D01*
G03X636566Y1512676I-200J0D01*
G02Y1515592I1661J1458D01*
G03X636616Y1515724I-150J132D01*
G01Y1516344D01*
G02X636818Y1516546I202J0D01*
G37*
G36*
G01X1156424D02*
X1159244D01*
G02X1159446Y1516344I0J-202D01*
G01Y1515724D01*
G03X1159496Y1515592I200J0D01*
G02Y1512676I-1661J-1458D01*
G03X1159446Y1512544I150J-132D01*
G01Y1510606D01*
G03X1159496Y1510474I200J0D01*
G02Y1507558I-1661J-1458D01*
G03X1159446Y1507426I150J-132D01*
G01Y1506806D01*
G02X1159244Y1506604I-202J0D01*
G01X1156424D01*
G02X1156222Y1506806I0J202D01*
G01Y1507426D01*
G03X1156172Y1507558I-200J0D01*
G02Y1510474I1661J1458D01*
G03X1156222Y1510606I-150J132D01*
G01Y1512544D01*
G03X1156172Y1512676I-200J0D01*
G02Y1515592I1661J1458D01*
G03X1156222Y1515724I-150J132D01*
G01Y1516344D01*
G02X1156424Y1516546I202J0D01*
G37*
G36*
G01X1658786D02*
X1661606D01*
G02X1661808Y1516344I0J-202D01*
G01Y1515724D01*
G03X1661858Y1515592I200J0D01*
G02Y1512676I-1661J-1458D01*
G03X1661808Y1512544I150J-132D01*
G01Y1510606D01*
G03X1661858Y1510474I200J0D01*
G02Y1507558I-1661J-1458D01*
G03X1661808Y1507426I150J-132D01*
G01Y1506806D01*
G02X1661606Y1506604I-202J0D01*
G01X1658786D01*
G02X1658584Y1506806I0J202D01*
G01Y1507426D01*
G03X1658534Y1507558I-200J0D01*
G02Y1510474I1661J1458D01*
G03X1658584Y1510606I-150J132D01*
G01Y1512544D01*
G03X1658534Y1512676I-200J0D01*
G02Y1515592I1661J1458D01*
G03X1658584Y1515724I-150J132D01*
G01Y1516344D01*
G02X1658786Y1516546I202J0D01*
G37*
G36*
G01X117132Y1506604D02*
G02X116930Y1506806I0J202D01*
G01Y1507428D01*
G03X116880Y1507560I-200J0D01*
G02Y1510472I1664J1456D01*
G03X116930Y1510604I-150J132D01*
G01Y1512546D01*
G03X116880Y1512678I-200J0D01*
G02Y1515590I1664J1456D01*
G03X116930Y1515722I-150J132D01*
G01Y1516344D01*
G02X117133Y1516546I203J-1D01*
G01X119954D01*
G02X120156Y1516344I0J-202D01*
G01Y1515722D01*
G03X120206Y1515590I200J0D01*
G02Y1512678I-1664J-1456D01*
G03X120156Y1512546I150J-132D01*
G01Y1510604D01*
G03X120206Y1510472I200J0D01*
G02Y1507560I-1664J-1456D01*
G03X120156Y1507428I150J-132D01*
G01Y1506806D01*
G02X119953Y1506604I-203J1D01*
G01X117132D01*
G37*
G36*
G01X325006D02*
G02X324804Y1506806I0J202D01*
G01Y1507428D01*
G03X324754Y1507560I-200J0D01*
G02Y1510472I1664J1456D01*
G03X324804Y1510604I-150J132D01*
G01Y1512546D01*
G03X324754Y1512678I-200J0D01*
G02Y1515590I1664J1456D01*
G03X324804Y1515722I-150J132D01*
G01Y1516344D01*
G02X325007Y1516546I203J-1D01*
G01X327828D01*
G02X328030Y1516344I0J-202D01*
G01Y1515722D01*
G03X328080Y1515590I200J0D01*
G02Y1512678I-1664J-1456D01*
G03X328030Y1512546I150J-132D01*
G01Y1510604D01*
G03X328080Y1510472I200J0D01*
G02Y1507560I-1664J-1456D01*
G03X328030Y1507428I150J-132D01*
G01Y1506806D01*
G02X327827Y1506604I-203J1D01*
G01X325006D01*
G37*
G36*
G01X1139100D02*
G02X1138898Y1506806I0J202D01*
G01Y1507428D01*
G03X1138848Y1507560I-200J0D01*
G02Y1510472I1664J1456D01*
G03X1138898Y1510604I-150J132D01*
G01Y1512546D01*
G03X1138848Y1512678I-200J0D01*
G02Y1515590I1664J1456D01*
G03X1138898Y1515722I-150J132D01*
G01Y1516344D01*
G02X1139101Y1516546I203J-1D01*
G01X1141922D01*
G02X1142124Y1516344I0J-202D01*
G01Y1515722D01*
G03X1142174Y1515590I200J0D01*
G02Y1512678I-1664J-1456D01*
G03X1142124Y1512546I150J-132D01*
G01Y1510604D01*
G03X1142174Y1510472I200J0D01*
G02Y1507560I-1664J-1456D01*
G03X1142124Y1507428I150J-132D01*
G01Y1506806D01*
G02X1141921Y1506604I-203J1D01*
G01X1139100D01*
G37*
G36*
G01X1676108D02*
G02X1675906Y1506806I0J202D01*
G01Y1507428D01*
G03X1675856Y1507560I-200J0D01*
G02Y1510472I1664J1456D01*
G03X1675906Y1510604I-150J132D01*
G01Y1512546D01*
G03X1675856Y1512678I-200J0D01*
G02Y1515590I1664J1456D01*
G03X1675906Y1515722I-150J132D01*
G01Y1516344D01*
G02X1676109Y1516546I203J-1D01*
G01X1678930D01*
G02X1679132Y1516344I0J-202D01*
G01Y1515722D01*
G03X1679182Y1515590I200J0D01*
G02Y1512678I-1664J-1456D01*
G03X1679132Y1512546I150J-132D01*
G01Y1510604D01*
G03X1679182Y1510472I200J0D01*
G02Y1507560I-1664J-1456D01*
G03X1679132Y1507428I150J-132D01*
G01Y1506806D01*
G02X1678929Y1506604I-203J1D01*
G01X1676108D01*
G37*
G36*
G01X454929Y1568516D02*
X457749D01*
G02X457952Y1568313I0J-203D01*
G01Y1567691D01*
G03X458002Y1567559I200J0D01*
G02Y1564647I-1664J-1456D01*
G03X457952Y1564515I150J-132D01*
G01Y1562573D01*
G03X458002Y1562441I200J0D01*
G02Y1559529I-1664J-1456D01*
G03X457952Y1559397I150J-132D01*
G01Y1558775D01*
G02X457749Y1558572I-203J0D01*
G01X454929D01*
G02X454726Y1558775I0J203D01*
G01Y1559397D01*
G03X454676Y1559529I-200J0D01*
G02Y1562441I1664J1456D01*
G03X454726Y1562573I-150J132D01*
G01Y1564515D01*
G03X454676Y1564647I-200J0D01*
G02Y1567559I1664J1456D01*
G03X454726Y1567691I-150J132D01*
G01Y1568313D01*
G02X454929Y1568516I203J0D01*
G37*
G36*
G01X475274Y1558774D02*
G02X475072Y1558572I-202J0D01*
G01X472252D01*
G02X472050Y1558775I1J203D01*
G01Y1559395D01*
G03X472000Y1559527I-200J0D01*
G02Y1562443I1661J1458D01*
G03X472050Y1562575I-150J132D01*
G01Y1564513D01*
G03X472000Y1564645I-200J0D01*
G02Y1567561I1661J1458D01*
G03X472050Y1567693I-150J132D01*
G01Y1568314D01*
G02X472252Y1568516I202J0D01*
G01X475072D01*
G02X475274Y1568313I-1J-203D01*
G01Y1567693D01*
G03X475324Y1567561I200J0D01*
G02Y1564645I-1661J-1458D01*
G03X475274Y1564513I150J-132D01*
G01Y1562575D01*
G03X475324Y1562443I200J0D01*
G02Y1559527I-1661J-1458D01*
G03X475274Y1559395I150J-132D01*
G01Y1558774D01*
G37*
G36*
G01X489575Y1568516D02*
X492395D01*
G02X492598Y1568313I0J-203D01*
G01Y1567691D01*
G03X492648Y1567559I200J0D01*
G02Y1564647I-1664J-1456D01*
G03X492598Y1564515I150J-132D01*
G01Y1562573D01*
G03X492648Y1562441I200J0D01*
G02Y1559529I-1664J-1456D01*
G03X492598Y1559397I150J-132D01*
G01Y1558775D01*
G02X492395Y1558572I-203J0D01*
G01X489575D01*
G02X489372Y1558775I0J203D01*
G01Y1559397D01*
G03X489322Y1559529I-200J0D01*
G02Y1562441I1664J1456D01*
G03X489372Y1562573I-150J132D01*
G01Y1564515D01*
G03X489322Y1564647I-200J0D01*
G02Y1567559I1664J1456D01*
G03X489372Y1567691I-150J132D01*
G01Y1568313D01*
G02X489575Y1568516I203J0D01*
G37*
G36*
G01X506897D02*
X509717D01*
G02X509920Y1568313I0J-203D01*
G01Y1567691D01*
G03X509970Y1567559I200J0D01*
G02Y1564647I-1664J-1456D01*
G03X509920Y1564515I150J-132D01*
G01Y1562573D01*
G03X509970Y1562441I200J0D01*
G02Y1559529I-1664J-1456D01*
G03X509920Y1559397I150J-132D01*
G01Y1558775D01*
G02X509717Y1558572I-203J0D01*
G01X506897D01*
G02X506694Y1558775I0J203D01*
G01Y1559397D01*
G03X506644Y1559529I-200J0D01*
G02Y1562441I1664J1456D01*
G03X506694Y1562573I-150J132D01*
G01Y1564515D01*
G03X506644Y1564647I-200J0D01*
G02Y1567559I1664J1456D01*
G03X506694Y1567691I-150J132D01*
G01Y1568313D01*
G02X506897Y1568516I203J0D01*
G37*
G36*
G01X1497242Y1558774D02*
G02X1497040Y1558572I-202J0D01*
G01X1494220D01*
G02X1494018Y1558775I1J203D01*
G01Y1559395D01*
G03X1493968Y1559527I-200J0D01*
G02Y1562443I1661J1458D01*
G03X1494018Y1562575I-150J132D01*
G01Y1564513D01*
G03X1493968Y1564645I-200J0D01*
G02Y1567561I1661J1458D01*
G03X1494018Y1567693I-150J132D01*
G01Y1568314D01*
G02X1494220Y1568516I202J0D01*
G01X1497040D01*
G02X1497242Y1568313I-1J-203D01*
G01Y1567693D01*
G03X1497292Y1567561I200J0D01*
G02Y1564645I-1661J-1458D01*
G03X1497242Y1564513I150J-132D01*
G01Y1562575D01*
G03X1497292Y1562443I200J0D01*
G02Y1559527I-1661J-1458D01*
G03X1497242Y1559395I150J-132D01*
G01Y1558774D01*
G37*
G36*
G01X1511543Y1568516D02*
X1514363D01*
G02X1514566Y1568313I0J-203D01*
G01Y1567691D01*
G03X1514616Y1567559I200J0D01*
G02Y1564647I-1664J-1456D01*
G03X1514566Y1564515I150J-132D01*
G01Y1562573D01*
G03X1514616Y1562441I200J0D01*
G02Y1559529I-1664J-1456D01*
G03X1514566Y1559397I150J-132D01*
G01Y1558775D01*
G02X1514363Y1558572I-203J0D01*
G01X1511543D01*
G02X1511340Y1558775I0J203D01*
G01Y1559397D01*
G03X1511290Y1559529I-200J0D01*
G02Y1562441I1664J1456D01*
G03X1511340Y1562573I-150J132D01*
G01Y1564515D01*
G03X1511290Y1564647I-200J0D01*
G02Y1567559I1664J1456D01*
G03X1511340Y1567691I-150J132D01*
G01Y1568313D01*
G02X1511543Y1568516I203J0D01*
G37*
G36*
G01X1528865D02*
X1531685D01*
G02X1531888Y1568313I0J-203D01*
G01Y1567691D01*
G03X1531938Y1567559I200J0D01*
G02Y1564647I-1664J-1456D01*
G03X1531888Y1564515I150J-132D01*
G01Y1562573D01*
G03X1531938Y1562441I200J0D01*
G02Y1559529I-1664J-1456D01*
G03X1531888Y1559397I150J-132D01*
G01Y1558775D01*
G02X1531685Y1558572I-203J0D01*
G01X1528865D01*
G02X1528662Y1558775I0J203D01*
G01Y1559397D01*
G03X1528612Y1559529I-200J0D01*
G02Y1562441I1664J1456D01*
G03X1528662Y1562573I-150J132D01*
G01Y1564515D01*
G03X1528612Y1564647I-200J0D01*
G02Y1567559I1664J1456D01*
G03X1528662Y1567691I-150J132D01*
G01Y1568313D01*
G02X1528865Y1568516I203J0D01*
G37*
G36*
G01X463590Y1572846D02*
X466410D01*
G02X466612Y1572644I0J-202D01*
G01Y1572024D01*
G03X466662Y1571892I200J0D01*
G02Y1568976I-1661J-1458D01*
G03X466612Y1568844I150J-132D01*
G01Y1566905D01*
G03X466662Y1566773I200J0D01*
G02Y1563857I-1661J-1458D01*
G03X466612Y1563725I150J-132D01*
G01Y1563106D01*
G02X466410Y1562904I-202J0D01*
G01X463590D01*
G02X463388Y1563106I0J202D01*
G01Y1563725D01*
G03X463338Y1563857I-200J0D01*
G02Y1566773I1661J1458D01*
G03X463388Y1566905I-150J132D01*
G01Y1568844D01*
G03X463338Y1568976I-200J0D01*
G02Y1571892I1661J1458D01*
G03X463388Y1572024I-150J132D01*
G01Y1572644D01*
G02X463590Y1572846I202J0D01*
G37*
G36*
G01X498236D02*
X501056D01*
G02X501258Y1572644I0J-202D01*
G01Y1572024D01*
G03X501308Y1571892I200J0D01*
G02Y1568976I-1661J-1458D01*
G03X501258Y1568844I150J-132D01*
G01Y1566905D01*
G03X501308Y1566773I200J0D01*
G02Y1563857I-1661J-1458D01*
G03X501258Y1563725I150J-132D01*
G01Y1563106D01*
G02X501056Y1562904I-202J0D01*
G01X498236D01*
G02X498034Y1563106I0J202D01*
G01Y1563725D01*
G03X497984Y1563857I-200J0D01*
G02Y1566773I1661J1458D01*
G03X498034Y1566905I-150J132D01*
G01Y1568844D01*
G03X497984Y1568976I-200J0D01*
G02Y1571892I1661J1458D01*
G03X498034Y1572024I-150J132D01*
G01Y1572644D01*
G02X498236Y1572846I202J0D01*
G37*
G36*
G01X1485558D02*
X1488378D01*
G02X1488580Y1572644I0J-202D01*
G01Y1572024D01*
G03X1488630Y1571892I200J0D01*
G02Y1568976I-1661J-1458D01*
G03X1488580Y1568844I150J-132D01*
G01Y1566905D01*
G03X1488630Y1566773I200J0D01*
G02Y1563857I-1661J-1458D01*
G03X1488580Y1563725I150J-132D01*
G01Y1563106D01*
G02X1488378Y1562904I-202J0D01*
G01X1485558D01*
G02X1485356Y1563106I0J202D01*
G01Y1563725D01*
G03X1485306Y1563857I-200J0D01*
G02Y1566773I1661J1458D01*
G03X1485356Y1566905I-150J132D01*
G01Y1568844D01*
G03X1485306Y1568976I-200J0D01*
G02Y1571892I1661J1458D01*
G03X1485356Y1572024I-150J132D01*
G01Y1572644D01*
G02X1485558Y1572846I202J0D01*
G37*
G36*
G01X1520204D02*
X1523024D01*
G02X1523226Y1572644I0J-202D01*
G01Y1572024D01*
G03X1523276Y1571892I200J0D01*
G02Y1568976I-1661J-1458D01*
G03X1523226Y1568844I150J-132D01*
G01Y1566905D01*
G03X1523276Y1566773I200J0D01*
G02Y1563857I-1661J-1458D01*
G03X1523226Y1563725I150J-132D01*
G01Y1563106D01*
G02X1523024Y1562904I-202J0D01*
G01X1520204D01*
G02X1520002Y1563106I0J202D01*
G01Y1563725D01*
G03X1519952Y1563857I-200J0D01*
G02Y1566773I1661J1458D01*
G03X1520002Y1566905I-150J132D01*
G01Y1568844D01*
G03X1519952Y1568976I-200J0D01*
G02Y1571892I1661J1458D01*
G03X1520002Y1572024I-150J132D01*
G01Y1572644D01*
G02X1520204Y1572846I202J0D01*
G37*
G36*
G01X480912Y1562904D02*
G02X480710Y1563106I0J202D01*
G01Y1563727D01*
G03X480660Y1563859I-200J0D01*
G02Y1566771I1664J1456D01*
G03X480710Y1566903I-150J132D01*
G01Y1568846D01*
G03X480660Y1568978I-200J0D01*
G02Y1571890I1664J1456D01*
G03X480710Y1572022I-150J132D01*
G01Y1572644D01*
G02X480913Y1572846I203J-1D01*
G01X483734D01*
G02X483936Y1572644I0J-202D01*
G01Y1572022D01*
G03X483986Y1571890I200J0D01*
G02Y1568978I-1664J-1456D01*
G03X483936Y1568846I150J-132D01*
G01Y1566903D01*
G03X483986Y1566771I200J0D01*
G02Y1563859I-1664J-1456D01*
G03X483936Y1563727I150J-132D01*
G01Y1563106D01*
G02X483733Y1562904I-203J1D01*
G01X480912D01*
G37*
G36*
G01X1502880D02*
G02X1502678Y1563106I0J202D01*
G01Y1563727D01*
G03X1502628Y1563859I-200J0D01*
G02Y1566771I1664J1456D01*
G03X1502678Y1566903I-150J132D01*
G01Y1568846D01*
G03X1502628Y1568978I-200J0D01*
G02Y1571890I1664J1456D01*
G03X1502678Y1572022I-150J132D01*
G01Y1572644D01*
G02X1502881Y1572846I203J-1D01*
G01X1505702D01*
G02X1505904Y1572644I0J-202D01*
G01Y1572022D01*
G03X1505954Y1571890I200J0D01*
G02Y1568978I-1664J-1456D01*
G03X1505904Y1568846I150J-132D01*
G01Y1566903D01*
G03X1505954Y1566771I200J0D01*
G02Y1563859I-1664J-1456D01*
G03X1505904Y1563727I150J-132D01*
G01Y1563106D01*
G02X1505701Y1562904I-203J1D01*
G01X1502880D01*
G37*
G36*
G01X1537526D02*
G02X1537324Y1563106I0J202D01*
G01Y1563727D01*
G03X1537274Y1563859I-200J0D01*
G02Y1566771I1664J1456D01*
G03X1537324Y1566903I-150J132D01*
G01Y1568846D01*
G03X1537274Y1568978I-200J0D01*
G02Y1571890I1664J1456D01*
G03X1537324Y1572022I-150J132D01*
G01Y1572644D01*
G02X1537527Y1572846I203J-1D01*
G01X1540348D01*
G02X1540550Y1572644I0J-202D01*
G01Y1572022D01*
G03X1540600Y1571890I200J0D01*
G02Y1568978I-1664J-1456D01*
G03X1540550Y1568846I150J-132D01*
G01Y1566903D01*
G03X1540600Y1566771I200J0D01*
G02Y1563859I-1664J-1456D01*
G03X1540550Y1563727I150J-132D01*
G01Y1563106D01*
G02X1540347Y1562904I-203J1D01*
G01X1537526D01*
G37*
G36*
G01X454929Y1583870D02*
X457749D01*
G02X457952Y1583667I0J-203D01*
G01Y1583045D01*
G03X458002Y1582913I200J0D01*
G02Y1580001I-1664J-1456D01*
G03X457952Y1579869I150J-132D01*
G01Y1577927D01*
G03X458002Y1577795I200J0D01*
G02Y1574883I-1664J-1456D01*
G03X457952Y1574751I150J-132D01*
G01Y1574129D01*
G02X457749Y1573926I-203J0D01*
G01X454929D01*
G02X454726Y1574129I0J203D01*
G01Y1574751D01*
G03X454676Y1574883I-200J0D01*
G02Y1577795I1664J1456D01*
G03X454726Y1577927I-150J132D01*
G01Y1579869D01*
G03X454676Y1580001I-200J0D01*
G02Y1582913I1664J1456D01*
G03X454726Y1583045I-150J132D01*
G01Y1583667D01*
G02X454929Y1583870I203J0D01*
G37*
G36*
G01X475274Y1574128D02*
G02X475072Y1573926I-202J0D01*
G01X472252D01*
G02X472050Y1574129I1J203D01*
G01Y1574749D01*
G03X472000Y1574881I-200J0D01*
G02Y1577797I1661J1458D01*
G03X472050Y1577929I-150J132D01*
G01Y1579867D01*
G03X472000Y1579999I-200J0D01*
G02Y1582915I1661J1458D01*
G03X472050Y1583047I-150J132D01*
G01Y1583668D01*
G02X472252Y1583870I202J0D01*
G01X475072D01*
G02X475274Y1583667I-1J-203D01*
G01Y1583047D01*
G03X475324Y1582915I200J0D01*
G02Y1579999I-1661J-1458D01*
G03X475274Y1579867I150J-132D01*
G01Y1577929D01*
G03X475324Y1577797I200J0D01*
G02Y1574881I-1661J-1458D01*
G03X475274Y1574749I150J-132D01*
G01Y1574128D01*
G37*
G36*
G01X489575Y1583870D02*
X492395D01*
G02X492598Y1583667I0J-203D01*
G01Y1583045D01*
G03X492648Y1582913I200J0D01*
G02Y1580001I-1664J-1456D01*
G03X492598Y1579869I150J-132D01*
G01Y1577927D01*
G03X492648Y1577795I200J0D01*
G02Y1574883I-1664J-1456D01*
G03X492598Y1574751I150J-132D01*
G01Y1574129D01*
G02X492395Y1573926I-203J0D01*
G01X489575D01*
G02X489372Y1574129I0J203D01*
G01Y1574751D01*
G03X489322Y1574883I-200J0D01*
G02Y1577795I1664J1456D01*
G03X489372Y1577927I-150J132D01*
G01Y1579869D01*
G03X489322Y1580001I-200J0D01*
G02Y1582913I1664J1456D01*
G03X489372Y1583045I-150J132D01*
G01Y1583667D01*
G02X489575Y1583870I203J0D01*
G37*
G36*
G01X506897D02*
X509717D01*
G02X509920Y1583667I0J-203D01*
G01Y1583045D01*
G03X509970Y1582913I200J0D01*
G02Y1580001I-1664J-1456D01*
G03X509920Y1579869I150J-132D01*
G01Y1577927D01*
G03X509970Y1577795I200J0D01*
G02Y1574883I-1664J-1456D01*
G03X509920Y1574751I150J-132D01*
G01Y1574129D01*
G02X509717Y1573926I-203J0D01*
G01X506897D01*
G02X506694Y1574129I0J203D01*
G01Y1574751D01*
G03X506644Y1574883I-200J0D01*
G02Y1577795I1664J1456D01*
G03X506694Y1577927I-150J132D01*
G01Y1579869D01*
G03X506644Y1580001I-200J0D01*
G02Y1582913I1664J1456D01*
G03X506694Y1583045I-150J132D01*
G01Y1583667D01*
G02X506897Y1583870I203J0D01*
G37*
G36*
G01X1497242Y1574128D02*
G02X1497040Y1573926I-202J0D01*
G01X1494220D01*
G02X1494018Y1574129I1J203D01*
G01Y1574749D01*
G03X1493968Y1574881I-200J0D01*
G02Y1577797I1661J1458D01*
G03X1494018Y1577929I-150J132D01*
G01Y1579867D01*
G03X1493968Y1579999I-200J0D01*
G02Y1582915I1661J1458D01*
G03X1494018Y1583047I-150J132D01*
G01Y1583668D01*
G02X1494220Y1583870I202J0D01*
G01X1497040D01*
G02X1497242Y1583667I-1J-203D01*
G01Y1583047D01*
G03X1497292Y1582915I200J0D01*
G02Y1579999I-1661J-1458D01*
G03X1497242Y1579867I150J-132D01*
G01Y1577929D01*
G03X1497292Y1577797I200J0D01*
G02Y1574881I-1661J-1458D01*
G03X1497242Y1574749I150J-132D01*
G01Y1574128D01*
G37*
G36*
G01X1511543Y1583870D02*
X1514363D01*
G02X1514566Y1583667I0J-203D01*
G01Y1583045D01*
G03X1514616Y1582913I200J0D01*
G02Y1580001I-1664J-1456D01*
G03X1514566Y1579869I150J-132D01*
G01Y1577927D01*
G03X1514616Y1577795I200J0D01*
G02Y1574883I-1664J-1456D01*
G03X1514566Y1574751I150J-132D01*
G01Y1574129D01*
G02X1514363Y1573926I-203J0D01*
G01X1511543D01*
G02X1511340Y1574129I0J203D01*
G01Y1574751D01*
G03X1511290Y1574883I-200J0D01*
G02Y1577795I1664J1456D01*
G03X1511340Y1577927I-150J132D01*
G01Y1579869D01*
G03X1511290Y1580001I-200J0D01*
G02Y1582913I1664J1456D01*
G03X1511340Y1583045I-150J132D01*
G01Y1583667D01*
G02X1511543Y1583870I203J0D01*
G37*
G36*
G01X1528865D02*
X1531685D01*
G02X1531888Y1583667I0J-203D01*
G01Y1583045D01*
G03X1531938Y1582913I200J0D01*
G02Y1580001I-1664J-1456D01*
G03X1531888Y1579869I150J-132D01*
G01Y1577927D01*
G03X1531938Y1577795I200J0D01*
G02Y1574883I-1664J-1456D01*
G03X1531888Y1574751I150J-132D01*
G01Y1574129D01*
G02X1531685Y1573926I-203J0D01*
G01X1528865D01*
G02X1528662Y1574129I0J203D01*
G01Y1574751D01*
G03X1528612Y1574883I-200J0D01*
G02Y1577795I1664J1456D01*
G03X1528662Y1577927I-150J132D01*
G01Y1579869D01*
G03X1528612Y1580001I-200J0D01*
G02Y1582913I1664J1456D01*
G03X1528662Y1583045I-150J132D01*
G01Y1583667D01*
G02X1528865Y1583870I203J0D01*
G37*
G36*
G01X463590Y1588200D02*
X466410D01*
G02X466612Y1587998I0J-202D01*
G01Y1587378D01*
G03X466662Y1587246I200J0D01*
G02Y1584330I-1661J-1458D01*
G03X466612Y1584198I150J-132D01*
G01Y1582260D01*
G03X466662Y1582128I200J0D01*
G02Y1579212I-1661J-1458D01*
G03X466612Y1579080I150J-132D01*
G01Y1578460D01*
G02X466410Y1578258I-202J0D01*
G01X463590D01*
G02X463388Y1578460I0J202D01*
G01Y1579080D01*
G03X463338Y1579212I-200J0D01*
G02Y1582128I1661J1458D01*
G03X463388Y1582260I-150J132D01*
G01Y1584198D01*
G03X463338Y1584330I-200J0D01*
G02Y1587246I1661J1458D01*
G03X463388Y1587378I-150J132D01*
G01Y1587998D01*
G02X463590Y1588200I202J0D01*
G37*
G36*
G01X498236D02*
X501056D01*
G02X501258Y1587998I0J-202D01*
G01Y1587378D01*
G03X501308Y1587246I200J0D01*
G02Y1584330I-1661J-1458D01*
G03X501258Y1584198I150J-132D01*
G01Y1582260D01*
G03X501308Y1582128I200J0D01*
G02Y1579212I-1661J-1458D01*
G03X501258Y1579080I150J-132D01*
G01Y1578460D01*
G02X501056Y1578258I-202J0D01*
G01X498236D01*
G02X498034Y1578460I0J202D01*
G01Y1579080D01*
G03X497984Y1579212I-200J0D01*
G02Y1582128I1661J1458D01*
G03X498034Y1582260I-150J132D01*
G01Y1584198D01*
G03X497984Y1584330I-200J0D01*
G02Y1587246I1661J1458D01*
G03X498034Y1587378I-150J132D01*
G01Y1587998D01*
G02X498236Y1588200I202J0D01*
G37*
G36*
G01X1485558D02*
X1488378D01*
G02X1488580Y1587998I0J-202D01*
G01Y1587378D01*
G03X1488630Y1587246I200J0D01*
G02Y1584330I-1661J-1458D01*
G03X1488580Y1584198I150J-132D01*
G01Y1582260D01*
G03X1488630Y1582128I200J0D01*
G02Y1579212I-1661J-1458D01*
G03X1488580Y1579080I150J-132D01*
G01Y1578460D01*
G02X1488378Y1578258I-202J0D01*
G01X1485558D01*
G02X1485356Y1578460I0J202D01*
G01Y1579080D01*
G03X1485306Y1579212I-200J0D01*
G02Y1582128I1661J1458D01*
G03X1485356Y1582260I-150J132D01*
G01Y1584198D01*
G03X1485306Y1584330I-200J0D01*
G02Y1587246I1661J1458D01*
G03X1485356Y1587378I-150J132D01*
G01Y1587998D01*
G02X1485558Y1588200I202J0D01*
G37*
G36*
G01X1520204D02*
X1523024D01*
G02X1523226Y1587998I0J-202D01*
G01Y1587378D01*
G03X1523276Y1587246I200J0D01*
G02Y1584330I-1661J-1458D01*
G03X1523226Y1584198I150J-132D01*
G01Y1582260D01*
G03X1523276Y1582128I200J0D01*
G02Y1579212I-1661J-1458D01*
G03X1523226Y1579080I150J-132D01*
G01Y1578460D01*
G02X1523024Y1578258I-202J0D01*
G01X1520204D01*
G02X1520002Y1578460I0J202D01*
G01Y1579080D01*
G03X1519952Y1579212I-200J0D01*
G02Y1582128I1661J1458D01*
G03X1520002Y1582260I-150J132D01*
G01Y1584198D01*
G03X1519952Y1584330I-200J0D01*
G02Y1587246I1661J1458D01*
G03X1520002Y1587378I-150J132D01*
G01Y1587998D01*
G02X1520204Y1588200I202J0D01*
G37*
G36*
G01X480912Y1578258D02*
G02X480710Y1578460I0J202D01*
G01Y1579082D01*
G03X480660Y1579214I-200J0D01*
G02Y1582126I1664J1456D01*
G03X480710Y1582258I-150J132D01*
G01Y1584200D01*
G03X480660Y1584332I-200J0D01*
G02Y1587244I1664J1456D01*
G03X480710Y1587376I-150J132D01*
G01Y1587998D01*
G02X480913Y1588200I203J-1D01*
G01X483734D01*
G02X483936Y1587998I0J-202D01*
G01Y1587376D01*
G03X483986Y1587244I200J0D01*
G02Y1584332I-1664J-1456D01*
G03X483936Y1584200I150J-132D01*
G01Y1582258D01*
G03X483986Y1582126I200J0D01*
G02Y1579214I-1664J-1456D01*
G03X483936Y1579082I150J-132D01*
G01Y1578460D01*
G02X483733Y1578258I-203J1D01*
G01X480912D01*
G37*
G36*
G01X1502880D02*
G02X1502678Y1578460I0J202D01*
G01Y1579082D01*
G03X1502628Y1579214I-200J0D01*
G02Y1582126I1664J1456D01*
G03X1502678Y1582258I-150J132D01*
G01Y1584200D01*
G03X1502628Y1584332I-200J0D01*
G02Y1587244I1664J1456D01*
G03X1502678Y1587376I-150J132D01*
G01Y1587998D01*
G02X1502881Y1588200I203J-1D01*
G01X1505702D01*
G02X1505904Y1587998I0J-202D01*
G01Y1587376D01*
G03X1505954Y1587244I200J0D01*
G02Y1584332I-1664J-1456D01*
G03X1505904Y1584200I150J-132D01*
G01Y1582258D01*
G03X1505954Y1582126I200J0D01*
G02Y1579214I-1664J-1456D01*
G03X1505904Y1579082I150J-132D01*
G01Y1578460D01*
G02X1505701Y1578258I-203J1D01*
G01X1502880D01*
G37*
G36*
G01X1537526D02*
G02X1537324Y1578460I0J202D01*
G01Y1579082D01*
G03X1537274Y1579214I-200J0D01*
G02Y1582126I1664J1456D01*
G03X1537324Y1582258I-150J132D01*
G01Y1584200D01*
G03X1537274Y1584332I-200J0D01*
G02Y1587244I1664J1456D01*
G03X1537324Y1587376I-150J132D01*
G01Y1587998D01*
G02X1537527Y1588200I203J-1D01*
G01X1540348D01*
G02X1540550Y1587998I0J-202D01*
G01Y1587376D01*
G03X1540600Y1587244I200J0D01*
G02Y1584332I-1664J-1456D01*
G03X1540550Y1584200I150J-132D01*
G01Y1582258D01*
G03X1540600Y1582126I200J0D01*
G02Y1579214I-1664J-1456D01*
G03X1540550Y1579082I150J-132D01*
G01Y1578460D01*
G02X1540347Y1578258I-203J1D01*
G01X1537526D01*
G37*
G36*
G01X454929Y1599224D02*
X457749D01*
G02X457952Y1599021I0J-203D01*
G01Y1598399D01*
G03X458002Y1598267I200J0D01*
G02Y1595355I-1664J-1456D01*
G03X457952Y1595223I150J-132D01*
G01Y1593281D01*
G03X458002Y1593149I200J0D01*
G02Y1590237I-1664J-1456D01*
G03X457952Y1590105I150J-132D01*
G01Y1589483D01*
G02X457749Y1589280I-203J0D01*
G01X454929D01*
G02X454726Y1589483I0J203D01*
G01Y1590105D01*
G03X454676Y1590237I-200J0D01*
G02Y1593149I1664J1456D01*
G03X454726Y1593281I-150J132D01*
G01Y1595223D01*
G03X454676Y1595355I-200J0D01*
G02Y1598267I1664J1456D01*
G03X454726Y1598399I-150J132D01*
G01Y1599021D01*
G02X454929Y1599224I203J0D01*
G37*
G36*
G01X475274Y1589482D02*
G02X475072Y1589280I-202J0D01*
G01X472252D01*
G02X472050Y1589483I1J203D01*
G01Y1590103D01*
G03X472000Y1590235I-200J0D01*
G02Y1593151I1661J1458D01*
G03X472050Y1593283I-150J132D01*
G01Y1595221D01*
G03X472000Y1595353I-200J0D01*
G02Y1598269I1661J1458D01*
G03X472050Y1598401I-150J132D01*
G01Y1599022D01*
G02X472252Y1599224I202J0D01*
G01X475072D01*
G02X475274Y1599021I-1J-203D01*
G01Y1598401D01*
G03X475324Y1598269I200J0D01*
G02Y1595353I-1661J-1458D01*
G03X475274Y1595221I150J-132D01*
G01Y1593283D01*
G03X475324Y1593151I200J0D01*
G02Y1590235I-1661J-1458D01*
G03X475274Y1590103I150J-132D01*
G01Y1589482D01*
G37*
G36*
G01X489575Y1599224D02*
X492395D01*
G02X492598Y1599021I0J-203D01*
G01Y1598399D01*
G03X492648Y1598267I200J0D01*
G02Y1595355I-1664J-1456D01*
G03X492598Y1595223I150J-132D01*
G01Y1593281D01*
G03X492648Y1593149I200J0D01*
G02Y1590237I-1664J-1456D01*
G03X492598Y1590105I150J-132D01*
G01Y1589483D01*
G02X492395Y1589280I-203J0D01*
G01X489575D01*
G02X489372Y1589483I0J203D01*
G01Y1590105D01*
G03X489322Y1590237I-200J0D01*
G02Y1593149I1664J1456D01*
G03X489372Y1593281I-150J132D01*
G01Y1595223D01*
G03X489322Y1595355I-200J0D01*
G02Y1598267I1664J1456D01*
G03X489372Y1598399I-150J132D01*
G01Y1599021D01*
G02X489575Y1599224I203J0D01*
G37*
G36*
G01X506897D02*
X509717D01*
G02X509920Y1599021I0J-203D01*
G01Y1598399D01*
G03X509970Y1598267I200J0D01*
G02Y1595355I-1664J-1456D01*
G03X509920Y1595223I150J-132D01*
G01Y1593281D01*
G03X509970Y1593149I200J0D01*
G02Y1590237I-1664J-1456D01*
G03X509920Y1590105I150J-132D01*
G01Y1589483D01*
G02X509717Y1589280I-203J0D01*
G01X506897D01*
G02X506694Y1589483I0J203D01*
G01Y1590105D01*
G03X506644Y1590237I-200J0D01*
G02Y1593149I1664J1456D01*
G03X506694Y1593281I-150J132D01*
G01Y1595223D01*
G03X506644Y1595355I-200J0D01*
G02Y1598267I1664J1456D01*
G03X506694Y1598399I-150J132D01*
G01Y1599021D01*
G02X506897Y1599224I203J0D01*
G37*
G36*
G01X1497242Y1589482D02*
G02X1497040Y1589280I-202J0D01*
G01X1494220D01*
G02X1494018Y1589483I1J203D01*
G01Y1590103D01*
G03X1493968Y1590235I-200J0D01*
G02Y1593151I1661J1458D01*
G03X1494018Y1593283I-150J132D01*
G01Y1595221D01*
G03X1493968Y1595353I-200J0D01*
G02Y1598269I1661J1458D01*
G03X1494018Y1598401I-150J132D01*
G01Y1599022D01*
G02X1494220Y1599224I202J0D01*
G01X1497040D01*
G02X1497242Y1599021I-1J-203D01*
G01Y1598401D01*
G03X1497292Y1598269I200J0D01*
G02Y1595353I-1661J-1458D01*
G03X1497242Y1595221I150J-132D01*
G01Y1593283D01*
G03X1497292Y1593151I200J0D01*
G02Y1590235I-1661J-1458D01*
G03X1497242Y1590103I150J-132D01*
G01Y1589482D01*
G37*
G36*
G01X1511543Y1599224D02*
X1514363D01*
G02X1514566Y1599021I0J-203D01*
G01Y1598399D01*
G03X1514616Y1598267I200J0D01*
G02Y1595355I-1664J-1456D01*
G03X1514566Y1595223I150J-132D01*
G01Y1593281D01*
G03X1514616Y1593149I200J0D01*
G02Y1590237I-1664J-1456D01*
G03X1514566Y1590105I150J-132D01*
G01Y1589483D01*
G02X1514363Y1589280I-203J0D01*
G01X1511543D01*
G02X1511340Y1589483I0J203D01*
G01Y1590105D01*
G03X1511290Y1590237I-200J0D01*
G02Y1593149I1664J1456D01*
G03X1511340Y1593281I-150J132D01*
G01Y1595223D01*
G03X1511290Y1595355I-200J0D01*
G02Y1598267I1664J1456D01*
G03X1511340Y1598399I-150J132D01*
G01Y1599021D01*
G02X1511543Y1599224I203J0D01*
G37*
G36*
G01X1528865D02*
X1531685D01*
G02X1531888Y1599021I0J-203D01*
G01Y1598399D01*
G03X1531938Y1598267I200J0D01*
G02Y1595355I-1664J-1456D01*
G03X1531888Y1595223I150J-132D01*
G01Y1593281D01*
G03X1531938Y1593149I200J0D01*
G02Y1590237I-1664J-1456D01*
G03X1531888Y1590105I150J-132D01*
G01Y1589483D01*
G02X1531685Y1589280I-203J0D01*
G01X1528865D01*
G02X1528662Y1589483I0J203D01*
G01Y1590105D01*
G03X1528612Y1590237I-200J0D01*
G02Y1593149I1664J1456D01*
G03X1528662Y1593281I-150J132D01*
G01Y1595223D01*
G03X1528612Y1595355I-200J0D01*
G02Y1598267I1664J1456D01*
G03X1528662Y1598399I-150J132D01*
G01Y1599021D01*
G02X1528865Y1599224I203J0D01*
G37*
G36*
G01X463590Y1603554D02*
X466410D01*
G02X466612Y1603352I0J-202D01*
G01Y1602732D01*
G03X466662Y1602600I200J0D01*
G02Y1599684I-1661J-1458D01*
G03X466612Y1599552I150J-132D01*
G01Y1597614D01*
G03X466662Y1597482I200J0D01*
G02Y1594566I-1661J-1458D01*
G03X466612Y1594434I150J-132D01*
G01Y1593814D01*
G02X466410Y1593612I-202J0D01*
G01X463590D01*
G02X463388Y1593814I0J202D01*
G01Y1594434D01*
G03X463338Y1594566I-200J0D01*
G02Y1597482I1661J1458D01*
G03X463388Y1597614I-150J132D01*
G01Y1599552D01*
G03X463338Y1599684I-200J0D01*
G02Y1602600I1661J1458D01*
G03X463388Y1602732I-150J132D01*
G01Y1603352D01*
G02X463590Y1603554I202J0D01*
G37*
G36*
G01X498236D02*
X501056D01*
G02X501258Y1603352I0J-202D01*
G01Y1602732D01*
G03X501308Y1602600I200J0D01*
G02Y1599684I-1661J-1458D01*
G03X501258Y1599552I150J-132D01*
G01Y1597614D01*
G03X501308Y1597482I200J0D01*
G02Y1594566I-1661J-1458D01*
G03X501258Y1594434I150J-132D01*
G01Y1593814D01*
G02X501056Y1593612I-202J0D01*
G01X498236D01*
G02X498034Y1593814I0J202D01*
G01Y1594434D01*
G03X497984Y1594566I-200J0D01*
G02Y1597482I1661J1458D01*
G03X498034Y1597614I-150J132D01*
G01Y1599552D01*
G03X497984Y1599684I-200J0D01*
G02Y1602600I1661J1458D01*
G03X498034Y1602732I-150J132D01*
G01Y1603352D01*
G02X498236Y1603554I202J0D01*
G37*
G36*
G01X1485558D02*
X1488378D01*
G02X1488580Y1603352I0J-202D01*
G01Y1602732D01*
G03X1488630Y1602600I200J0D01*
G02Y1599684I-1661J-1458D01*
G03X1488580Y1599552I150J-132D01*
G01Y1597614D01*
G03X1488630Y1597482I200J0D01*
G02Y1594566I-1661J-1458D01*
G03X1488580Y1594434I150J-132D01*
G01Y1593814D01*
G02X1488378Y1593612I-202J0D01*
G01X1485558D01*
G02X1485356Y1593814I0J202D01*
G01Y1594434D01*
G03X1485306Y1594566I-200J0D01*
G02Y1597482I1661J1458D01*
G03X1485356Y1597614I-150J132D01*
G01Y1599552D01*
G03X1485306Y1599684I-200J0D01*
G02Y1602600I1661J1458D01*
G03X1485356Y1602732I-150J132D01*
G01Y1603352D01*
G02X1485558Y1603554I202J0D01*
G37*
G36*
G01X1520204D02*
X1523024D01*
G02X1523226Y1603352I0J-202D01*
G01Y1602732D01*
G03X1523276Y1602600I200J0D01*
G02Y1599684I-1661J-1458D01*
G03X1523226Y1599552I150J-132D01*
G01Y1597614D01*
G03X1523276Y1597482I200J0D01*
G02Y1594566I-1661J-1458D01*
G03X1523226Y1594434I150J-132D01*
G01Y1593814D01*
G02X1523024Y1593612I-202J0D01*
G01X1520204D01*
G02X1520002Y1593814I0J202D01*
G01Y1594434D01*
G03X1519952Y1594566I-200J0D01*
G02Y1597482I1661J1458D01*
G03X1520002Y1597614I-150J132D01*
G01Y1599552D01*
G03X1519952Y1599684I-200J0D01*
G02Y1602600I1661J1458D01*
G03X1520002Y1602732I-150J132D01*
G01Y1603352D01*
G02X1520204Y1603554I202J0D01*
G37*
G36*
G01X480912Y1593612D02*
G02X480710Y1593814I0J202D01*
G01Y1594436D01*
G03X480660Y1594568I-200J0D01*
G02Y1597480I1664J1456D01*
G03X480710Y1597612I-150J132D01*
G01Y1599554D01*
G03X480660Y1599686I-200J0D01*
G02Y1602598I1664J1456D01*
G03X480710Y1602730I-150J132D01*
G01Y1603352D01*
G02X480913Y1603554I203J-1D01*
G01X483734D01*
G02X483936Y1603352I0J-202D01*
G01Y1602730D01*
G03X483986Y1602598I200J0D01*
G02Y1599686I-1664J-1456D01*
G03X483936Y1599554I150J-132D01*
G01Y1597612D01*
G03X483986Y1597480I200J0D01*
G02Y1594568I-1664J-1456D01*
G03X483936Y1594436I150J-132D01*
G01Y1593814D01*
G02X483733Y1593612I-203J1D01*
G01X480912D01*
G37*
G36*
G01X1502880D02*
G02X1502678Y1593814I0J202D01*
G01Y1594436D01*
G03X1502628Y1594568I-200J0D01*
G02Y1597480I1664J1456D01*
G03X1502678Y1597612I-150J132D01*
G01Y1599554D01*
G03X1502628Y1599686I-200J0D01*
G02Y1602598I1664J1456D01*
G03X1502678Y1602730I-150J132D01*
G01Y1603352D01*
G02X1502881Y1603554I203J-1D01*
G01X1505702D01*
G02X1505904Y1603352I0J-202D01*
G01Y1602730D01*
G03X1505954Y1602598I200J0D01*
G02Y1599686I-1664J-1456D01*
G03X1505904Y1599554I150J-132D01*
G01Y1597612D01*
G03X1505954Y1597480I200J0D01*
G02Y1594568I-1664J-1456D01*
G03X1505904Y1594436I150J-132D01*
G01Y1593814D01*
G02X1505701Y1593612I-203J1D01*
G01X1502880D01*
G37*
G36*
G01X1537526D02*
G02X1537324Y1593814I0J202D01*
G01Y1594436D01*
G03X1537274Y1594568I-200J0D01*
G02Y1597480I1664J1456D01*
G03X1537324Y1597612I-150J132D01*
G01Y1599554D01*
G03X1537274Y1599686I-200J0D01*
G02Y1602598I1664J1456D01*
G03X1537324Y1602730I-150J132D01*
G01Y1603352D01*
G02X1537527Y1603554I203J-1D01*
G01X1540348D01*
G02X1540550Y1603352I0J-202D01*
G01Y1602730D01*
G03X1540600Y1602598I200J0D01*
G02Y1599686I-1664J-1456D01*
G03X1540550Y1599554I150J-132D01*
G01Y1597612D01*
G03X1540600Y1597480I200J0D01*
G02Y1594568I-1664J-1456D01*
G03X1540550Y1594436I150J-132D01*
G01Y1593814D01*
G02X1540347Y1593612I-203J1D01*
G01X1537526D01*
G37*
G36*
G01X472252Y1614578D02*
X475072D01*
G02X475274Y1614376I0J-202D01*
G01Y1613756D01*
G03X475324Y1613624I200J0D01*
G02Y1610708I-1661J-1458D01*
G03X475274Y1610576I150J-132D01*
G01Y1608638D01*
G03X475324Y1608506I200J0D01*
G02Y1605590I-1661J-1458D01*
G03X475274Y1605458I150J-132D01*
G01Y1604838D01*
G02X475072Y1604636I-202J0D01*
G01X472252D01*
G02X472050Y1604838I0J202D01*
G01Y1605458D01*
G03X472000Y1605590I-200J0D01*
G02Y1608506I1661J1458D01*
G03X472050Y1608638I-150J132D01*
G01Y1610576D01*
G03X472000Y1610708I-200J0D01*
G02Y1613624I1661J1458D01*
G03X472050Y1613756I-150J132D01*
G01Y1614376D01*
G02X472252Y1614578I202J0D01*
G37*
G36*
G01X1494220D02*
X1497040D01*
G02X1497242Y1614376I0J-202D01*
G01Y1613756D01*
G03X1497292Y1613624I200J0D01*
G02Y1610708I-1661J-1458D01*
G03X1497242Y1610576I150J-132D01*
G01Y1608638D01*
G03X1497292Y1608506I200J0D01*
G02Y1605590I-1661J-1458D01*
G03X1497242Y1605458I150J-132D01*
G01Y1604838D01*
G02X1497040Y1604636I-202J0D01*
G01X1494220D01*
G02X1494018Y1604838I0J202D01*
G01Y1605458D01*
G03X1493968Y1605590I-200J0D01*
G02Y1608506I1661J1458D01*
G03X1494018Y1608638I-150J132D01*
G01Y1610576D01*
G03X1493968Y1610708I-200J0D01*
G02Y1613624I1661J1458D01*
G03X1494018Y1613756I-150J132D01*
G01Y1614376D01*
G02X1494220Y1614578I202J0D01*
G37*
G36*
G01X454928Y1604636D02*
G02X454726Y1604838I0J202D01*
G01Y1605460D01*
G03X454676Y1605592I-200J0D01*
G02Y1608504I1664J1456D01*
G03X454726Y1608636I-150J132D01*
G01Y1610578D01*
G03X454676Y1610710I-200J0D01*
G02Y1613622I1664J1456D01*
G03X454726Y1613754I-150J132D01*
G01Y1614376D01*
G02X454929Y1614578I203J-1D01*
G01X457750D01*
G02X457952Y1614376I0J-202D01*
G01Y1613754D01*
G03X458002Y1613622I200J0D01*
G02Y1610710I-1664J-1456D01*
G03X457952Y1610578I150J-132D01*
G01Y1608636D01*
G03X458002Y1608504I200J0D01*
G02Y1605592I-1664J-1456D01*
G03X457952Y1605460I150J-132D01*
G01Y1604838D01*
G02X457749Y1604636I-203J1D01*
G01X454928D01*
G37*
G36*
G01X489574D02*
G02X489372Y1604838I0J202D01*
G01Y1605460D01*
G03X489322Y1605592I-200J0D01*
G02Y1608504I1664J1456D01*
G03X489372Y1608636I-150J132D01*
G01Y1610578D01*
G03X489322Y1610710I-200J0D01*
G02Y1613622I1664J1456D01*
G03X489372Y1613754I-150J132D01*
G01Y1614376D01*
G02X489575Y1614578I203J-1D01*
G01X492396D01*
G02X492598Y1614376I0J-202D01*
G01Y1613754D01*
G03X492648Y1613622I200J0D01*
G02Y1610710I-1664J-1456D01*
G03X492598Y1610578I150J-132D01*
G01Y1608636D01*
G03X492648Y1608504I200J0D01*
G02Y1605592I-1664J-1456D01*
G03X492598Y1605460I150J-132D01*
G01Y1604838D01*
G02X492395Y1604636I-203J1D01*
G01X489574D01*
G37*
G36*
G01X506896D02*
G02X506694Y1604838I0J202D01*
G01Y1605460D01*
G03X506644Y1605592I-200J0D01*
G02Y1608504I1664J1456D01*
G03X506694Y1608636I-150J132D01*
G01Y1610578D01*
G03X506644Y1610710I-200J0D01*
G02Y1613622I1664J1456D01*
G03X506694Y1613754I-150J132D01*
G01Y1614376D01*
G02X506897Y1614578I203J-1D01*
G01X509718D01*
G02X509920Y1614376I0J-202D01*
G01Y1613754D01*
G03X509970Y1613622I200J0D01*
G02Y1610710I-1664J-1456D01*
G03X509920Y1610578I150J-132D01*
G01Y1608636D01*
G03X509970Y1608504I200J0D01*
G02Y1605592I-1664J-1456D01*
G03X509920Y1605460I150J-132D01*
G01Y1604838D01*
G02X509717Y1604636I-203J1D01*
G01X506896D01*
G37*
G36*
G01X1511542D02*
G02X1511340Y1604838I0J202D01*
G01Y1605460D01*
G03X1511290Y1605592I-200J0D01*
G02Y1608504I1664J1456D01*
G03X1511340Y1608636I-150J132D01*
G01Y1610578D01*
G03X1511290Y1610710I-200J0D01*
G02Y1613622I1664J1456D01*
G03X1511340Y1613754I-150J132D01*
G01Y1614376D01*
G02X1511543Y1614578I203J-1D01*
G01X1514364D01*
G02X1514566Y1614376I0J-202D01*
G01Y1613754D01*
G03X1514616Y1613622I200J0D01*
G02Y1610710I-1664J-1456D01*
G03X1514566Y1610578I150J-132D01*
G01Y1608636D01*
G03X1514616Y1608504I200J0D01*
G02Y1605592I-1664J-1456D01*
G03X1514566Y1605460I150J-132D01*
G01Y1604838D01*
G02X1514363Y1604636I-203J1D01*
G01X1511542D01*
G37*
G36*
G01X1528864D02*
G02X1528662Y1604838I0J202D01*
G01Y1605460D01*
G03X1528612Y1605592I-200J0D01*
G02Y1608504I1664J1456D01*
G03X1528662Y1608636I-150J132D01*
G01Y1610578D01*
G03X1528612Y1610710I-200J0D01*
G02Y1613622I1664J1456D01*
G03X1528662Y1613754I-150J132D01*
G01Y1614376D01*
G02X1528865Y1614578I203J-1D01*
G01X1531686D01*
G02X1531888Y1614376I0J-202D01*
G01Y1613754D01*
G03X1531938Y1613622I200J0D01*
G02Y1610710I-1664J-1456D01*
G03X1531888Y1610578I150J-132D01*
G01Y1608636D01*
G03X1531938Y1608504I200J0D01*
G02Y1605592I-1664J-1456D01*
G03X1531888Y1605460I150J-132D01*
G01Y1604838D01*
G02X1531685Y1604636I-203J1D01*
G01X1528864D01*
G37*
G36*
G01X463590Y1618908D02*
X466410D01*
G02X466612Y1618706I0J-202D01*
G01Y1618086D01*
G03X466662Y1617954I200J0D01*
G02Y1615038I-1661J-1458D01*
G03X466612Y1614906I150J-132D01*
G01Y1612968D01*
G03X466662Y1612836I200J0D01*
G02Y1609920I-1661J-1458D01*
G03X466612Y1609788I150J-132D01*
G01Y1609168D01*
G02X466410Y1608966I-202J0D01*
G01X463590D01*
G02X463388Y1609168I0J202D01*
G01Y1609788D01*
G03X463338Y1609920I-200J0D01*
G02Y1612836I1661J1458D01*
G03X463388Y1612968I-150J132D01*
G01Y1614906D01*
G03X463338Y1615038I-200J0D01*
G02Y1617954I1661J1458D01*
G03X463388Y1618086I-150J132D01*
G01Y1618706D01*
G02X463590Y1618908I202J0D01*
G37*
G36*
G01X498236D02*
X501056D01*
G02X501258Y1618706I0J-202D01*
G01Y1618086D01*
G03X501308Y1617954I200J0D01*
G02Y1615038I-1661J-1458D01*
G03X501258Y1614906I150J-132D01*
G01Y1612968D01*
G03X501308Y1612836I200J0D01*
G02Y1609920I-1661J-1458D01*
G03X501258Y1609788I150J-132D01*
G01Y1609168D01*
G02X501056Y1608966I-202J0D01*
G01X498236D01*
G02X498034Y1609168I0J202D01*
G01Y1609788D01*
G03X497984Y1609920I-200J0D01*
G02Y1612836I1661J1458D01*
G03X498034Y1612968I-150J132D01*
G01Y1614906D01*
G03X497984Y1615038I-200J0D01*
G02Y1617954I1661J1458D01*
G03X498034Y1618086I-150J132D01*
G01Y1618706D01*
G02X498236Y1618908I202J0D01*
G37*
G36*
G01X1485558D02*
X1488378D01*
G02X1488580Y1618706I0J-202D01*
G01Y1618086D01*
G03X1488630Y1617954I200J0D01*
G02Y1615038I-1661J-1458D01*
G03X1488580Y1614906I150J-132D01*
G01Y1612968D01*
G03X1488630Y1612836I200J0D01*
G02Y1609920I-1661J-1458D01*
G03X1488580Y1609788I150J-132D01*
G01Y1609168D01*
G02X1488378Y1608966I-202J0D01*
G01X1485558D01*
G02X1485356Y1609168I0J202D01*
G01Y1609788D01*
G03X1485306Y1609920I-200J0D01*
G02Y1612836I1661J1458D01*
G03X1485356Y1612968I-150J132D01*
G01Y1614906D01*
G03X1485306Y1615038I-200J0D01*
G02Y1617954I1661J1458D01*
G03X1485356Y1618086I-150J132D01*
G01Y1618706D01*
G02X1485558Y1618908I202J0D01*
G37*
G36*
G01X1520204D02*
X1523024D01*
G02X1523226Y1618706I0J-202D01*
G01Y1618086D01*
G03X1523276Y1617954I200J0D01*
G02Y1615038I-1661J-1458D01*
G03X1523226Y1614906I150J-132D01*
G01Y1612968D01*
G03X1523276Y1612836I200J0D01*
G02Y1609920I-1661J-1458D01*
G03X1523226Y1609788I150J-132D01*
G01Y1609168D01*
G02X1523024Y1608966I-202J0D01*
G01X1520204D01*
G02X1520002Y1609168I0J202D01*
G01Y1609788D01*
G03X1519952Y1609920I-200J0D01*
G02Y1612836I1661J1458D01*
G03X1520002Y1612968I-150J132D01*
G01Y1614906D01*
G03X1519952Y1615038I-200J0D01*
G02Y1617954I1661J1458D01*
G03X1520002Y1618086I-150J132D01*
G01Y1618706D01*
G02X1520204Y1618908I202J0D01*
G37*
G36*
G01X480912Y1608966D02*
G02X480710Y1609168I0J202D01*
G01Y1609790D01*
G03X480660Y1609922I-200J0D01*
G02Y1612834I1664J1456D01*
G03X480710Y1612966I-150J132D01*
G01Y1614908D01*
G03X480660Y1615040I-200J0D01*
G02Y1617952I1664J1456D01*
G03X480710Y1618084I-150J132D01*
G01Y1618706D01*
G02X480913Y1618908I203J-1D01*
G01X483734D01*
G02X483936Y1618706I0J-202D01*
G01Y1618084D01*
G03X483986Y1617952I200J0D01*
G02Y1615040I-1664J-1456D01*
G03X483936Y1614908I150J-132D01*
G01Y1612966D01*
G03X483986Y1612834I200J0D01*
G02Y1609922I-1664J-1456D01*
G03X483936Y1609790I150J-132D01*
G01Y1609168D01*
G02X483733Y1608966I-203J1D01*
G01X480912D01*
G37*
G36*
G01X1502880D02*
G02X1502678Y1609168I0J202D01*
G01Y1609790D01*
G03X1502628Y1609922I-200J0D01*
G02Y1612834I1664J1456D01*
G03X1502678Y1612966I-150J132D01*
G01Y1614908D01*
G03X1502628Y1615040I-200J0D01*
G02Y1617952I1664J1456D01*
G03X1502678Y1618084I-150J132D01*
G01Y1618706D01*
G02X1502881Y1618908I203J-1D01*
G01X1505702D01*
G02X1505904Y1618706I0J-202D01*
G01Y1618084D01*
G03X1505954Y1617952I200J0D01*
G02Y1615040I-1664J-1456D01*
G03X1505904Y1614908I150J-132D01*
G01Y1612966D01*
G03X1505954Y1612834I200J0D01*
G02Y1609922I-1664J-1456D01*
G03X1505904Y1609790I150J-132D01*
G01Y1609168D01*
G02X1505701Y1608966I-203J1D01*
G01X1502880D01*
G37*
G36*
G01X1537526D02*
G02X1537324Y1609168I0J202D01*
G01Y1609790D01*
G03X1537274Y1609922I-200J0D01*
G02Y1612834I1664J1456D01*
G03X1537324Y1612966I-150J132D01*
G01Y1614908D01*
G03X1537274Y1615040I-200J0D01*
G02Y1617952I1664J1456D01*
G03X1537324Y1618084I-150J132D01*
G01Y1618706D01*
G02X1537527Y1618908I203J-1D01*
G01X1540348D01*
G02X1540550Y1618706I0J-202D01*
G01Y1618084D01*
G03X1540600Y1617952I200J0D01*
G02Y1615040I-1664J-1456D01*
G03X1540550Y1614908I150J-132D01*
G01Y1612966D01*
G03X1540600Y1612834I200J0D01*
G02Y1609922I-1664J-1456D01*
G03X1540550Y1609790I150J-132D01*
G01Y1609168D01*
G02X1540347Y1608966I-203J1D01*
G01X1537526D01*
G37*
G36*
G01X125795Y1466154D02*
X128615D01*
G02X128818Y1465951I0J-203D01*
G01Y1465329D01*
G03X128868Y1465197I200J0D01*
G02Y1462285I-1664J-1456D01*
G03X128818Y1462153I150J-132D01*
G01Y1460210D01*
G03X128868Y1460078I200J0D01*
G02Y1457166I-1664J-1456D01*
G03X128818Y1457034I150J-132D01*
G01Y1456413D01*
G02X128615Y1456210I-203J0D01*
G01X125795D01*
G02X125592Y1456413I0J203D01*
G01Y1457034D01*
G03X125542Y1457166I-200J0D01*
G02Y1460078I1664J1456D01*
G03X125592Y1460210I-150J132D01*
G01Y1462153D01*
G03X125542Y1462285I-200J0D01*
G02Y1465197I1664J1456D01*
G03X125592Y1465329I-150J132D01*
G01Y1465951D01*
G02X125795Y1466154I203J0D01*
G37*
G36*
G01X143118D02*
X145938D01*
G02X146140Y1465951I-1J-203D01*
G01Y1465331D01*
G03X146190Y1465199I200J0D01*
G02Y1462283I-1661J-1458D01*
G03X146140Y1462151I150J-132D01*
G01Y1460212D01*
G03X146190Y1460080I200J0D01*
G02Y1457164I-1661J-1458D01*
G03X146140Y1457032I150J-132D01*
G01Y1456413D01*
G02X145938Y1456210I-202J-1D01*
G01X143118D01*
G02X142916Y1456413I1J203D01*
G01Y1457032D01*
G03X142866Y1457164I-200J0D01*
G02Y1460080I1661J1458D01*
G03X142916Y1460212I-150J132D01*
G01Y1462151D01*
G03X142866Y1462283I-200J0D01*
G02Y1465199I1661J1458D01*
G03X142916Y1465331I-150J132D01*
G01Y1465951D01*
G02X143118Y1466154I202J1D01*
G37*
G36*
G01X160440D02*
X163260D01*
G02X163462Y1465951I-1J-203D01*
G01Y1465331D01*
G03X163512Y1465199I200J0D01*
G02Y1462283I-1661J-1458D01*
G03X163462Y1462151I150J-132D01*
G01Y1460212D01*
G03X163512Y1460080I200J0D01*
G02Y1457164I-1661J-1458D01*
G03X163462Y1457032I150J-132D01*
G01Y1456413D01*
G02X163260Y1456210I-202J-1D01*
G01X160440D01*
G02X160238Y1456413I1J203D01*
G01Y1457032D01*
G03X160188Y1457164I-200J0D01*
G02Y1460080I1661J1458D01*
G03X160238Y1460212I-150J132D01*
G01Y1462151D01*
G03X160188Y1462283I-200J0D01*
G02Y1465199I1661J1458D01*
G03X160238Y1465331I-150J132D01*
G01Y1465951D01*
G02X160440Y1466154I202J1D01*
G37*
G36*
G01X177763D02*
X180583D01*
G02X180786Y1465951I0J-203D01*
G01Y1465329D01*
G03X180836Y1465197I200J0D01*
G02Y1462285I-1664J-1456D01*
G03X180786Y1462153I150J-132D01*
G01Y1460210D01*
G03X180836Y1460078I200J0D01*
G02Y1457166I-1664J-1456D01*
G03X180786Y1457034I150J-132D01*
G01Y1456413D01*
G02X180583Y1456210I-203J0D01*
G01X177763D01*
G02X177560Y1456413I0J203D01*
G01Y1457034D01*
G03X177510Y1457166I-200J0D01*
G02Y1460078I1664J1456D01*
G03X177560Y1460210I-150J132D01*
G01Y1462153D01*
G03X177510Y1462285I-200J0D01*
G02Y1465197I1664J1456D01*
G03X177560Y1465329I-150J132D01*
G01Y1465951D01*
G02X177763Y1466154I203J0D01*
G37*
G36*
G01X281700D02*
X284520D01*
G02X284722Y1465951I-1J-203D01*
G01Y1465331D01*
G03X284772Y1465199I200J0D01*
G02Y1462283I-1661J-1458D01*
G03X284722Y1462151I150J-132D01*
G01Y1460212D01*
G03X284772Y1460080I200J0D01*
G02Y1457164I-1661J-1458D01*
G03X284722Y1457032I150J-132D01*
G01Y1456413D01*
G02X284520Y1456210I-202J-1D01*
G01X281700D01*
G02X281498Y1456413I1J203D01*
G01Y1457032D01*
G03X281448Y1457164I-200J0D01*
G02Y1460080I1661J1458D01*
G03X281498Y1460212I-150J132D01*
G01Y1462151D01*
G03X281448Y1462283I-200J0D01*
G02Y1465199I1661J1458D01*
G03X281498Y1465331I-150J132D01*
G01Y1465951D01*
G02X281700Y1466154I202J1D01*
G37*
G36*
G01X299023D02*
X301843D01*
G02X302046Y1465951I0J-203D01*
G01Y1465329D01*
G03X302096Y1465197I200J0D01*
G02Y1462285I-1664J-1456D01*
G03X302046Y1462153I150J-132D01*
G01Y1460210D01*
G03X302096Y1460078I200J0D01*
G02Y1457166I-1664J-1456D01*
G03X302046Y1457034I150J-132D01*
G01Y1456413D01*
G02X301843Y1456210I-203J0D01*
G01X299023D01*
G02X298820Y1456413I0J203D01*
G01Y1457034D01*
G03X298770Y1457166I-200J0D01*
G02Y1460078I1664J1456D01*
G03X298820Y1460210I-150J132D01*
G01Y1462153D01*
G03X298770Y1462285I-200J0D01*
G02Y1465197I1664J1456D01*
G03X298820Y1465329I-150J132D01*
G01Y1465951D01*
G02X299023Y1466154I203J0D01*
G37*
G36*
G01X454929D02*
X457749D01*
G02X457952Y1465951I0J-203D01*
G01Y1465329D01*
G03X458002Y1465197I200J0D01*
G02Y1462285I-1664J-1456D01*
G03X457952Y1462153I150J-132D01*
G01Y1460210D01*
G03X458002Y1460078I200J0D01*
G02Y1457166I-1664J-1456D01*
G03X457952Y1457034I150J-132D01*
G01Y1456413D01*
G02X457749Y1456210I-203J0D01*
G01X454929D01*
G02X454726Y1456413I0J203D01*
G01Y1457034D01*
G03X454676Y1457166I-200J0D01*
G02Y1460078I1664J1456D01*
G03X454726Y1460210I-150J132D01*
G01Y1462153D01*
G03X454676Y1462285I-200J0D01*
G02Y1465197I1664J1456D01*
G03X454726Y1465329I-150J132D01*
G01Y1465951D01*
G02X454929Y1466154I203J0D01*
G37*
G36*
G01X472252D02*
X475072D01*
G02X475274Y1465951I-1J-203D01*
G01Y1465331D01*
G03X475324Y1465199I200J0D01*
G02Y1462283I-1661J-1458D01*
G03X475274Y1462151I150J-132D01*
G01Y1460212D01*
G03X475324Y1460080I200J0D01*
G02Y1457164I-1661J-1458D01*
G03X475274Y1457032I150J-132D01*
G01Y1456413D01*
G02X475072Y1456210I-202J-1D01*
G01X472252D01*
G02X472050Y1456413I1J203D01*
G01Y1457032D01*
G03X472000Y1457164I-200J0D01*
G02Y1460080I1661J1458D01*
G03X472050Y1460212I-150J132D01*
G01Y1462151D01*
G03X472000Y1462283I-200J0D01*
G02Y1465199I1661J1458D01*
G03X472050Y1465331I-150J132D01*
G01Y1465951D01*
G02X472252Y1466154I202J1D01*
G37*
G36*
G01X489575D02*
X492395D01*
G02X492598Y1465951I0J-203D01*
G01Y1465329D01*
G03X492648Y1465197I200J0D01*
G02Y1462285I-1664J-1456D01*
G03X492598Y1462153I150J-132D01*
G01Y1460210D01*
G03X492648Y1460078I200J0D01*
G02Y1457166I-1664J-1456D01*
G03X492598Y1457034I150J-132D01*
G01Y1456413D01*
G02X492395Y1456210I-203J0D01*
G01X489575D01*
G02X489372Y1456413I0J203D01*
G01Y1457034D01*
G03X489322Y1457166I-200J0D01*
G02Y1460078I1664J1456D01*
G03X489372Y1460210I-150J132D01*
G01Y1462153D01*
G03X489322Y1462285I-200J0D01*
G02Y1465197I1664J1456D01*
G03X489372Y1465329I-150J132D01*
G01Y1465951D01*
G02X489575Y1466154I203J0D01*
G37*
G36*
G01X506897D02*
X509717D01*
G02X509920Y1465951I0J-203D01*
G01Y1465329D01*
G03X509970Y1465197I200J0D01*
G02Y1462285I-1664J-1456D01*
G03X509920Y1462153I150J-132D01*
G01Y1460210D01*
G03X509970Y1460078I200J0D01*
G02Y1457166I-1664J-1456D01*
G03X509920Y1457034I150J-132D01*
G01Y1456413D01*
G02X509717Y1456210I-203J0D01*
G01X506897D01*
G02X506694Y1456413I0J203D01*
G01Y1457034D01*
G03X506644Y1457166I-200J0D01*
G02Y1460078I1664J1456D01*
G03X506694Y1460210I-150J132D01*
G01Y1462153D01*
G03X506644Y1462285I-200J0D01*
G02Y1465197I1664J1456D01*
G03X506694Y1465329I-150J132D01*
G01Y1465951D01*
G02X506897Y1466154I203J0D01*
G37*
G36*
G01X645480D02*
X648300D01*
G02X648502Y1465951I-1J-203D01*
G01Y1465331D01*
G03X648552Y1465199I200J0D01*
G02Y1462283I-1661J-1458D01*
G03X648502Y1462151I150J-132D01*
G01Y1460212D01*
G03X648552Y1460080I200J0D01*
G02Y1457164I-1661J-1458D01*
G03X648502Y1457032I150J-132D01*
G01Y1456413D01*
G02X648300Y1456210I-202J-1D01*
G01X645480D01*
G02X645278Y1456413I1J203D01*
G01Y1457032D01*
G03X645228Y1457164I-200J0D01*
G02Y1460080I1661J1458D01*
G03X645278Y1460212I-150J132D01*
G01Y1462151D01*
G03X645228Y1462283I-200J0D01*
G02Y1465199I1661J1458D01*
G03X645278Y1465331I-150J132D01*
G01Y1465951D01*
G02X645480Y1466154I202J1D01*
G37*
G36*
G01X662803D02*
X665623D01*
G02X665826Y1465951I0J-203D01*
G01Y1465329D01*
G03X665876Y1465197I200J0D01*
G02Y1462285I-1664J-1456D01*
G03X665826Y1462153I150J-132D01*
G01Y1460210D01*
G03X665876Y1460078I200J0D01*
G02Y1457166I-1664J-1456D01*
G03X665826Y1457034I150J-132D01*
G01Y1456413D01*
G02X665623Y1456210I-203J0D01*
G01X662803D01*
G02X662600Y1456413I0J203D01*
G01Y1457034D01*
G03X662550Y1457166I-200J0D01*
G02Y1460078I1664J1456D01*
G03X662600Y1460210I-150J132D01*
G01Y1462153D01*
G03X662550Y1462285I-200J0D01*
G02Y1465197I1664J1456D01*
G03X662600Y1465329I-150J132D01*
G01Y1465951D01*
G02X662803Y1466154I203J0D01*
G37*
G36*
G01X680125D02*
X682945D01*
G02X683148Y1465951I0J-203D01*
G01Y1465329D01*
G03X683198Y1465197I200J0D01*
G02Y1462285I-1664J-1456D01*
G03X683148Y1462153I150J-132D01*
G01Y1460210D01*
G03X683198Y1460078I200J0D01*
G02Y1457166I-1664J-1456D01*
G03X683148Y1457034I150J-132D01*
G01Y1456413D01*
G02X682945Y1456210I-203J0D01*
G01X680125D01*
G02X679922Y1456413I0J203D01*
G01Y1457034D01*
G03X679872Y1457166I-200J0D01*
G02Y1460078I1664J1456D01*
G03X679922Y1460210I-150J132D01*
G01Y1462153D01*
G03X679872Y1462285I-200J0D01*
G02Y1465197I1664J1456D01*
G03X679922Y1465329I-150J132D01*
G01Y1465951D01*
G02X680125Y1466154I203J0D01*
G37*
G36*
G01X1165086D02*
X1167906D01*
G02X1168108Y1465951I-1J-203D01*
G01Y1465331D01*
G03X1168158Y1465199I200J0D01*
G02Y1462283I-1661J-1458D01*
G03X1168108Y1462151I150J-132D01*
G01Y1460212D01*
G03X1168158Y1460080I200J0D01*
G02Y1457164I-1661J-1458D01*
G03X1168108Y1457032I150J-132D01*
G01Y1456413D01*
G02X1167906Y1456210I-202J-1D01*
G01X1165086D01*
G02X1164884Y1456413I1J203D01*
G01Y1457032D01*
G03X1164834Y1457164I-200J0D01*
G02Y1460080I1661J1458D01*
G03X1164884Y1460212I-150J132D01*
G01Y1462151D01*
G03X1164834Y1462283I-200J0D01*
G02Y1465199I1661J1458D01*
G03X1164884Y1465331I-150J132D01*
G01Y1465951D01*
G02X1165086Y1466154I202J1D01*
G37*
G36*
G01X1182408D02*
X1185228D01*
G02X1185430Y1465951I-1J-203D01*
G01Y1465331D01*
G03X1185480Y1465199I200J0D01*
G02Y1462283I-1661J-1458D01*
G03X1185430Y1462151I150J-132D01*
G01Y1460212D01*
G03X1185480Y1460080I200J0D01*
G02Y1457164I-1661J-1458D01*
G03X1185430Y1457032I150J-132D01*
G01Y1456413D01*
G02X1185228Y1456210I-202J-1D01*
G01X1182408D01*
G02X1182206Y1456413I1J203D01*
G01Y1457032D01*
G03X1182156Y1457164I-200J0D01*
G02Y1460080I1661J1458D01*
G03X1182206Y1460212I-150J132D01*
G01Y1462151D01*
G03X1182156Y1462283I-200J0D01*
G02Y1465199I1661J1458D01*
G03X1182206Y1465331I-150J132D01*
G01Y1465951D01*
G02X1182408Y1466154I202J1D01*
G37*
G36*
G01X1303669D02*
X1306489D01*
G02X1306692Y1465951I0J-203D01*
G01Y1465329D01*
G03X1306742Y1465197I200J0D01*
G02Y1462285I-1664J-1456D01*
G03X1306692Y1462153I150J-132D01*
G01Y1460210D01*
G03X1306742Y1460078I200J0D01*
G02Y1457166I-1664J-1456D01*
G03X1306692Y1457034I150J-132D01*
G01Y1456413D01*
G02X1306489Y1456210I-203J0D01*
G01X1303669D01*
G02X1303466Y1456413I0J203D01*
G01Y1457034D01*
G03X1303416Y1457166I-200J0D01*
G02Y1460078I1664J1456D01*
G03X1303466Y1460210I-150J132D01*
G01Y1462153D01*
G03X1303416Y1462285I-200J0D01*
G02Y1465197I1664J1456D01*
G03X1303466Y1465329I-150J132D01*
G01Y1465951D01*
G02X1303669Y1466154I203J0D01*
G37*
G36*
G01X1320992D02*
X1323812D01*
G02X1324014Y1465951I-1J-203D01*
G01Y1465331D01*
G03X1324064Y1465199I200J0D01*
G02Y1462283I-1661J-1458D01*
G03X1324014Y1462151I150J-132D01*
G01Y1460212D01*
G03X1324064Y1460080I200J0D01*
G02Y1457164I-1661J-1458D01*
G03X1324014Y1457032I150J-132D01*
G01Y1456413D01*
G02X1323812Y1456210I-202J-1D01*
G01X1320992D01*
G02X1320790Y1456413I1J203D01*
G01Y1457032D01*
G03X1320740Y1457164I-200J0D01*
G02Y1460080I1661J1458D01*
G03X1320790Y1460212I-150J132D01*
G01Y1462151D01*
G03X1320740Y1462283I-200J0D01*
G02Y1465199I1661J1458D01*
G03X1320790Y1465331I-150J132D01*
G01Y1465951D01*
G02X1320992Y1466154I202J1D01*
G37*
G36*
G01X1338315D02*
X1341135D01*
G02X1341338Y1465951I0J-203D01*
G01Y1465329D01*
G03X1341388Y1465197I200J0D01*
G02Y1462285I-1664J-1456D01*
G03X1341338Y1462153I150J-132D01*
G01Y1460210D01*
G03X1341388Y1460078I200J0D01*
G02Y1457166I-1664J-1456D01*
G03X1341338Y1457034I150J-132D01*
G01Y1456413D01*
G02X1341135Y1456210I-203J0D01*
G01X1338315D01*
G02X1338112Y1456413I0J203D01*
G01Y1457034D01*
G03X1338062Y1457166I-200J0D01*
G02Y1460078I1664J1456D01*
G03X1338112Y1460210I-150J132D01*
G01Y1462153D01*
G03X1338062Y1462285I-200J0D01*
G02Y1465197I1664J1456D01*
G03X1338112Y1465329I-150J132D01*
G01Y1465951D01*
G02X1338315Y1466154I203J0D01*
G37*
G36*
G01X1355637D02*
X1358457D01*
G02X1358660Y1465951I0J-203D01*
G01Y1465329D01*
G03X1358710Y1465197I200J0D01*
G02Y1462285I-1664J-1456D01*
G03X1358660Y1462153I150J-132D01*
G01Y1460210D01*
G03X1358710Y1460078I200J0D01*
G02Y1457166I-1664J-1456D01*
G03X1358660Y1457034I150J-132D01*
G01Y1456413D01*
G02X1358457Y1456210I-203J0D01*
G01X1355637D01*
G02X1355434Y1456413I0J203D01*
G01Y1457034D01*
G03X1355384Y1457166I-200J0D01*
G02Y1460078I1664J1456D01*
G03X1355434Y1460210I-150J132D01*
G01Y1462153D01*
G03X1355384Y1462285I-200J0D01*
G02Y1465197I1664J1456D01*
G03X1355434Y1465329I-150J132D01*
G01Y1465951D01*
G02X1355637Y1466154I203J0D01*
G37*
G36*
G01X1476897D02*
X1479717D01*
G02X1479920Y1465951I0J-203D01*
G01Y1465329D01*
G03X1479970Y1465197I200J0D01*
G02Y1462285I-1664J-1456D01*
G03X1479920Y1462153I150J-132D01*
G01Y1460210D01*
G03X1479970Y1460078I200J0D01*
G02Y1457166I-1664J-1456D01*
G03X1479920Y1457034I150J-132D01*
G01Y1456413D01*
G02X1479717Y1456210I-203J0D01*
G01X1476897D01*
G02X1476694Y1456413I0J203D01*
G01Y1457034D01*
G03X1476644Y1457166I-200J0D01*
G02Y1460078I1664J1456D01*
G03X1476694Y1460210I-150J132D01*
G01Y1462153D01*
G03X1476644Y1462285I-200J0D01*
G02Y1465197I1664J1456D01*
G03X1476694Y1465329I-150J132D01*
G01Y1465951D01*
G02X1476897Y1466154I203J0D01*
G37*
G36*
G01X1494220D02*
X1497040D01*
G02X1497242Y1465951I-1J-203D01*
G01Y1465331D01*
G03X1497292Y1465199I200J0D01*
G02Y1462283I-1661J-1458D01*
G03X1497242Y1462151I150J-132D01*
G01Y1460212D01*
G03X1497292Y1460080I200J0D01*
G02Y1457164I-1661J-1458D01*
G03X1497242Y1457032I150J-132D01*
G01Y1456413D01*
G02X1497040Y1456210I-202J-1D01*
G01X1494220D01*
G02X1494018Y1456413I1J203D01*
G01Y1457032D01*
G03X1493968Y1457164I-200J0D01*
G02Y1460080I1661J1458D01*
G03X1494018Y1460212I-150J132D01*
G01Y1462151D01*
G03X1493968Y1462283I-200J0D01*
G02Y1465199I1661J1458D01*
G03X1494018Y1465331I-150J132D01*
G01Y1465951D01*
G02X1494220Y1466154I202J1D01*
G37*
G36*
G01X1511543D02*
X1514363D01*
G02X1514566Y1465951I0J-203D01*
G01Y1465329D01*
G03X1514616Y1465197I200J0D01*
G02Y1462285I-1664J-1456D01*
G03X1514566Y1462153I150J-132D01*
G01Y1460210D01*
G03X1514616Y1460078I200J0D01*
G02Y1457166I-1664J-1456D01*
G03X1514566Y1457034I150J-132D01*
G01Y1456413D01*
G02X1514363Y1456210I-203J0D01*
G01X1511543D01*
G02X1511340Y1456413I0J203D01*
G01Y1457034D01*
G03X1511290Y1457166I-200J0D01*
G02Y1460078I1664J1456D01*
G03X1511340Y1460210I-150J132D01*
G01Y1462153D01*
G03X1511290Y1462285I-200J0D01*
G02Y1465197I1664J1456D01*
G03X1511340Y1465329I-150J132D01*
G01Y1465951D01*
G02X1511543Y1466154I203J0D01*
G37*
G36*
G01X1528865D02*
X1531685D01*
G02X1531888Y1465951I0J-203D01*
G01Y1465329D01*
G03X1531938Y1465197I200J0D01*
G02Y1462285I-1664J-1456D01*
G03X1531888Y1462153I150J-132D01*
G01Y1460210D01*
G03X1531938Y1460078I200J0D01*
G02Y1457166I-1664J-1456D01*
G03X1531888Y1457034I150J-132D01*
G01Y1456413D01*
G02X1531685Y1456210I-203J0D01*
G01X1528865D01*
G02X1528662Y1456413I0J203D01*
G01Y1457034D01*
G03X1528612Y1457166I-200J0D01*
G02Y1460078I1664J1456D01*
G03X1528662Y1460210I-150J132D01*
G01Y1462153D01*
G03X1528612Y1462285I-200J0D01*
G02Y1465197I1664J1456D01*
G03X1528662Y1465329I-150J132D01*
G01Y1465951D01*
G02X1528865Y1466154I203J0D01*
G37*
G36*
G01X1684771D02*
X1687591D01*
G02X1687794Y1465951I0J-203D01*
G01Y1465329D01*
G03X1687844Y1465197I200J0D01*
G02Y1462285I-1664J-1456D01*
G03X1687794Y1462153I150J-132D01*
G01Y1460210D01*
G03X1687844Y1460078I200J0D01*
G02Y1457166I-1664J-1456D01*
G03X1687794Y1457034I150J-132D01*
G01Y1456413D01*
G02X1687591Y1456210I-203J0D01*
G01X1684771D01*
G02X1684568Y1456413I0J203D01*
G01Y1457034D01*
G03X1684518Y1457166I-200J0D01*
G02Y1460078I1664J1456D01*
G03X1684568Y1460210I-150J132D01*
G01Y1462153D01*
G03X1684518Y1462285I-200J0D01*
G02Y1465197I1664J1456D01*
G03X1684568Y1465329I-150J132D01*
G01Y1465951D01*
G02X1684771Y1466154I203J0D01*
G37*
G36*
G01X1702093D02*
X1704913D01*
G02X1705116Y1465951I0J-203D01*
G01Y1465329D01*
G03X1705166Y1465197I200J0D01*
G02Y1462285I-1664J-1456D01*
G03X1705116Y1462153I150J-132D01*
G01Y1460210D01*
G03X1705166Y1460078I200J0D01*
G02Y1457166I-1664J-1456D01*
G03X1705116Y1457034I150J-132D01*
G01Y1456413D01*
G02X1704913Y1456210I-203J0D01*
G01X1702093D01*
G02X1701890Y1456413I0J203D01*
G01Y1457034D01*
G03X1701840Y1457166I-200J0D01*
G02Y1460078I1664J1456D01*
G03X1701890Y1460210I-150J132D01*
G01Y1462153D01*
G03X1701840Y1462285I-200J0D01*
G02Y1465197I1664J1456D01*
G03X1701890Y1465329I-150J132D01*
G01Y1465951D01*
G02X1702093Y1466154I203J0D01*
G37*
G36*
G01X134456Y1470484D02*
X137276D01*
G02X137478Y1470281I-1J-203D01*
G01Y1469661D01*
G03X137528Y1469529I200J0D01*
G02Y1466613I-1661J-1458D01*
G03X137478Y1466481I150J-132D01*
G01Y1464543D01*
G03X137528Y1464411I200J0D01*
G02Y1461495I-1661J-1458D01*
G03X137478Y1461363I150J-132D01*
G01Y1460743D01*
G02X137276Y1460540I-202J-1D01*
G01X134456D01*
G02X134254Y1460743I1J203D01*
G01Y1461363D01*
G03X134204Y1461495I-200J0D01*
G02Y1464411I1661J1458D01*
G03X134254Y1464543I-150J132D01*
G01Y1466481D01*
G03X134204Y1466613I-200J0D01*
G02Y1469529I1661J1458D01*
G03X134254Y1469661I-150J132D01*
G01Y1470281D01*
G02X134456Y1470484I202J1D01*
G37*
G36*
G01X151779D02*
X154599D01*
G02X154802Y1470281I0J-203D01*
G01Y1469659D01*
G03X154852Y1469527I200J0D01*
G02Y1466615I-1664J-1456D01*
G03X154802Y1466483I150J-132D01*
G01Y1464541D01*
G03X154852Y1464409I200J0D01*
G02Y1461497I-1664J-1456D01*
G03X154802Y1461365I150J-132D01*
G01Y1460743D01*
G02X154599Y1460540I-203J0D01*
G01X151779D01*
G02X151576Y1460743I0J203D01*
G01Y1461365D01*
G03X151526Y1461497I-200J0D01*
G02Y1464409I1664J1456D01*
G03X151576Y1464541I-150J132D01*
G01Y1466483D01*
G03X151526Y1466615I-200J0D01*
G02Y1469527I1664J1456D01*
G03X151576Y1469659I-150J132D01*
G01Y1470281D01*
G02X151779Y1470484I203J0D01*
G37*
G36*
G01X169102D02*
X171922D01*
G02X172124Y1470281I-1J-203D01*
G01Y1469661D01*
G03X172174Y1469529I200J0D01*
G02Y1466613I-1661J-1458D01*
G03X172124Y1466481I150J-132D01*
G01Y1464543D01*
G03X172174Y1464411I200J0D01*
G02Y1461495I-1661J-1458D01*
G03X172124Y1461363I150J-132D01*
G01Y1460743D01*
G02X171922Y1460540I-202J-1D01*
G01X169102D01*
G02X168900Y1460743I1J203D01*
G01Y1461363D01*
G03X168850Y1461495I-200J0D01*
G02Y1464411I1661J1458D01*
G03X168900Y1464543I-150J132D01*
G01Y1466481D01*
G03X168850Y1466613I-200J0D01*
G02Y1469529I1661J1458D01*
G03X168900Y1469661I-150J132D01*
G01Y1470281D01*
G02X169102Y1470484I202J1D01*
G37*
G36*
G01X186425D02*
X189245D01*
G02X189448Y1470281I0J-203D01*
G01Y1469659D01*
G03X189498Y1469527I200J0D01*
G02Y1466615I-1664J-1456D01*
G03X189448Y1466483I150J-132D01*
G01Y1464541D01*
G03X189498Y1464409I200J0D01*
G02Y1461497I-1664J-1456D01*
G03X189448Y1461365I150J-132D01*
G01Y1460743D01*
G02X189245Y1460540I-203J0D01*
G01X186425D01*
G02X186222Y1460743I0J203D01*
G01Y1461365D01*
G03X186172Y1461497I-200J0D01*
G02Y1464409I1664J1456D01*
G03X186222Y1464541I-150J132D01*
G01Y1466483D01*
G03X186172Y1466615I-200J0D01*
G02Y1469527I1664J1456D01*
G03X186222Y1469659I-150J132D01*
G01Y1470281D01*
G02X186425Y1470484I203J0D01*
G37*
G36*
G01X290361D02*
X293181D01*
G02X293384Y1470281I0J-203D01*
G01Y1469659D01*
G03X293434Y1469527I200J0D01*
G02Y1466615I-1664J-1456D01*
G03X293384Y1466483I150J-132D01*
G01Y1464541D01*
G03X293434Y1464409I200J0D01*
G02Y1461497I-1664J-1456D01*
G03X293384Y1461365I150J-132D01*
G01Y1460743D01*
G02X293181Y1460540I-203J0D01*
G01X290361D01*
G02X290158Y1460743I0J203D01*
G01Y1461365D01*
G03X290108Y1461497I-200J0D01*
G02Y1464409I1664J1456D01*
G03X290158Y1464541I-150J132D01*
G01Y1466483D01*
G03X290108Y1466615I-200J0D01*
G02Y1469527I1664J1456D01*
G03X290158Y1469659I-150J132D01*
G01Y1470281D01*
G02X290361Y1470484I203J0D01*
G37*
G36*
G01X463590D02*
X466410D01*
G02X466612Y1470281I-1J-203D01*
G01Y1469661D01*
G03X466662Y1469529I200J0D01*
G02Y1466613I-1661J-1458D01*
G03X466612Y1466481I150J-132D01*
G01Y1464543D01*
G03X466662Y1464411I200J0D01*
G02Y1461495I-1661J-1458D01*
G03X466612Y1461363I150J-132D01*
G01Y1460743D01*
G02X466410Y1460540I-202J-1D01*
G01X463590D01*
G02X463388Y1460743I1J203D01*
G01Y1461363D01*
G03X463338Y1461495I-200J0D01*
G02Y1464411I1661J1458D01*
G03X463388Y1464543I-150J132D01*
G01Y1466481D01*
G03X463338Y1466613I-200J0D01*
G02Y1469529I1661J1458D01*
G03X463388Y1469661I-150J132D01*
G01Y1470281D01*
G02X463590Y1470484I202J1D01*
G37*
G36*
G01X480913D02*
X483733D01*
G02X483936Y1470281I0J-203D01*
G01Y1469659D01*
G03X483986Y1469527I200J0D01*
G02Y1466615I-1664J-1456D01*
G03X483936Y1466483I150J-132D01*
G01Y1464541D01*
G03X483986Y1464409I200J0D01*
G02Y1461497I-1664J-1456D01*
G03X483936Y1461365I150J-132D01*
G01Y1460743D01*
G02X483733Y1460540I-203J0D01*
G01X480913D01*
G02X480710Y1460743I0J203D01*
G01Y1461365D01*
G03X480660Y1461497I-200J0D01*
G02Y1464409I1664J1456D01*
G03X480710Y1464541I-150J132D01*
G01Y1466483D01*
G03X480660Y1466615I-200J0D01*
G02Y1469527I1664J1456D01*
G03X480710Y1469659I-150J132D01*
G01Y1470281D01*
G02X480913Y1470484I203J0D01*
G37*
G36*
G01X498236D02*
X501056D01*
G02X501258Y1470281I-1J-203D01*
G01Y1469661D01*
G03X501308Y1469529I200J0D01*
G02Y1466613I-1661J-1458D01*
G03X501258Y1466481I150J-132D01*
G01Y1464543D01*
G03X501308Y1464411I200J0D01*
G02Y1461495I-1661J-1458D01*
G03X501258Y1461363I150J-132D01*
G01Y1460743D01*
G02X501056Y1460540I-202J-1D01*
G01X498236D01*
G02X498034Y1460743I1J203D01*
G01Y1461363D01*
G03X497984Y1461495I-200J0D01*
G02Y1464411I1661J1458D01*
G03X498034Y1464543I-150J132D01*
G01Y1466481D01*
G03X497984Y1466613I-200J0D01*
G02Y1469529I1661J1458D01*
G03X498034Y1469661I-150J132D01*
G01Y1470281D01*
G02X498236Y1470484I202J1D01*
G37*
G36*
G01X515559D02*
X518379D01*
G02X518582Y1470281I0J-203D01*
G01Y1469659D01*
G03X518632Y1469527I200J0D01*
G02Y1466615I-1664J-1456D01*
G03X518582Y1466483I150J-132D01*
G01Y1464541D01*
G03X518632Y1464409I200J0D01*
G02Y1461497I-1664J-1456D01*
G03X518582Y1461365I150J-132D01*
G01Y1460743D01*
G02X518379Y1460540I-203J0D01*
G01X515559D01*
G02X515356Y1460743I0J203D01*
G01Y1461365D01*
G03X515306Y1461497I-200J0D01*
G02Y1464409I1664J1456D01*
G03X515356Y1464541I-150J132D01*
G01Y1466483D01*
G03X515306Y1466615I-200J0D01*
G02Y1469527I1664J1456D01*
G03X515356Y1469659I-150J132D01*
G01Y1470281D01*
G02X515559Y1470484I203J0D01*
G37*
G36*
G01X654141D02*
X656961D01*
G02X657164Y1470281I0J-203D01*
G01Y1469659D01*
G03X657214Y1469527I200J0D01*
G02Y1466615I-1664J-1456D01*
G03X657164Y1466483I150J-132D01*
G01Y1464541D01*
G03X657214Y1464409I200J0D01*
G02Y1461497I-1664J-1456D01*
G03X657164Y1461365I150J-132D01*
G01Y1460743D01*
G02X656961Y1460540I-203J0D01*
G01X654141D01*
G02X653938Y1460743I0J203D01*
G01Y1461365D01*
G03X653888Y1461497I-200J0D01*
G02Y1464409I1664J1456D01*
G03X653938Y1464541I-150J132D01*
G01Y1466483D01*
G03X653888Y1466615I-200J0D01*
G02Y1469527I1664J1456D01*
G03X653938Y1469659I-150J132D01*
G01Y1470281D01*
G02X654141Y1470484I203J0D01*
G37*
G36*
G01X671464D02*
X674284D01*
G02X674486Y1470281I-1J-203D01*
G01Y1469661D01*
G03X674536Y1469529I200J0D01*
G02Y1466613I-1661J-1458D01*
G03X674486Y1466481I150J-132D01*
G01Y1464543D01*
G03X674536Y1464411I200J0D01*
G02Y1461495I-1661J-1458D01*
G03X674486Y1461363I150J-132D01*
G01Y1460743D01*
G02X674284Y1460540I-202J-1D01*
G01X671464D01*
G02X671262Y1460743I1J203D01*
G01Y1461363D01*
G03X671212Y1461495I-200J0D01*
G02Y1464411I1661J1458D01*
G03X671262Y1464543I-150J132D01*
G01Y1466481D01*
G03X671212Y1466613I-200J0D01*
G02Y1469529I1661J1458D01*
G03X671262Y1469661I-150J132D01*
G01Y1470281D01*
G02X671464Y1470484I202J1D01*
G37*
G36*
G01X688787D02*
X691607D01*
G02X691810Y1470281I0J-203D01*
G01Y1469659D01*
G03X691860Y1469527I200J0D01*
G02Y1466615I-1664J-1456D01*
G03X691810Y1466483I150J-132D01*
G01Y1464541D01*
G03X691860Y1464409I200J0D01*
G02Y1461497I-1664J-1456D01*
G03X691810Y1461365I150J-132D01*
G01Y1460743D01*
G02X691607Y1460540I-203J0D01*
G01X688787D01*
G02X688584Y1460743I0J203D01*
G01Y1461365D01*
G03X688534Y1461497I-200J0D01*
G02Y1464409I1664J1456D01*
G03X688584Y1464541I-150J132D01*
G01Y1466483D01*
G03X688534Y1466615I-200J0D01*
G02Y1469527I1664J1456D01*
G03X688584Y1469659I-150J132D01*
G01Y1470281D01*
G02X688787Y1470484I203J0D01*
G37*
G36*
G01X1173747D02*
X1176567D01*
G02X1176770Y1470281I0J-203D01*
G01Y1469659D01*
G03X1176820Y1469527I200J0D01*
G02Y1466615I-1664J-1456D01*
G03X1176770Y1466483I150J-132D01*
G01Y1464541D01*
G03X1176820Y1464409I200J0D01*
G02Y1461497I-1664J-1456D01*
G03X1176770Y1461365I150J-132D01*
G01Y1460743D01*
G02X1176567Y1460540I-203J0D01*
G01X1173747D01*
G02X1173544Y1460743I0J203D01*
G01Y1461365D01*
G03X1173494Y1461497I-200J0D01*
G02Y1464409I1664J1456D01*
G03X1173544Y1464541I-150J132D01*
G01Y1466483D01*
G03X1173494Y1466615I-200J0D01*
G02Y1469527I1664J1456D01*
G03X1173544Y1469659I-150J132D01*
G01Y1470281D01*
G02X1173747Y1470484I203J0D01*
G37*
G36*
G01X1191070D02*
X1193890D01*
G02X1194092Y1470281I-1J-203D01*
G01Y1469661D01*
G03X1194142Y1469529I200J0D01*
G02Y1466613I-1661J-1458D01*
G03X1194092Y1466481I150J-132D01*
G01Y1464543D01*
G03X1194142Y1464411I200J0D01*
G02Y1461495I-1661J-1458D01*
G03X1194092Y1461363I150J-132D01*
G01Y1460743D01*
G02X1193890Y1460540I-202J-1D01*
G01X1191070D01*
G02X1190868Y1460743I1J203D01*
G01Y1461363D01*
G03X1190818Y1461495I-200J0D01*
G02Y1464411I1661J1458D01*
G03X1190868Y1464543I-150J132D01*
G01Y1466481D01*
G03X1190818Y1466613I-200J0D01*
G02Y1469529I1661J1458D01*
G03X1190868Y1469661I-150J132D01*
G01Y1470281D01*
G02X1191070Y1470484I202J1D01*
G37*
G36*
G01X1312330D02*
X1315150D01*
G02X1315352Y1470281I-1J-203D01*
G01Y1469661D01*
G03X1315402Y1469529I200J0D01*
G02Y1466613I-1661J-1458D01*
G03X1315352Y1466481I150J-132D01*
G01Y1464543D01*
G03X1315402Y1464411I200J0D01*
G02Y1461495I-1661J-1458D01*
G03X1315352Y1461363I150J-132D01*
G01Y1460743D01*
G02X1315150Y1460540I-202J-1D01*
G01X1312330D01*
G02X1312128Y1460743I1J203D01*
G01Y1461363D01*
G03X1312078Y1461495I-200J0D01*
G02Y1464411I1661J1458D01*
G03X1312128Y1464543I-150J132D01*
G01Y1466481D01*
G03X1312078Y1466613I-200J0D01*
G02Y1469529I1661J1458D01*
G03X1312128Y1469661I-150J132D01*
G01Y1470281D01*
G02X1312330Y1470484I202J1D01*
G37*
G36*
G01X1329653D02*
X1332473D01*
G02X1332676Y1470281I0J-203D01*
G01Y1469659D01*
G03X1332726Y1469527I200J0D01*
G02Y1466615I-1664J-1456D01*
G03X1332676Y1466483I150J-132D01*
G01Y1464541D01*
G03X1332726Y1464409I200J0D01*
G02Y1461497I-1664J-1456D01*
G03X1332676Y1461365I150J-132D01*
G01Y1460743D01*
G02X1332473Y1460540I-203J0D01*
G01X1329653D01*
G02X1329450Y1460743I0J203D01*
G01Y1461365D01*
G03X1329400Y1461497I-200J0D01*
G02Y1464409I1664J1456D01*
G03X1329450Y1464541I-150J132D01*
G01Y1466483D01*
G03X1329400Y1466615I-200J0D01*
G02Y1469527I1664J1456D01*
G03X1329450Y1469659I-150J132D01*
G01Y1470281D01*
G02X1329653Y1470484I203J0D01*
G37*
G36*
G01X1346976D02*
X1349796D01*
G02X1349998Y1470281I-1J-203D01*
G01Y1469661D01*
G03X1350048Y1469529I200J0D01*
G02Y1466613I-1661J-1458D01*
G03X1349998Y1466481I150J-132D01*
G01Y1464543D01*
G03X1350048Y1464411I200J0D01*
G02Y1461495I-1661J-1458D01*
G03X1349998Y1461363I150J-132D01*
G01Y1460743D01*
G02X1349796Y1460540I-202J-1D01*
G01X1346976D01*
G02X1346774Y1460743I1J203D01*
G01Y1461363D01*
G03X1346724Y1461495I-200J0D01*
G02Y1464411I1661J1458D01*
G03X1346774Y1464543I-150J132D01*
G01Y1466481D01*
G03X1346724Y1466613I-200J0D01*
G02Y1469529I1661J1458D01*
G03X1346774Y1469661I-150J132D01*
G01Y1470281D01*
G02X1346976Y1470484I202J1D01*
G37*
G36*
G01X1364299D02*
X1367119D01*
G02X1367322Y1470281I0J-203D01*
G01Y1469659D01*
G03X1367372Y1469527I200J0D01*
G02Y1466615I-1664J-1456D01*
G03X1367322Y1466483I150J-132D01*
G01Y1464541D01*
G03X1367372Y1464409I200J0D01*
G02Y1461497I-1664J-1456D01*
G03X1367322Y1461365I150J-132D01*
G01Y1460743D01*
G02X1367119Y1460540I-203J0D01*
G01X1364299D01*
G02X1364096Y1460743I0J203D01*
G01Y1461365D01*
G03X1364046Y1461497I-200J0D01*
G02Y1464409I1664J1456D01*
G03X1364096Y1464541I-150J132D01*
G01Y1466483D01*
G03X1364046Y1466615I-200J0D01*
G02Y1469527I1664J1456D01*
G03X1364096Y1469659I-150J132D01*
G01Y1470281D01*
G02X1364299Y1470484I203J0D01*
G37*
G36*
G01X1485558D02*
X1488378D01*
G02X1488580Y1470281I-1J-203D01*
G01Y1469661D01*
G03X1488630Y1469529I200J0D01*
G02Y1466613I-1661J-1458D01*
G03X1488580Y1466481I150J-132D01*
G01Y1464543D01*
G03X1488630Y1464411I200J0D01*
G02Y1461495I-1661J-1458D01*
G03X1488580Y1461363I150J-132D01*
G01Y1460743D01*
G02X1488378Y1460540I-202J-1D01*
G01X1485558D01*
G02X1485356Y1460743I1J203D01*
G01Y1461363D01*
G03X1485306Y1461495I-200J0D01*
G02Y1464411I1661J1458D01*
G03X1485356Y1464543I-150J132D01*
G01Y1466481D01*
G03X1485306Y1466613I-200J0D01*
G02Y1469529I1661J1458D01*
G03X1485356Y1469661I-150J132D01*
G01Y1470281D01*
G02X1485558Y1470484I202J1D01*
G37*
G36*
G01X1502881D02*
X1505701D01*
G02X1505904Y1470281I0J-203D01*
G01Y1469659D01*
G03X1505954Y1469527I200J0D01*
G02Y1466615I-1664J-1456D01*
G03X1505904Y1466483I150J-132D01*
G01Y1464541D01*
G03X1505954Y1464409I200J0D01*
G02Y1461497I-1664J-1456D01*
G03X1505904Y1461365I150J-132D01*
G01Y1460743D01*
G02X1505701Y1460540I-203J0D01*
G01X1502881D01*
G02X1502678Y1460743I0J203D01*
G01Y1461365D01*
G03X1502628Y1461497I-200J0D01*
G02Y1464409I1664J1456D01*
G03X1502678Y1464541I-150J132D01*
G01Y1466483D01*
G03X1502628Y1466615I-200J0D01*
G02Y1469527I1664J1456D01*
G03X1502678Y1469659I-150J132D01*
G01Y1470281D01*
G02X1502881Y1470484I203J0D01*
G37*
G36*
G01X1520204D02*
X1523024D01*
G02X1523226Y1470281I-1J-203D01*
G01Y1469661D01*
G03X1523276Y1469529I200J0D01*
G02Y1466613I-1661J-1458D01*
G03X1523226Y1466481I150J-132D01*
G01Y1464543D01*
G03X1523276Y1464411I200J0D01*
G02Y1461495I-1661J-1458D01*
G03X1523226Y1461363I150J-132D01*
G01Y1460743D01*
G02X1523024Y1460540I-202J-1D01*
G01X1520204D01*
G02X1520002Y1460743I1J203D01*
G01Y1461363D01*
G03X1519952Y1461495I-200J0D01*
G02Y1464411I1661J1458D01*
G03X1520002Y1464543I-150J132D01*
G01Y1466481D01*
G03X1519952Y1466613I-200J0D01*
G02Y1469529I1661J1458D01*
G03X1520002Y1469661I-150J132D01*
G01Y1470281D01*
G02X1520204Y1470484I202J1D01*
G37*
G36*
G01X1537527D02*
X1540347D01*
G02X1540550Y1470281I0J-203D01*
G01Y1469659D01*
G03X1540600Y1469527I200J0D01*
G02Y1466615I-1664J-1456D01*
G03X1540550Y1466483I150J-132D01*
G01Y1464541D01*
G03X1540600Y1464409I200J0D01*
G02Y1461497I-1664J-1456D01*
G03X1540550Y1461365I150J-132D01*
G01Y1460743D01*
G02X1540347Y1460540I-203J0D01*
G01X1537527D01*
G02X1537324Y1460743I0J203D01*
G01Y1461365D01*
G03X1537274Y1461497I-200J0D01*
G02Y1464409I1664J1456D01*
G03X1537324Y1464541I-150J132D01*
G01Y1466483D01*
G03X1537274Y1466615I-200J0D01*
G02Y1469527I1664J1456D01*
G03X1537324Y1469659I-150J132D01*
G01Y1470281D01*
G02X1537527Y1470484I203J0D01*
G37*
G36*
G01X1693432D02*
X1696252D01*
G02X1696454Y1470281I-1J-203D01*
G01Y1469661D01*
G03X1696504Y1469529I200J0D01*
G02Y1466613I-1661J-1458D01*
G03X1696454Y1466481I150J-132D01*
G01Y1464543D01*
G03X1696504Y1464411I200J0D01*
G02Y1461495I-1661J-1458D01*
G03X1696454Y1461363I150J-132D01*
G01Y1460743D01*
G02X1696252Y1460540I-202J-1D01*
G01X1693432D01*
G02X1693230Y1460743I1J203D01*
G01Y1461363D01*
G03X1693180Y1461495I-200J0D01*
G02Y1464411I1661J1458D01*
G03X1693230Y1464543I-150J132D01*
G01Y1466481D01*
G03X1693180Y1466613I-200J0D01*
G02Y1469529I1661J1458D01*
G03X1693230Y1469661I-150J132D01*
G01Y1470281D01*
G02X1693432Y1470484I202J1D01*
G37*
G36*
G01X1710755D02*
X1713575D01*
G02X1713778Y1470281I0J-203D01*
G01Y1469659D01*
G03X1713828Y1469527I200J0D01*
G02Y1466615I-1664J-1456D01*
G03X1713778Y1466483I150J-132D01*
G01Y1464541D01*
G03X1713828Y1464409I200J0D01*
G02Y1461497I-1664J-1456D01*
G03X1713778Y1461365I150J-132D01*
G01Y1460743D01*
G02X1713575Y1460540I-203J0D01*
G01X1710755D01*
G02X1710552Y1460743I0J203D01*
G01Y1461365D01*
G03X1710502Y1461497I-200J0D01*
G02Y1464409I1664J1456D01*
G03X1710552Y1464541I-150J132D01*
G01Y1466483D01*
G03X1710502Y1466615I-200J0D01*
G02Y1469527I1664J1456D01*
G03X1710552Y1469659I-150J132D01*
G01Y1470281D01*
G02X1710755Y1470484I203J0D01*
G37*
G36*
G01X125795Y1481508D02*
X128615D01*
G02X128818Y1481305I0J-203D01*
G01Y1480683D01*
G03X128868Y1480551I200J0D01*
G02Y1477639I-1664J-1456D01*
G03X128818Y1477507I150J-132D01*
G01Y1475565D01*
G03X128868Y1475433I200J0D01*
G02Y1472521I-1664J-1456D01*
G03X128818Y1472389I150J-132D01*
G01Y1471767D01*
G02X128615Y1471564I-203J0D01*
G01X125795D01*
G02X125592Y1471767I0J203D01*
G01Y1472389D01*
G03X125542Y1472521I-200J0D01*
G02Y1475433I1664J1456D01*
G03X125592Y1475565I-150J132D01*
G01Y1477507D01*
G03X125542Y1477639I-200J0D01*
G02Y1480551I1664J1456D01*
G03X125592Y1480683I-150J132D01*
G01Y1481305D01*
G02X125795Y1481508I203J0D01*
G37*
G36*
G01X143118D02*
X145938D01*
G02X146140Y1481305I-1J-203D01*
G01Y1480685D01*
G03X146190Y1480553I200J0D01*
G02Y1477637I-1661J-1458D01*
G03X146140Y1477505I150J-132D01*
G01Y1475567D01*
G03X146190Y1475435I200J0D01*
G02Y1472519I-1661J-1458D01*
G03X146140Y1472387I150J-132D01*
G01Y1471767D01*
G02X145938Y1471564I-202J-1D01*
G01X143118D01*
G02X142916Y1471767I1J203D01*
G01Y1472387D01*
G03X142866Y1472519I-200J0D01*
G02Y1475435I1661J1458D01*
G03X142916Y1475567I-150J132D01*
G01Y1477505D01*
G03X142866Y1477637I-200J0D01*
G02Y1480553I1661J1458D01*
G03X142916Y1480685I-150J132D01*
G01Y1481305D01*
G02X143118Y1481508I202J1D01*
G37*
G36*
G01X160440D02*
X163260D01*
G02X163462Y1481305I-1J-203D01*
G01Y1480685D01*
G03X163512Y1480553I200J0D01*
G02Y1477637I-1661J-1458D01*
G03X163462Y1477505I150J-132D01*
G01Y1475567D01*
G03X163512Y1475435I200J0D01*
G02Y1472519I-1661J-1458D01*
G03X163462Y1472387I150J-132D01*
G01Y1471767D01*
G02X163260Y1471564I-202J-1D01*
G01X160440D01*
G02X160238Y1471767I1J203D01*
G01Y1472387D01*
G03X160188Y1472519I-200J0D01*
G02Y1475435I1661J1458D01*
G03X160238Y1475567I-150J132D01*
G01Y1477505D01*
G03X160188Y1477637I-200J0D01*
G02Y1480553I1661J1458D01*
G03X160238Y1480685I-150J132D01*
G01Y1481305D01*
G02X160440Y1481508I202J1D01*
G37*
G36*
G01X177763D02*
X180583D01*
G02X180786Y1481305I0J-203D01*
G01Y1480683D01*
G03X180836Y1480551I200J0D01*
G02Y1477639I-1664J-1456D01*
G03X180786Y1477507I150J-132D01*
G01Y1475565D01*
G03X180836Y1475433I200J0D01*
G02Y1472521I-1664J-1456D01*
G03X180786Y1472389I150J-132D01*
G01Y1471767D01*
G02X180583Y1471564I-203J0D01*
G01X177763D01*
G02X177560Y1471767I0J203D01*
G01Y1472389D01*
G03X177510Y1472521I-200J0D01*
G02Y1475433I1664J1456D01*
G03X177560Y1475565I-150J132D01*
G01Y1477507D01*
G03X177510Y1477639I-200J0D01*
G02Y1480551I1664J1456D01*
G03X177560Y1480683I-150J132D01*
G01Y1481305D01*
G02X177763Y1481508I203J0D01*
G37*
G36*
G01X281700D02*
X284520D01*
G02X284722Y1481305I-1J-203D01*
G01Y1480685D01*
G03X284772Y1480553I200J0D01*
G02Y1477637I-1661J-1458D01*
G03X284722Y1477505I150J-132D01*
G01Y1475567D01*
G03X284772Y1475435I200J0D01*
G02Y1472519I-1661J-1458D01*
G03X284722Y1472387I150J-132D01*
G01Y1471767D01*
G02X284520Y1471564I-202J-1D01*
G01X281700D01*
G02X281498Y1471767I1J203D01*
G01Y1472387D01*
G03X281448Y1472519I-200J0D01*
G02Y1475435I1661J1458D01*
G03X281498Y1475567I-150J132D01*
G01Y1477505D01*
G03X281448Y1477637I-200J0D01*
G02Y1480553I1661J1458D01*
G03X281498Y1480685I-150J132D01*
G01Y1481305D01*
G02X281700Y1481508I202J1D01*
G37*
G36*
G01X299023D02*
X301843D01*
G02X302046Y1481305I0J-203D01*
G01Y1480683D01*
G03X302096Y1480551I200J0D01*
G02Y1477639I-1664J-1456D01*
G03X302046Y1477507I150J-132D01*
G01Y1475565D01*
G03X302096Y1475433I200J0D01*
G02Y1472521I-1664J-1456D01*
G03X302046Y1472389I150J-132D01*
G01Y1471767D01*
G02X301843Y1471564I-203J0D01*
G01X299023D01*
G02X298820Y1471767I0J203D01*
G01Y1472389D01*
G03X298770Y1472521I-200J0D01*
G02Y1475433I1664J1456D01*
G03X298820Y1475565I-150J132D01*
G01Y1477507D01*
G03X298770Y1477639I-200J0D01*
G02Y1480551I1664J1456D01*
G03X298820Y1480683I-150J132D01*
G01Y1481305D01*
G02X299023Y1481508I203J0D01*
G37*
G36*
G01X454929D02*
X457749D01*
G02X457952Y1481305I0J-203D01*
G01Y1480683D01*
G03X458002Y1480551I200J0D01*
G02Y1477639I-1664J-1456D01*
G03X457952Y1477507I150J-132D01*
G01Y1475565D01*
G03X458002Y1475433I200J0D01*
G02Y1472521I-1664J-1456D01*
G03X457952Y1472389I150J-132D01*
G01Y1471767D01*
G02X457749Y1471564I-203J0D01*
G01X454929D01*
G02X454726Y1471767I0J203D01*
G01Y1472389D01*
G03X454676Y1472521I-200J0D01*
G02Y1475433I1664J1456D01*
G03X454726Y1475565I-150J132D01*
G01Y1477507D01*
G03X454676Y1477639I-200J0D01*
G02Y1480551I1664J1456D01*
G03X454726Y1480683I-150J132D01*
G01Y1481305D01*
G02X454929Y1481508I203J0D01*
G37*
G36*
G01X472252D02*
X475072D01*
G02X475274Y1481305I-1J-203D01*
G01Y1480685D01*
G03X475324Y1480553I200J0D01*
G02Y1477637I-1661J-1458D01*
G03X475274Y1477505I150J-132D01*
G01Y1475567D01*
G03X475324Y1475435I200J0D01*
G02Y1472519I-1661J-1458D01*
G03X475274Y1472387I150J-132D01*
G01Y1471767D01*
G02X475072Y1471564I-202J-1D01*
G01X472252D01*
G02X472050Y1471767I1J203D01*
G01Y1472387D01*
G03X472000Y1472519I-200J0D01*
G02Y1475435I1661J1458D01*
G03X472050Y1475567I-150J132D01*
G01Y1477505D01*
G03X472000Y1477637I-200J0D01*
G02Y1480553I1661J1458D01*
G03X472050Y1480685I-150J132D01*
G01Y1481305D01*
G02X472252Y1481508I202J1D01*
G37*
G36*
G01X489575D02*
X492395D01*
G02X492598Y1481305I0J-203D01*
G01Y1480683D01*
G03X492648Y1480551I200J0D01*
G02Y1477639I-1664J-1456D01*
G03X492598Y1477507I150J-132D01*
G01Y1475565D01*
G03X492648Y1475433I200J0D01*
G02Y1472521I-1664J-1456D01*
G03X492598Y1472389I150J-132D01*
G01Y1471767D01*
G02X492395Y1471564I-203J0D01*
G01X489575D01*
G02X489372Y1471767I0J203D01*
G01Y1472389D01*
G03X489322Y1472521I-200J0D01*
G02Y1475433I1664J1456D01*
G03X489372Y1475565I-150J132D01*
G01Y1477507D01*
G03X489322Y1477639I-200J0D01*
G02Y1480551I1664J1456D01*
G03X489372Y1480683I-150J132D01*
G01Y1481305D01*
G02X489575Y1481508I203J0D01*
G37*
G36*
G01X506897D02*
X509717D01*
G02X509920Y1481305I0J-203D01*
G01Y1480683D01*
G03X509970Y1480551I200J0D01*
G02Y1477639I-1664J-1456D01*
G03X509920Y1477507I150J-132D01*
G01Y1475565D01*
G03X509970Y1475433I200J0D01*
G02Y1472521I-1664J-1456D01*
G03X509920Y1472389I150J-132D01*
G01Y1471767D01*
G02X509717Y1471564I-203J0D01*
G01X506897D01*
G02X506694Y1471767I0J203D01*
G01Y1472389D01*
G03X506644Y1472521I-200J0D01*
G02Y1475433I1664J1456D01*
G03X506694Y1475565I-150J132D01*
G01Y1477507D01*
G03X506644Y1477639I-200J0D01*
G02Y1480551I1664J1456D01*
G03X506694Y1480683I-150J132D01*
G01Y1481305D01*
G02X506897Y1481508I203J0D01*
G37*
G36*
G01X645480D02*
X648300D01*
G02X648502Y1481305I-1J-203D01*
G01Y1480685D01*
G03X648552Y1480553I200J0D01*
G02Y1477637I-1661J-1458D01*
G03X648502Y1477505I150J-132D01*
G01Y1475567D01*
G03X648552Y1475435I200J0D01*
G02Y1472519I-1661J-1458D01*
G03X648502Y1472387I150J-132D01*
G01Y1471767D01*
G02X648300Y1471564I-202J-1D01*
G01X645480D01*
G02X645278Y1471767I1J203D01*
G01Y1472387D01*
G03X645228Y1472519I-200J0D01*
G02Y1475435I1661J1458D01*
G03X645278Y1475567I-150J132D01*
G01Y1477505D01*
G03X645228Y1477637I-200J0D01*
G02Y1480553I1661J1458D01*
G03X645278Y1480685I-150J132D01*
G01Y1481305D01*
G02X645480Y1481508I202J1D01*
G37*
G36*
G01X662803D02*
X665623D01*
G02X665826Y1481305I0J-203D01*
G01Y1480683D01*
G03X665876Y1480551I200J0D01*
G02Y1477639I-1664J-1456D01*
G03X665826Y1477507I150J-132D01*
G01Y1475565D01*
G03X665876Y1475433I200J0D01*
G02Y1472521I-1664J-1456D01*
G03X665826Y1472389I150J-132D01*
G01Y1471767D01*
G02X665623Y1471564I-203J0D01*
G01X662803D01*
G02X662600Y1471767I0J203D01*
G01Y1472389D01*
G03X662550Y1472521I-200J0D01*
G02Y1475433I1664J1456D01*
G03X662600Y1475565I-150J132D01*
G01Y1477507D01*
G03X662550Y1477639I-200J0D01*
G02Y1480551I1664J1456D01*
G03X662600Y1480683I-150J132D01*
G01Y1481305D01*
G02X662803Y1481508I203J0D01*
G37*
G36*
G01X680125D02*
X682945D01*
G02X683148Y1481305I0J-203D01*
G01Y1480683D01*
G03X683198Y1480551I200J0D01*
G02Y1477639I-1664J-1456D01*
G03X683148Y1477507I150J-132D01*
G01Y1475565D01*
G03X683198Y1475433I200J0D01*
G02Y1472521I-1664J-1456D01*
G03X683148Y1472389I150J-132D01*
G01Y1471767D01*
G02X682945Y1471564I-203J0D01*
G01X680125D01*
G02X679922Y1471767I0J203D01*
G01Y1472389D01*
G03X679872Y1472521I-200J0D01*
G02Y1475433I1664J1456D01*
G03X679922Y1475565I-150J132D01*
G01Y1477507D01*
G03X679872Y1477639I-200J0D01*
G02Y1480551I1664J1456D01*
G03X679922Y1480683I-150J132D01*
G01Y1481305D01*
G02X680125Y1481508I203J0D01*
G37*
G36*
G01X1165086D02*
X1167906D01*
G02X1168108Y1481305I-1J-203D01*
G01Y1480685D01*
G03X1168158Y1480553I200J0D01*
G02Y1477637I-1661J-1458D01*
G03X1168108Y1477505I150J-132D01*
G01Y1475567D01*
G03X1168158Y1475435I200J0D01*
G02Y1472519I-1661J-1458D01*
G03X1168108Y1472387I150J-132D01*
G01Y1471767D01*
G02X1167906Y1471564I-202J-1D01*
G01X1165086D01*
G02X1164884Y1471767I1J203D01*
G01Y1472387D01*
G03X1164834Y1472519I-200J0D01*
G02Y1475435I1661J1458D01*
G03X1164884Y1475567I-150J132D01*
G01Y1477505D01*
G03X1164834Y1477637I-200J0D01*
G02Y1480553I1661J1458D01*
G03X1164884Y1480685I-150J132D01*
G01Y1481305D01*
G02X1165086Y1481508I202J1D01*
G37*
G36*
G01X1182408D02*
X1185228D01*
G02X1185430Y1481305I-1J-203D01*
G01Y1480685D01*
G03X1185480Y1480553I200J0D01*
G02Y1477637I-1661J-1458D01*
G03X1185430Y1477505I150J-132D01*
G01Y1475567D01*
G03X1185480Y1475435I200J0D01*
G02Y1472519I-1661J-1458D01*
G03X1185430Y1472387I150J-132D01*
G01Y1471767D01*
G02X1185228Y1471564I-202J-1D01*
G01X1182408D01*
G02X1182206Y1471767I1J203D01*
G01Y1472387D01*
G03X1182156Y1472519I-200J0D01*
G02Y1475435I1661J1458D01*
G03X1182206Y1475567I-150J132D01*
G01Y1477505D01*
G03X1182156Y1477637I-200J0D01*
G02Y1480553I1661J1458D01*
G03X1182206Y1480685I-150J132D01*
G01Y1481305D01*
G02X1182408Y1481508I202J1D01*
G37*
G36*
G01X1303669D02*
X1306489D01*
G02X1306692Y1481305I0J-203D01*
G01Y1480683D01*
G03X1306742Y1480551I200J0D01*
G02Y1477639I-1664J-1456D01*
G03X1306692Y1477507I150J-132D01*
G01Y1475565D01*
G03X1306742Y1475433I200J0D01*
G02Y1472521I-1664J-1456D01*
G03X1306692Y1472389I150J-132D01*
G01Y1471767D01*
G02X1306489Y1471564I-203J0D01*
G01X1303669D01*
G02X1303466Y1471767I0J203D01*
G01Y1472389D01*
G03X1303416Y1472521I-200J0D01*
G02Y1475433I1664J1456D01*
G03X1303466Y1475565I-150J132D01*
G01Y1477507D01*
G03X1303416Y1477639I-200J0D01*
G02Y1480551I1664J1456D01*
G03X1303466Y1480683I-150J132D01*
G01Y1481305D01*
G02X1303669Y1481508I203J0D01*
G37*
G36*
G01X1320992D02*
X1323812D01*
G02X1324014Y1481305I-1J-203D01*
G01Y1480685D01*
G03X1324064Y1480553I200J0D01*
G02Y1477637I-1661J-1458D01*
G03X1324014Y1477505I150J-132D01*
G01Y1475567D01*
G03X1324064Y1475435I200J0D01*
G02Y1472519I-1661J-1458D01*
G03X1324014Y1472387I150J-132D01*
G01Y1471767D01*
G02X1323812Y1471564I-202J-1D01*
G01X1320992D01*
G02X1320790Y1471767I1J203D01*
G01Y1472387D01*
G03X1320740Y1472519I-200J0D01*
G02Y1475435I1661J1458D01*
G03X1320790Y1475567I-150J132D01*
G01Y1477505D01*
G03X1320740Y1477637I-200J0D01*
G02Y1480553I1661J1458D01*
G03X1320790Y1480685I-150J132D01*
G01Y1481305D01*
G02X1320992Y1481508I202J1D01*
G37*
G36*
G01X1338315D02*
X1341135D01*
G02X1341338Y1481305I0J-203D01*
G01Y1480683D01*
G03X1341388Y1480551I200J0D01*
G02Y1477639I-1664J-1456D01*
G03X1341338Y1477507I150J-132D01*
G01Y1475565D01*
G03X1341388Y1475433I200J0D01*
G02Y1472521I-1664J-1456D01*
G03X1341338Y1472389I150J-132D01*
G01Y1471767D01*
G02X1341135Y1471564I-203J0D01*
G01X1338315D01*
G02X1338112Y1471767I0J203D01*
G01Y1472389D01*
G03X1338062Y1472521I-200J0D01*
G02Y1475433I1664J1456D01*
G03X1338112Y1475565I-150J132D01*
G01Y1477507D01*
G03X1338062Y1477639I-200J0D01*
G02Y1480551I1664J1456D01*
G03X1338112Y1480683I-150J132D01*
G01Y1481305D01*
G02X1338315Y1481508I203J0D01*
G37*
G36*
G01X1355637D02*
X1358457D01*
G02X1358660Y1481305I0J-203D01*
G01Y1480683D01*
G03X1358710Y1480551I200J0D01*
G02Y1477639I-1664J-1456D01*
G03X1358660Y1477507I150J-132D01*
G01Y1475565D01*
G03X1358710Y1475433I200J0D01*
G02Y1472521I-1664J-1456D01*
G03X1358660Y1472389I150J-132D01*
G01Y1471767D01*
G02X1358457Y1471564I-203J0D01*
G01X1355637D01*
G02X1355434Y1471767I0J203D01*
G01Y1472389D01*
G03X1355384Y1472521I-200J0D01*
G02Y1475433I1664J1456D01*
G03X1355434Y1475565I-150J132D01*
G01Y1477507D01*
G03X1355384Y1477639I-200J0D01*
G02Y1480551I1664J1456D01*
G03X1355434Y1480683I-150J132D01*
G01Y1481305D01*
G02X1355637Y1481508I203J0D01*
G37*
G36*
G01X1476897D02*
X1479717D01*
G02X1479920Y1481305I0J-203D01*
G01Y1480683D01*
G03X1479970Y1480551I200J0D01*
G02Y1477639I-1664J-1456D01*
G03X1479920Y1477507I150J-132D01*
G01Y1475565D01*
G03X1479970Y1475433I200J0D01*
G02Y1472521I-1664J-1456D01*
G03X1479920Y1472389I150J-132D01*
G01Y1471767D01*
G02X1479717Y1471564I-203J0D01*
G01X1476897D01*
G02X1476694Y1471767I0J203D01*
G01Y1472389D01*
G03X1476644Y1472521I-200J0D01*
G02Y1475433I1664J1456D01*
G03X1476694Y1475565I-150J132D01*
G01Y1477507D01*
G03X1476644Y1477639I-200J0D01*
G02Y1480551I1664J1456D01*
G03X1476694Y1480683I-150J132D01*
G01Y1481305D01*
G02X1476897Y1481508I203J0D01*
G37*
G36*
G01X1494220D02*
X1497040D01*
G02X1497242Y1481305I-1J-203D01*
G01Y1480685D01*
G03X1497292Y1480553I200J0D01*
G02Y1477637I-1661J-1458D01*
G03X1497242Y1477505I150J-132D01*
G01Y1475567D01*
G03X1497292Y1475435I200J0D01*
G02Y1472519I-1661J-1458D01*
G03X1497242Y1472387I150J-132D01*
G01Y1471767D01*
G02X1497040Y1471564I-202J-1D01*
G01X1494220D01*
G02X1494018Y1471767I1J203D01*
G01Y1472387D01*
G03X1493968Y1472519I-200J0D01*
G02Y1475435I1661J1458D01*
G03X1494018Y1475567I-150J132D01*
G01Y1477505D01*
G03X1493968Y1477637I-200J0D01*
G02Y1480553I1661J1458D01*
G03X1494018Y1480685I-150J132D01*
G01Y1481305D01*
G02X1494220Y1481508I202J1D01*
G37*
G36*
G01X1511543D02*
X1514363D01*
G02X1514566Y1481305I0J-203D01*
G01Y1480683D01*
G03X1514616Y1480551I200J0D01*
G02Y1477639I-1664J-1456D01*
G03X1514566Y1477507I150J-132D01*
G01Y1475565D01*
G03X1514616Y1475433I200J0D01*
G02Y1472521I-1664J-1456D01*
G03X1514566Y1472389I150J-132D01*
G01Y1471767D01*
G02X1514363Y1471564I-203J0D01*
G01X1511543D01*
G02X1511340Y1471767I0J203D01*
G01Y1472389D01*
G03X1511290Y1472521I-200J0D01*
G02Y1475433I1664J1456D01*
G03X1511340Y1475565I-150J132D01*
G01Y1477507D01*
G03X1511290Y1477639I-200J0D01*
G02Y1480551I1664J1456D01*
G03X1511340Y1480683I-150J132D01*
G01Y1481305D01*
G02X1511543Y1481508I203J0D01*
G37*
G36*
G01X1528865D02*
X1531685D01*
G02X1531888Y1481305I0J-203D01*
G01Y1480683D01*
G03X1531938Y1480551I200J0D01*
G02Y1477639I-1664J-1456D01*
G03X1531888Y1477507I150J-132D01*
G01Y1475565D01*
G03X1531938Y1475433I200J0D01*
G02Y1472521I-1664J-1456D01*
G03X1531888Y1472389I150J-132D01*
G01Y1471767D01*
G02X1531685Y1471564I-203J0D01*
G01X1528865D01*
G02X1528662Y1471767I0J203D01*
G01Y1472389D01*
G03X1528612Y1472521I-200J0D01*
G02Y1475433I1664J1456D01*
G03X1528662Y1475565I-150J132D01*
G01Y1477507D01*
G03X1528612Y1477639I-200J0D01*
G02Y1480551I1664J1456D01*
G03X1528662Y1480683I-150J132D01*
G01Y1481305D01*
G02X1528865Y1481508I203J0D01*
G37*
G36*
G01X1684771D02*
X1687591D01*
G02X1687794Y1481305I0J-203D01*
G01Y1480683D01*
G03X1687844Y1480551I200J0D01*
G02Y1477639I-1664J-1456D01*
G03X1687794Y1477507I150J-132D01*
G01Y1475565D01*
G03X1687844Y1475433I200J0D01*
G02Y1472521I-1664J-1456D01*
G03X1687794Y1472389I150J-132D01*
G01Y1471767D01*
G02X1687591Y1471564I-203J0D01*
G01X1684771D01*
G02X1684568Y1471767I0J203D01*
G01Y1472389D01*
G03X1684518Y1472521I-200J0D01*
G02Y1475433I1664J1456D01*
G03X1684568Y1475565I-150J132D01*
G01Y1477507D01*
G03X1684518Y1477639I-200J0D01*
G02Y1480551I1664J1456D01*
G03X1684568Y1480683I-150J132D01*
G01Y1481305D01*
G02X1684771Y1481508I203J0D01*
G37*
G36*
G01X1702093D02*
X1704913D01*
G02X1705116Y1481305I0J-203D01*
G01Y1480683D01*
G03X1705166Y1480551I200J0D01*
G02Y1477639I-1664J-1456D01*
G03X1705116Y1477507I150J-132D01*
G01Y1475565D01*
G03X1705166Y1475433I200J0D01*
G02Y1472521I-1664J-1456D01*
G03X1705116Y1472389I150J-132D01*
G01Y1471767D01*
G02X1704913Y1471564I-203J0D01*
G01X1702093D01*
G02X1701890Y1471767I0J203D01*
G01Y1472389D01*
G03X1701840Y1472521I-200J0D01*
G02Y1475433I1664J1456D01*
G03X1701890Y1475565I-150J132D01*
G01Y1477507D01*
G03X1701840Y1477639I-200J0D01*
G02Y1480551I1664J1456D01*
G03X1701890Y1480683I-150J132D01*
G01Y1481305D01*
G02X1702093Y1481508I203J0D01*
G37*
G36*
G01X134456Y1485838D02*
X137276D01*
G02X137478Y1485635I-1J-203D01*
G01Y1485016D01*
G03X137528Y1484884I200J0D01*
G02Y1481968I-1661J-1458D01*
G03X137478Y1481836I150J-132D01*
G01Y1479898D01*
G03X137528Y1479766I200J0D01*
G02Y1476850I-1661J-1458D01*
G03X137478Y1476718I150J-132D01*
G01Y1476097D01*
G02X137276Y1475894I-202J-1D01*
G01X134456D01*
G02X134254Y1476097I1J203D01*
G01Y1476718D01*
G03X134204Y1476850I-200J0D01*
G02Y1479766I1661J1458D01*
G03X134254Y1479898I-150J132D01*
G01Y1481836D01*
G03X134204Y1481968I-200J0D01*
G02Y1484884I1661J1458D01*
G03X134254Y1485016I-150J132D01*
G01Y1485635D01*
G02X134456Y1485838I202J1D01*
G37*
G36*
G01X151779D02*
X154599D01*
G02X154802Y1485635I0J-203D01*
G01Y1485014D01*
G03X154852Y1484882I200J0D01*
G02Y1481970I-1664J-1456D01*
G03X154802Y1481838I150J-132D01*
G01Y1479896D01*
G03X154852Y1479764I200J0D01*
G02Y1476852I-1664J-1456D01*
G03X154802Y1476720I150J-132D01*
G01Y1476097D01*
G02X154599Y1475894I-203J0D01*
G01X151779D01*
G02X151576Y1476097I0J203D01*
G01Y1476720D01*
G03X151526Y1476852I-200J0D01*
G02Y1479764I1664J1456D01*
G03X151576Y1479896I-150J132D01*
G01Y1481838D01*
G03X151526Y1481970I-200J0D01*
G02Y1484882I1664J1456D01*
G03X151576Y1485014I-150J132D01*
G01Y1485635D01*
G02X151779Y1485838I203J0D01*
G37*
G36*
G01X169102D02*
X171922D01*
G02X172124Y1485635I-1J-203D01*
G01Y1485016D01*
G03X172174Y1484884I200J0D01*
G02Y1481968I-1661J-1458D01*
G03X172124Y1481836I150J-132D01*
G01Y1479898D01*
G03X172174Y1479766I200J0D01*
G02Y1476850I-1661J-1458D01*
G03X172124Y1476718I150J-132D01*
G01Y1476097D01*
G02X171922Y1475894I-202J-1D01*
G01X169102D01*
G02X168900Y1476097I1J203D01*
G01Y1476718D01*
G03X168850Y1476850I-200J0D01*
G02Y1479766I1661J1458D01*
G03X168900Y1479898I-150J132D01*
G01Y1481836D01*
G03X168850Y1481968I-200J0D01*
G02Y1484884I1661J1458D01*
G03X168900Y1485016I-150J132D01*
G01Y1485635D01*
G02X169102Y1485838I202J1D01*
G37*
G36*
G01X290361D02*
X293181D01*
G02X293384Y1485635I0J-203D01*
G01Y1485014D01*
G03X293434Y1484882I200J0D01*
G02Y1481970I-1664J-1456D01*
G03X293384Y1481838I150J-132D01*
G01Y1479896D01*
G03X293434Y1479764I200J0D01*
G02Y1476852I-1664J-1456D01*
G03X293384Y1476720I150J-132D01*
G01Y1476097D01*
G02X293181Y1475894I-203J0D01*
G01X290361D01*
G02X290158Y1476097I0J203D01*
G01Y1476720D01*
G03X290108Y1476852I-200J0D01*
G02Y1479764I1664J1456D01*
G03X290158Y1479896I-150J132D01*
G01Y1481838D01*
G03X290108Y1481970I-200J0D01*
G02Y1484882I1664J1456D01*
G03X290158Y1485014I-150J132D01*
G01Y1485635D01*
G02X290361Y1485838I203J0D01*
G37*
G36*
G01X463590D02*
X466410D01*
G02X466612Y1485635I-1J-203D01*
G01Y1485016D01*
G03X466662Y1484884I200J0D01*
G02Y1481968I-1661J-1458D01*
G03X466612Y1481836I150J-132D01*
G01Y1479898D01*
G03X466662Y1479766I200J0D01*
G02Y1476850I-1661J-1458D01*
G03X466612Y1476718I150J-132D01*
G01Y1476097D01*
G02X466410Y1475894I-202J-1D01*
G01X463590D01*
G02X463388Y1476097I1J203D01*
G01Y1476718D01*
G03X463338Y1476850I-200J0D01*
G02Y1479766I1661J1458D01*
G03X463388Y1479898I-150J132D01*
G01Y1481836D01*
G03X463338Y1481968I-200J0D01*
G02Y1484884I1661J1458D01*
G03X463388Y1485016I-150J132D01*
G01Y1485635D01*
G02X463590Y1485838I202J1D01*
G37*
G36*
G01X480913D02*
X483733D01*
G02X483936Y1485635I0J-203D01*
G01Y1485014D01*
G03X483986Y1484882I200J0D01*
G02Y1481970I-1664J-1456D01*
G03X483936Y1481838I150J-132D01*
G01Y1479896D01*
G03X483986Y1479764I200J0D01*
G02Y1476852I-1664J-1456D01*
G03X483936Y1476720I150J-132D01*
G01Y1476097D01*
G02X483733Y1475894I-203J0D01*
G01X480913D01*
G02X480710Y1476097I0J203D01*
G01Y1476720D01*
G03X480660Y1476852I-200J0D01*
G02Y1479764I1664J1456D01*
G03X480710Y1479896I-150J132D01*
G01Y1481838D01*
G03X480660Y1481970I-200J0D01*
G02Y1484882I1664J1456D01*
G03X480710Y1485014I-150J132D01*
G01Y1485635D01*
G02X480913Y1485838I203J0D01*
G37*
G36*
G01X498236D02*
X501056D01*
G02X501258Y1485635I-1J-203D01*
G01Y1485016D01*
G03X501308Y1484884I200J0D01*
G02Y1481968I-1661J-1458D01*
G03X501258Y1481836I150J-132D01*
G01Y1479898D01*
G03X501308Y1479766I200J0D01*
G02Y1476850I-1661J-1458D01*
G03X501258Y1476718I150J-132D01*
G01Y1476097D01*
G02X501056Y1475894I-202J-1D01*
G01X498236D01*
G02X498034Y1476097I1J203D01*
G01Y1476718D01*
G03X497984Y1476850I-200J0D01*
G02Y1479766I1661J1458D01*
G03X498034Y1479898I-150J132D01*
G01Y1481836D01*
G03X497984Y1481968I-200J0D01*
G02Y1484884I1661J1458D01*
G03X498034Y1485016I-150J132D01*
G01Y1485635D01*
G02X498236Y1485838I202J1D01*
G37*
G36*
G01X515559D02*
X518379D01*
G02X518582Y1485635I0J-203D01*
G01Y1485014D01*
G03X518632Y1484882I200J0D01*
G02Y1481970I-1664J-1456D01*
G03X518582Y1481838I150J-132D01*
G01Y1479896D01*
G03X518632Y1479764I200J0D01*
G02Y1476852I-1664J-1456D01*
G03X518582Y1476720I150J-132D01*
G01Y1476097D01*
G02X518379Y1475894I-203J0D01*
G01X515559D01*
G02X515356Y1476097I0J203D01*
G01Y1476720D01*
G03X515306Y1476852I-200J0D01*
G02Y1479764I1664J1456D01*
G03X515356Y1479896I-150J132D01*
G01Y1481838D01*
G03X515306Y1481970I-200J0D01*
G02Y1484882I1664J1456D01*
G03X515356Y1485014I-150J132D01*
G01Y1485635D01*
G02X515559Y1485838I203J0D01*
G37*
G36*
G01X654141D02*
X656961D01*
G02X657164Y1485635I0J-203D01*
G01Y1485014D01*
G03X657214Y1484882I200J0D01*
G02Y1481970I-1664J-1456D01*
G03X657164Y1481838I150J-132D01*
G01Y1479896D01*
G03X657214Y1479764I200J0D01*
G02Y1476852I-1664J-1456D01*
G03X657164Y1476720I150J-132D01*
G01Y1476097D01*
G02X656961Y1475894I-203J0D01*
G01X654141D01*
G02X653938Y1476097I0J203D01*
G01Y1476720D01*
G03X653888Y1476852I-200J0D01*
G02Y1479764I1664J1456D01*
G03X653938Y1479896I-150J132D01*
G01Y1481838D01*
G03X653888Y1481970I-200J0D01*
G02Y1484882I1664J1456D01*
G03X653938Y1485014I-150J132D01*
G01Y1485635D01*
G02X654141Y1485838I203J0D01*
G37*
G36*
G01X671464D02*
X674284D01*
G02X674486Y1485635I-1J-203D01*
G01Y1485016D01*
G03X674536Y1484884I200J0D01*
G02Y1481968I-1661J-1458D01*
G03X674486Y1481836I150J-132D01*
G01Y1479898D01*
G03X674536Y1479766I200J0D01*
G02Y1476850I-1661J-1458D01*
G03X674486Y1476718I150J-132D01*
G01Y1476097D01*
G02X674284Y1475894I-202J-1D01*
G01X671464D01*
G02X671262Y1476097I1J203D01*
G01Y1476718D01*
G03X671212Y1476850I-200J0D01*
G02Y1479766I1661J1458D01*
G03X671262Y1479898I-150J132D01*
G01Y1481836D01*
G03X671212Y1481968I-200J0D01*
G02Y1484884I1661J1458D01*
G03X671262Y1485016I-150J132D01*
G01Y1485635D01*
G02X671464Y1485838I202J1D01*
G37*
G36*
G01X688787D02*
X691607D01*
G02X691810Y1485635I0J-203D01*
G01Y1485014D01*
G03X691860Y1484882I200J0D01*
G02Y1481970I-1664J-1456D01*
G03X691810Y1481838I150J-132D01*
G01Y1479896D01*
G03X691860Y1479764I200J0D01*
G02Y1476852I-1664J-1456D01*
G03X691810Y1476720I150J-132D01*
G01Y1476097D01*
G02X691607Y1475894I-203J0D01*
G01X688787D01*
G02X688584Y1476097I0J203D01*
G01Y1476720D01*
G03X688534Y1476852I-200J0D01*
G02Y1479764I1664J1456D01*
G03X688584Y1479896I-150J132D01*
G01Y1481838D01*
G03X688534Y1481970I-200J0D01*
G02Y1484882I1664J1456D01*
G03X688584Y1485014I-150J132D01*
G01Y1485635D01*
G02X688787Y1485838I203J0D01*
G37*
G36*
G01X1173747D02*
X1176567D01*
G02X1176770Y1485635I0J-203D01*
G01Y1485014D01*
G03X1176820Y1484882I200J0D01*
G02Y1481970I-1664J-1456D01*
G03X1176770Y1481838I150J-132D01*
G01Y1479896D01*
G03X1176820Y1479764I200J0D01*
G02Y1476852I-1664J-1456D01*
G03X1176770Y1476720I150J-132D01*
G01Y1476097D01*
G02X1176567Y1475894I-203J0D01*
G01X1173747D01*
G02X1173544Y1476097I0J203D01*
G01Y1476720D01*
G03X1173494Y1476852I-200J0D01*
G02Y1479764I1664J1456D01*
G03X1173544Y1479896I-150J132D01*
G01Y1481838D01*
G03X1173494Y1481970I-200J0D01*
G02Y1484882I1664J1456D01*
G03X1173544Y1485014I-150J132D01*
G01Y1485635D01*
G02X1173747Y1485838I203J0D01*
G37*
G36*
G01X1191070D02*
X1193890D01*
G02X1194092Y1485635I-1J-203D01*
G01Y1485016D01*
G03X1194142Y1484884I200J0D01*
G02Y1481968I-1661J-1458D01*
G03X1194092Y1481836I150J-132D01*
G01Y1479898D01*
G03X1194142Y1479766I200J0D01*
G02Y1476850I-1661J-1458D01*
G03X1194092Y1476718I150J-132D01*
G01Y1476097D01*
G02X1193890Y1475894I-202J-1D01*
G01X1191070D01*
G02X1190868Y1476097I1J203D01*
G01Y1476718D01*
G03X1190818Y1476850I-200J0D01*
G02Y1479766I1661J1458D01*
G03X1190868Y1479898I-150J132D01*
G01Y1481836D01*
G03X1190818Y1481968I-200J0D01*
G02Y1484884I1661J1458D01*
G03X1190868Y1485016I-150J132D01*
G01Y1485635D01*
G02X1191070Y1485838I202J1D01*
G37*
G36*
G01X1312330D02*
X1315150D01*
G02X1315352Y1485635I-1J-203D01*
G01Y1485016D01*
G03X1315402Y1484884I200J0D01*
G02Y1481968I-1661J-1458D01*
G03X1315352Y1481836I150J-132D01*
G01Y1479898D01*
G03X1315402Y1479766I200J0D01*
G02Y1476850I-1661J-1458D01*
G03X1315352Y1476718I150J-132D01*
G01Y1476097D01*
G02X1315150Y1475894I-202J-1D01*
G01X1312330D01*
G02X1312128Y1476097I1J203D01*
G01Y1476718D01*
G03X1312078Y1476850I-200J0D01*
G02Y1479766I1661J1458D01*
G03X1312128Y1479898I-150J132D01*
G01Y1481836D01*
G03X1312078Y1481968I-200J0D01*
G02Y1484884I1661J1458D01*
G03X1312128Y1485016I-150J132D01*
G01Y1485635D01*
G02X1312330Y1485838I202J1D01*
G37*
G36*
G01X1329653D02*
X1332473D01*
G02X1332676Y1485635I0J-203D01*
G01Y1485014D01*
G03X1332726Y1484882I200J0D01*
G02Y1481970I-1664J-1456D01*
G03X1332676Y1481838I150J-132D01*
G01Y1479896D01*
G03X1332726Y1479764I200J0D01*
G02Y1476852I-1664J-1456D01*
G03X1332676Y1476720I150J-132D01*
G01Y1476097D01*
G02X1332473Y1475894I-203J0D01*
G01X1329653D01*
G02X1329450Y1476097I0J203D01*
G01Y1476720D01*
G03X1329400Y1476852I-200J0D01*
G02Y1479764I1664J1456D01*
G03X1329450Y1479896I-150J132D01*
G01Y1481838D01*
G03X1329400Y1481970I-200J0D01*
G02Y1484882I1664J1456D01*
G03X1329450Y1485014I-150J132D01*
G01Y1485635D01*
G02X1329653Y1485838I203J0D01*
G37*
G36*
G01X1346976D02*
X1349796D01*
G02X1349998Y1485635I-1J-203D01*
G01Y1485016D01*
G03X1350048Y1484884I200J0D01*
G02Y1481968I-1661J-1458D01*
G03X1349998Y1481836I150J-132D01*
G01Y1479898D01*
G03X1350048Y1479766I200J0D01*
G02Y1476850I-1661J-1458D01*
G03X1349998Y1476718I150J-132D01*
G01Y1476097D01*
G02X1349796Y1475894I-202J-1D01*
G01X1346976D01*
G02X1346774Y1476097I1J203D01*
G01Y1476718D01*
G03X1346724Y1476850I-200J0D01*
G02Y1479766I1661J1458D01*
G03X1346774Y1479898I-150J132D01*
G01Y1481836D01*
G03X1346724Y1481968I-200J0D01*
G02Y1484884I1661J1458D01*
G03X1346774Y1485016I-150J132D01*
G01Y1485635D01*
G02X1346976Y1485838I202J1D01*
G37*
G36*
G01X1364299D02*
X1367119D01*
G02X1367322Y1485635I0J-203D01*
G01Y1485014D01*
G03X1367372Y1484882I200J0D01*
G02Y1481970I-1664J-1456D01*
G03X1367322Y1481838I150J-132D01*
G01Y1479896D01*
G03X1367372Y1479764I200J0D01*
G02Y1476852I-1664J-1456D01*
G03X1367322Y1476720I150J-132D01*
G01Y1476097D01*
G02X1367119Y1475894I-203J0D01*
G01X1364299D01*
G02X1364096Y1476097I0J203D01*
G01Y1476720D01*
G03X1364046Y1476852I-200J0D01*
G02Y1479764I1664J1456D01*
G03X1364096Y1479896I-150J132D01*
G01Y1481838D01*
G03X1364046Y1481970I-200J0D01*
G02Y1484882I1664J1456D01*
G03X1364096Y1485014I-150J132D01*
G01Y1485635D01*
G02X1364299Y1485838I203J0D01*
G37*
G36*
G01X1485558D02*
X1488378D01*
G02X1488580Y1485635I-1J-203D01*
G01Y1485016D01*
G03X1488630Y1484884I200J0D01*
G02Y1481968I-1661J-1458D01*
G03X1488580Y1481836I150J-132D01*
G01Y1479898D01*
G03X1488630Y1479766I200J0D01*
G02Y1476850I-1661J-1458D01*
G03X1488580Y1476718I150J-132D01*
G01Y1476097D01*
G02X1488378Y1475894I-202J-1D01*
G01X1485558D01*
G02X1485356Y1476097I1J203D01*
G01Y1476718D01*
G03X1485306Y1476850I-200J0D01*
G02Y1479766I1661J1458D01*
G03X1485356Y1479898I-150J132D01*
G01Y1481836D01*
G03X1485306Y1481968I-200J0D01*
G02Y1484884I1661J1458D01*
G03X1485356Y1485016I-150J132D01*
G01Y1485635D01*
G02X1485558Y1485838I202J1D01*
G37*
G36*
G01X1502881D02*
X1505701D01*
G02X1505904Y1485635I0J-203D01*
G01Y1485014D01*
G03X1505954Y1484882I200J0D01*
G02Y1481970I-1664J-1456D01*
G03X1505904Y1481838I150J-132D01*
G01Y1479896D01*
G03X1505954Y1479764I200J0D01*
G02Y1476852I-1664J-1456D01*
G03X1505904Y1476720I150J-132D01*
G01Y1476097D01*
G02X1505701Y1475894I-203J0D01*
G01X1502881D01*
G02X1502678Y1476097I0J203D01*
G01Y1476720D01*
G03X1502628Y1476852I-200J0D01*
G02Y1479764I1664J1456D01*
G03X1502678Y1479896I-150J132D01*
G01Y1481838D01*
G03X1502628Y1481970I-200J0D01*
G02Y1484882I1664J1456D01*
G03X1502678Y1485014I-150J132D01*
G01Y1485635D01*
G02X1502881Y1485838I203J0D01*
G37*
G36*
G01X1520204D02*
X1523024D01*
G02X1523226Y1485635I-1J-203D01*
G01Y1485016D01*
G03X1523276Y1484884I200J0D01*
G02Y1481968I-1661J-1458D01*
G03X1523226Y1481836I150J-132D01*
G01Y1479898D01*
G03X1523276Y1479766I200J0D01*
G02Y1476850I-1661J-1458D01*
G03X1523226Y1476718I150J-132D01*
G01Y1476097D01*
G02X1523024Y1475894I-202J-1D01*
G01X1520204D01*
G02X1520002Y1476097I1J203D01*
G01Y1476718D01*
G03X1519952Y1476850I-200J0D01*
G02Y1479766I1661J1458D01*
G03X1520002Y1479898I-150J132D01*
G01Y1481836D01*
G03X1519952Y1481968I-200J0D01*
G02Y1484884I1661J1458D01*
G03X1520002Y1485016I-150J132D01*
G01Y1485635D01*
G02X1520204Y1485838I202J1D01*
G37*
G36*
G01X1537527D02*
X1540347D01*
G02X1540550Y1485635I0J-203D01*
G01Y1485014D01*
G03X1540600Y1484882I200J0D01*
G02Y1481970I-1664J-1456D01*
G03X1540550Y1481838I150J-132D01*
G01Y1479896D01*
G03X1540600Y1479764I200J0D01*
G02Y1476852I-1664J-1456D01*
G03X1540550Y1476720I150J-132D01*
G01Y1476097D01*
G02X1540347Y1475894I-203J0D01*
G01X1537527D01*
G02X1537324Y1476097I0J203D01*
G01Y1476720D01*
G03X1537274Y1476852I-200J0D01*
G02Y1479764I1664J1456D01*
G03X1537324Y1479896I-150J132D01*
G01Y1481838D01*
G03X1537274Y1481970I-200J0D01*
G02Y1484882I1664J1456D01*
G03X1537324Y1485014I-150J132D01*
G01Y1485635D01*
G02X1537527Y1485838I203J0D01*
G37*
G36*
G01X1693432D02*
X1696252D01*
G02X1696454Y1485635I-1J-203D01*
G01Y1485016D01*
G03X1696504Y1484884I200J0D01*
G02Y1481968I-1661J-1458D01*
G03X1696454Y1481836I150J-132D01*
G01Y1479898D01*
G03X1696504Y1479766I200J0D01*
G02Y1476850I-1661J-1458D01*
G03X1696454Y1476718I150J-132D01*
G01Y1476097D01*
G02X1696252Y1475894I-202J-1D01*
G01X1693432D01*
G02X1693230Y1476097I1J203D01*
G01Y1476718D01*
G03X1693180Y1476850I-200J0D01*
G02Y1479766I1661J1458D01*
G03X1693230Y1479898I-150J132D01*
G01Y1481836D01*
G03X1693180Y1481968I-200J0D01*
G02Y1484884I1661J1458D01*
G03X1693230Y1485016I-150J132D01*
G01Y1485635D01*
G02X1693432Y1485838I202J1D01*
G37*
G36*
G01X1710755D02*
X1713575D01*
G02X1713778Y1485635I0J-203D01*
G01Y1485014D01*
G03X1713828Y1484882I200J0D01*
G02Y1481970I-1664J-1456D01*
G03X1713778Y1481838I150J-132D01*
G01Y1479896D01*
G03X1713828Y1479764I200J0D01*
G02Y1476852I-1664J-1456D01*
G03X1713778Y1476720I150J-132D01*
G01Y1476097D01*
G02X1713575Y1475894I-203J0D01*
G01X1710755D01*
G02X1710552Y1476097I0J203D01*
G01Y1476720D01*
G03X1710502Y1476852I-200J0D01*
G02Y1479764I1664J1456D01*
G03X1710552Y1479896I-150J132D01*
G01Y1481838D01*
G03X1710502Y1481970I-200J0D01*
G02Y1484882I1664J1456D01*
G03X1710552Y1485014I-150J132D01*
G01Y1485635D01*
G02X1710755Y1485838I203J0D01*
G37*
G36*
G01X186425D02*
X189245D01*
G02X189448Y1485636I1J-202D01*
G01Y1485014D01*
G03X189498Y1484882I200J0D01*
G02Y1481970I-1664J-1456D01*
G03X189448Y1481838I150J-132D01*
G01Y1479896D01*
G03X189498Y1479764I200J0D01*
G02Y1476852I-1664J-1456D01*
G03X189448Y1476720I150J-132D01*
G01Y1476098D01*
G02X189245Y1475896I-203J1D01*
G01X186425D01*
G02X186222Y1476098I-1J202D01*
G01Y1476720D01*
G03X186172Y1476852I-200J0D01*
G02Y1479764I1664J1456D01*
G03X186222Y1479896I-150J132D01*
G01Y1481838D01*
G03X186172Y1481970I-200J0D01*
G02Y1484882I1664J1456D01*
G03X186222Y1485014I-150J132D01*
G01Y1485636D01*
G02X186425Y1485838I203J-1D01*
G37*
G36*
G01X125795Y1496862D02*
X128615D01*
G02X128818Y1496659I0J-203D01*
G01Y1496037D01*
G03X128868Y1495905I200J0D01*
G02Y1492993I-1664J-1456D01*
G03X128818Y1492861I150J-132D01*
G01Y1490919D01*
G03X128868Y1490787I200J0D01*
G02Y1487875I-1664J-1456D01*
G03X128818Y1487743I150J-132D01*
G01Y1487121D01*
G02X128615Y1486918I-203J0D01*
G01X125795D01*
G02X125592Y1487121I0J203D01*
G01Y1487743D01*
G03X125542Y1487875I-200J0D01*
G02Y1490787I1664J1456D01*
G03X125592Y1490919I-150J132D01*
G01Y1492861D01*
G03X125542Y1492993I-200J0D01*
G02Y1495905I1664J1456D01*
G03X125592Y1496037I-150J132D01*
G01Y1496659D01*
G02X125795Y1496862I203J0D01*
G37*
G36*
G01X143118D02*
X145938D01*
G02X146140Y1496659I-1J-203D01*
G01Y1496039D01*
G03X146190Y1495907I200J0D01*
G02Y1492991I-1661J-1458D01*
G03X146140Y1492859I150J-132D01*
G01Y1490921D01*
G03X146190Y1490789I200J0D01*
G02Y1487873I-1661J-1458D01*
G03X146140Y1487741I150J-132D01*
G01Y1487121D01*
G02X145938Y1486918I-202J-1D01*
G01X143118D01*
G02X142916Y1487121I1J203D01*
G01Y1487741D01*
G03X142866Y1487873I-200J0D01*
G02Y1490789I1661J1458D01*
G03X142916Y1490921I-150J132D01*
G01Y1492859D01*
G03X142866Y1492991I-200J0D01*
G02Y1495907I1661J1458D01*
G03X142916Y1496039I-150J132D01*
G01Y1496659D01*
G02X143118Y1496862I202J1D01*
G37*
G36*
G01X160440D02*
X163260D01*
G02X163462Y1496659I-1J-203D01*
G01Y1496039D01*
G03X163512Y1495907I200J0D01*
G02Y1492991I-1661J-1458D01*
G03X163462Y1492859I150J-132D01*
G01Y1490921D01*
G03X163512Y1490789I200J0D01*
G02Y1487873I-1661J-1458D01*
G03X163462Y1487741I150J-132D01*
G01Y1487121D01*
G02X163260Y1486918I-202J-1D01*
G01X160440D01*
G02X160238Y1487121I1J203D01*
G01Y1487741D01*
G03X160188Y1487873I-200J0D01*
G02Y1490789I1661J1458D01*
G03X160238Y1490921I-150J132D01*
G01Y1492859D01*
G03X160188Y1492991I-200J0D01*
G02Y1495907I1661J1458D01*
G03X160238Y1496039I-150J132D01*
G01Y1496659D01*
G02X160440Y1496862I202J1D01*
G37*
G36*
G01X281700D02*
X284520D01*
G02X284722Y1496659I-1J-203D01*
G01Y1496039D01*
G03X284772Y1495907I200J0D01*
G02Y1492991I-1661J-1458D01*
G03X284722Y1492859I150J-132D01*
G01Y1490921D01*
G03X284772Y1490789I200J0D01*
G02Y1487873I-1661J-1458D01*
G03X284722Y1487741I150J-132D01*
G01Y1487121D01*
G02X284520Y1486918I-202J-1D01*
G01X281700D01*
G02X281498Y1487121I1J203D01*
G01Y1487741D01*
G03X281448Y1487873I-200J0D01*
G02Y1490789I1661J1458D01*
G03X281498Y1490921I-150J132D01*
G01Y1492859D01*
G03X281448Y1492991I-200J0D01*
G02Y1495907I1661J1458D01*
G03X281498Y1496039I-150J132D01*
G01Y1496659D01*
G02X281700Y1496862I202J1D01*
G37*
G36*
G01X299023D02*
X301843D01*
G02X302046Y1496659I0J-203D01*
G01Y1496037D01*
G03X302096Y1495905I200J0D01*
G02Y1492993I-1664J-1456D01*
G03X302046Y1492861I150J-132D01*
G01Y1490919D01*
G03X302096Y1490787I200J0D01*
G02Y1487875I-1664J-1456D01*
G03X302046Y1487743I150J-132D01*
G01Y1487121D01*
G02X301843Y1486918I-203J0D01*
G01X299023D01*
G02X298820Y1487121I0J203D01*
G01Y1487743D01*
G03X298770Y1487875I-200J0D01*
G02Y1490787I1664J1456D01*
G03X298820Y1490919I-150J132D01*
G01Y1492861D01*
G03X298770Y1492993I-200J0D01*
G02Y1495905I1664J1456D01*
G03X298820Y1496037I-150J132D01*
G01Y1496659D01*
G02X299023Y1496862I203J0D01*
G37*
G36*
G01X454929D02*
X457749D01*
G02X457952Y1496659I0J-203D01*
G01Y1496037D01*
G03X458002Y1495905I200J0D01*
G02Y1492993I-1664J-1456D01*
G03X457952Y1492861I150J-132D01*
G01Y1490919D01*
G03X458002Y1490787I200J0D01*
G02Y1487875I-1664J-1456D01*
G03X457952Y1487743I150J-132D01*
G01Y1487121D01*
G02X457749Y1486918I-203J0D01*
G01X454929D01*
G02X454726Y1487121I0J203D01*
G01Y1487743D01*
G03X454676Y1487875I-200J0D01*
G02Y1490787I1664J1456D01*
G03X454726Y1490919I-150J132D01*
G01Y1492861D01*
G03X454676Y1492993I-200J0D01*
G02Y1495905I1664J1456D01*
G03X454726Y1496037I-150J132D01*
G01Y1496659D01*
G02X454929Y1496862I203J0D01*
G37*
G36*
G01X472252D02*
X475072D01*
G02X475274Y1496659I-1J-203D01*
G01Y1496039D01*
G03X475324Y1495907I200J0D01*
G02Y1492991I-1661J-1458D01*
G03X475274Y1492859I150J-132D01*
G01Y1490921D01*
G03X475324Y1490789I200J0D01*
G02Y1487873I-1661J-1458D01*
G03X475274Y1487741I150J-132D01*
G01Y1487121D01*
G02X475072Y1486918I-202J-1D01*
G01X472252D01*
G02X472050Y1487121I1J203D01*
G01Y1487741D01*
G03X472000Y1487873I-200J0D01*
G02Y1490789I1661J1458D01*
G03X472050Y1490921I-150J132D01*
G01Y1492859D01*
G03X472000Y1492991I-200J0D01*
G02Y1495907I1661J1458D01*
G03X472050Y1496039I-150J132D01*
G01Y1496659D01*
G02X472252Y1496862I202J1D01*
G37*
G36*
G01X489575D02*
X492395D01*
G02X492598Y1496659I0J-203D01*
G01Y1496037D01*
G03X492648Y1495905I200J0D01*
G02Y1492993I-1664J-1456D01*
G03X492598Y1492861I150J-132D01*
G01Y1490919D01*
G03X492648Y1490787I200J0D01*
G02Y1487875I-1664J-1456D01*
G03X492598Y1487743I150J-132D01*
G01Y1487121D01*
G02X492395Y1486918I-203J0D01*
G01X489575D01*
G02X489372Y1487121I0J203D01*
G01Y1487743D01*
G03X489322Y1487875I-200J0D01*
G02Y1490787I1664J1456D01*
G03X489372Y1490919I-150J132D01*
G01Y1492861D01*
G03X489322Y1492993I-200J0D01*
G02Y1495905I1664J1456D01*
G03X489372Y1496037I-150J132D01*
G01Y1496659D01*
G02X489575Y1496862I203J0D01*
G37*
G36*
G01X506897D02*
X509717D01*
G02X509920Y1496659I0J-203D01*
G01Y1496037D01*
G03X509970Y1495905I200J0D01*
G02Y1492993I-1664J-1456D01*
G03X509920Y1492861I150J-132D01*
G01Y1490919D01*
G03X509970Y1490787I200J0D01*
G02Y1487875I-1664J-1456D01*
G03X509920Y1487743I150J-132D01*
G01Y1487121D01*
G02X509717Y1486918I-203J0D01*
G01X506897D01*
G02X506694Y1487121I0J203D01*
G01Y1487743D01*
G03X506644Y1487875I-200J0D01*
G02Y1490787I1664J1456D01*
G03X506694Y1490919I-150J132D01*
G01Y1492861D01*
G03X506644Y1492993I-200J0D01*
G02Y1495905I1664J1456D01*
G03X506694Y1496037I-150J132D01*
G01Y1496659D01*
G02X506897Y1496862I203J0D01*
G37*
G36*
G01X645480D02*
X648300D01*
G02X648502Y1496659I-1J-203D01*
G01Y1496039D01*
G03X648552Y1495907I200J0D01*
G02Y1492991I-1661J-1458D01*
G03X648502Y1492859I150J-132D01*
G01Y1490921D01*
G03X648552Y1490789I200J0D01*
G02Y1487873I-1661J-1458D01*
G03X648502Y1487741I150J-132D01*
G01Y1487121D01*
G02X648300Y1486918I-202J-1D01*
G01X645480D01*
G02X645278Y1487121I1J203D01*
G01Y1487741D01*
G03X645228Y1487873I-200J0D01*
G02Y1490789I1661J1458D01*
G03X645278Y1490921I-150J132D01*
G01Y1492859D01*
G03X645228Y1492991I-200J0D01*
G02Y1495907I1661J1458D01*
G03X645278Y1496039I-150J132D01*
G01Y1496659D01*
G02X645480Y1496862I202J1D01*
G37*
G36*
G01X662803D02*
X665623D01*
G02X665826Y1496659I0J-203D01*
G01Y1496037D01*
G03X665876Y1495905I200J0D01*
G02Y1492993I-1664J-1456D01*
G03X665826Y1492861I150J-132D01*
G01Y1490919D01*
G03X665876Y1490787I200J0D01*
G02Y1487875I-1664J-1456D01*
G03X665826Y1487743I150J-132D01*
G01Y1487121D01*
G02X665623Y1486918I-203J0D01*
G01X662803D01*
G02X662600Y1487121I0J203D01*
G01Y1487743D01*
G03X662550Y1487875I-200J0D01*
G02Y1490787I1664J1456D01*
G03X662600Y1490919I-150J132D01*
G01Y1492861D01*
G03X662550Y1492993I-200J0D01*
G02Y1495905I1664J1456D01*
G03X662600Y1496037I-150J132D01*
G01Y1496659D01*
G02X662803Y1496862I203J0D01*
G37*
G36*
G01X680125D02*
X682945D01*
G02X683148Y1496659I0J-203D01*
G01Y1496037D01*
G03X683198Y1495905I200J0D01*
G02Y1492993I-1664J-1456D01*
G03X683148Y1492861I150J-132D01*
G01Y1490919D01*
G03X683198Y1490787I200J0D01*
G02Y1487875I-1664J-1456D01*
G03X683148Y1487743I150J-132D01*
G01Y1487121D01*
G02X682945Y1486918I-203J0D01*
G01X680125D01*
G02X679922Y1487121I0J203D01*
G01Y1487743D01*
G03X679872Y1487875I-200J0D01*
G02Y1490787I1664J1456D01*
G03X679922Y1490919I-150J132D01*
G01Y1492861D01*
G03X679872Y1492993I-200J0D01*
G02Y1495905I1664J1456D01*
G03X679922Y1496037I-150J132D01*
G01Y1496659D01*
G02X680125Y1496862I203J0D01*
G37*
G36*
G01X1165086D02*
X1167906D01*
G02X1168108Y1496659I-1J-203D01*
G01Y1496039D01*
G03X1168158Y1495907I200J0D01*
G02Y1492991I-1661J-1458D01*
G03X1168108Y1492859I150J-132D01*
G01Y1490921D01*
G03X1168158Y1490789I200J0D01*
G02Y1487873I-1661J-1458D01*
G03X1168108Y1487741I150J-132D01*
G01Y1487121D01*
G02X1167906Y1486918I-202J-1D01*
G01X1165086D01*
G02X1164884Y1487121I1J203D01*
G01Y1487741D01*
G03X1164834Y1487873I-200J0D01*
G02Y1490789I1661J1458D01*
G03X1164884Y1490921I-150J132D01*
G01Y1492859D01*
G03X1164834Y1492991I-200J0D01*
G02Y1495907I1661J1458D01*
G03X1164884Y1496039I-150J132D01*
G01Y1496659D01*
G02X1165086Y1496862I202J1D01*
G37*
G36*
G01X1182408D02*
X1185228D01*
G02X1185430Y1496659I-1J-203D01*
G01Y1496039D01*
G03X1185480Y1495907I200J0D01*
G02Y1492991I-1661J-1458D01*
G03X1185430Y1492859I150J-132D01*
G01Y1490921D01*
G03X1185480Y1490789I200J0D01*
G02Y1487873I-1661J-1458D01*
G03X1185430Y1487741I150J-132D01*
G01Y1487121D01*
G02X1185228Y1486918I-202J-1D01*
G01X1182408D01*
G02X1182206Y1487121I1J203D01*
G01Y1487741D01*
G03X1182156Y1487873I-200J0D01*
G02Y1490789I1661J1458D01*
G03X1182206Y1490921I-150J132D01*
G01Y1492859D01*
G03X1182156Y1492991I-200J0D01*
G02Y1495907I1661J1458D01*
G03X1182206Y1496039I-150J132D01*
G01Y1496659D01*
G02X1182408Y1496862I202J1D01*
G37*
G36*
G01X1303669D02*
X1306489D01*
G02X1306692Y1496659I0J-203D01*
G01Y1496037D01*
G03X1306742Y1495905I200J0D01*
G02Y1492993I-1664J-1456D01*
G03X1306692Y1492861I150J-132D01*
G01Y1490919D01*
G03X1306742Y1490787I200J0D01*
G02Y1487875I-1664J-1456D01*
G03X1306692Y1487743I150J-132D01*
G01Y1487121D01*
G02X1306489Y1486918I-203J0D01*
G01X1303669D01*
G02X1303466Y1487121I0J203D01*
G01Y1487743D01*
G03X1303416Y1487875I-200J0D01*
G02Y1490787I1664J1456D01*
G03X1303466Y1490919I-150J132D01*
G01Y1492861D01*
G03X1303416Y1492993I-200J0D01*
G02Y1495905I1664J1456D01*
G03X1303466Y1496037I-150J132D01*
G01Y1496659D01*
G02X1303669Y1496862I203J0D01*
G37*
G36*
G01X1320992D02*
X1323812D01*
G02X1324014Y1496659I-1J-203D01*
G01Y1496039D01*
G03X1324064Y1495907I200J0D01*
G02Y1492991I-1661J-1458D01*
G03X1324014Y1492859I150J-132D01*
G01Y1490921D01*
G03X1324064Y1490789I200J0D01*
G02Y1487873I-1661J-1458D01*
G03X1324014Y1487741I150J-132D01*
G01Y1487121D01*
G02X1323812Y1486918I-202J-1D01*
G01X1320992D01*
G02X1320790Y1487121I1J203D01*
G01Y1487741D01*
G03X1320740Y1487873I-200J0D01*
G02Y1490789I1661J1458D01*
G03X1320790Y1490921I-150J132D01*
G01Y1492859D01*
G03X1320740Y1492991I-200J0D01*
G02Y1495907I1661J1458D01*
G03X1320790Y1496039I-150J132D01*
G01Y1496659D01*
G02X1320992Y1496862I202J1D01*
G37*
G36*
G01X1338315D02*
X1341135D01*
G02X1341338Y1496659I0J-203D01*
G01Y1496037D01*
G03X1341388Y1495905I200J0D01*
G02Y1492993I-1664J-1456D01*
G03X1341338Y1492861I150J-132D01*
G01Y1490919D01*
G03X1341388Y1490787I200J0D01*
G02Y1487875I-1664J-1456D01*
G03X1341338Y1487743I150J-132D01*
G01Y1487121D01*
G02X1341135Y1486918I-203J0D01*
G01X1338315D01*
G02X1338112Y1487121I0J203D01*
G01Y1487743D01*
G03X1338062Y1487875I-200J0D01*
G02Y1490787I1664J1456D01*
G03X1338112Y1490919I-150J132D01*
G01Y1492861D01*
G03X1338062Y1492993I-200J0D01*
G02Y1495905I1664J1456D01*
G03X1338112Y1496037I-150J132D01*
G01Y1496659D01*
G02X1338315Y1496862I203J0D01*
G37*
G36*
G01X1355637D02*
X1358457D01*
G02X1358660Y1496659I0J-203D01*
G01Y1496037D01*
G03X1358710Y1495905I200J0D01*
G02Y1492993I-1664J-1456D01*
G03X1358660Y1492861I150J-132D01*
G01Y1490919D01*
G03X1358710Y1490787I200J0D01*
G02Y1487875I-1664J-1456D01*
G03X1358660Y1487743I150J-132D01*
G01Y1487121D01*
G02X1358457Y1486918I-203J0D01*
G01X1355637D01*
G02X1355434Y1487121I0J203D01*
G01Y1487743D01*
G03X1355384Y1487875I-200J0D01*
G02Y1490787I1664J1456D01*
G03X1355434Y1490919I-150J132D01*
G01Y1492861D01*
G03X1355384Y1492993I-200J0D01*
G02Y1495905I1664J1456D01*
G03X1355434Y1496037I-150J132D01*
G01Y1496659D01*
G02X1355637Y1496862I203J0D01*
G37*
G36*
G01X1476897D02*
X1479717D01*
G02X1479920Y1496659I0J-203D01*
G01Y1496037D01*
G03X1479970Y1495905I200J0D01*
G02Y1492993I-1664J-1456D01*
G03X1479920Y1492861I150J-132D01*
G01Y1490919D01*
G03X1479970Y1490787I200J0D01*
G02Y1487875I-1664J-1456D01*
G03X1479920Y1487743I150J-132D01*
G01Y1487121D01*
G02X1479717Y1486918I-203J0D01*
G01X1476897D01*
G02X1476694Y1487121I0J203D01*
G01Y1487743D01*
G03X1476644Y1487875I-200J0D01*
G02Y1490787I1664J1456D01*
G03X1476694Y1490919I-150J132D01*
G01Y1492861D01*
G03X1476644Y1492993I-200J0D01*
G02Y1495905I1664J1456D01*
G03X1476694Y1496037I-150J132D01*
G01Y1496659D01*
G02X1476897Y1496862I203J0D01*
G37*
G36*
G01X1494220D02*
X1497040D01*
G02X1497242Y1496659I-1J-203D01*
G01Y1496039D01*
G03X1497292Y1495907I200J0D01*
G02Y1492991I-1661J-1458D01*
G03X1497242Y1492859I150J-132D01*
G01Y1490921D01*
G03X1497292Y1490789I200J0D01*
G02Y1487873I-1661J-1458D01*
G03X1497242Y1487741I150J-132D01*
G01Y1487121D01*
G02X1497040Y1486918I-202J-1D01*
G01X1494220D01*
G02X1494018Y1487121I1J203D01*
G01Y1487741D01*
G03X1493968Y1487873I-200J0D01*
G02Y1490789I1661J1458D01*
G03X1494018Y1490921I-150J132D01*
G01Y1492859D01*
G03X1493968Y1492991I-200J0D01*
G02Y1495907I1661J1458D01*
G03X1494018Y1496039I-150J132D01*
G01Y1496659D01*
G02X1494220Y1496862I202J1D01*
G37*
G36*
G01X1511543D02*
X1514363D01*
G02X1514566Y1496659I0J-203D01*
G01Y1496037D01*
G03X1514616Y1495905I200J0D01*
G02Y1492993I-1664J-1456D01*
G03X1514566Y1492861I150J-132D01*
G01Y1490919D01*
G03X1514616Y1490787I200J0D01*
G02Y1487875I-1664J-1456D01*
G03X1514566Y1487743I150J-132D01*
G01Y1487121D01*
G02X1514363Y1486918I-203J0D01*
G01X1511543D01*
G02X1511340Y1487121I0J203D01*
G01Y1487743D01*
G03X1511290Y1487875I-200J0D01*
G02Y1490787I1664J1456D01*
G03X1511340Y1490919I-150J132D01*
G01Y1492861D01*
G03X1511290Y1492993I-200J0D01*
G02Y1495905I1664J1456D01*
G03X1511340Y1496037I-150J132D01*
G01Y1496659D01*
G02X1511543Y1496862I203J0D01*
G37*
G36*
G01X1528865D02*
X1531685D01*
G02X1531888Y1496659I0J-203D01*
G01Y1496037D01*
G03X1531938Y1495905I200J0D01*
G02Y1492993I-1664J-1456D01*
G03X1531888Y1492861I150J-132D01*
G01Y1490919D01*
G03X1531938Y1490787I200J0D01*
G02Y1487875I-1664J-1456D01*
G03X1531888Y1487743I150J-132D01*
G01Y1487121D01*
G02X1531685Y1486918I-203J0D01*
G01X1528865D01*
G02X1528662Y1487121I0J203D01*
G01Y1487743D01*
G03X1528612Y1487875I-200J0D01*
G02Y1490787I1664J1456D01*
G03X1528662Y1490919I-150J132D01*
G01Y1492861D01*
G03X1528612Y1492993I-200J0D01*
G02Y1495905I1664J1456D01*
G03X1528662Y1496037I-150J132D01*
G01Y1496659D01*
G02X1528865Y1496862I203J0D01*
G37*
G36*
G01X1684771D02*
X1687591D01*
G02X1687794Y1496659I0J-203D01*
G01Y1496037D01*
G03X1687844Y1495905I200J0D01*
G02Y1492993I-1664J-1456D01*
G03X1687794Y1492861I150J-132D01*
G01Y1490919D01*
G03X1687844Y1490787I200J0D01*
G02Y1487875I-1664J-1456D01*
G03X1687794Y1487743I150J-132D01*
G01Y1487121D01*
G02X1687591Y1486918I-203J0D01*
G01X1684771D01*
G02X1684568Y1487121I0J203D01*
G01Y1487743D01*
G03X1684518Y1487875I-200J0D01*
G02Y1490787I1664J1456D01*
G03X1684568Y1490919I-150J132D01*
G01Y1492861D01*
G03X1684518Y1492993I-200J0D01*
G02Y1495905I1664J1456D01*
G03X1684568Y1496037I-150J132D01*
G01Y1496659D01*
G02X1684771Y1496862I203J0D01*
G37*
G36*
G01X1702093D02*
X1704913D01*
G02X1705116Y1496659I0J-203D01*
G01Y1496037D01*
G03X1705166Y1495905I200J0D01*
G02Y1492993I-1664J-1456D01*
G03X1705116Y1492861I150J-132D01*
G01Y1490919D01*
G03X1705166Y1490787I200J0D01*
G02Y1487875I-1664J-1456D01*
G03X1705116Y1487743I150J-132D01*
G01Y1487121D01*
G02X1704913Y1486918I-203J0D01*
G01X1702093D01*
G02X1701890Y1487121I0J203D01*
G01Y1487743D01*
G03X1701840Y1487875I-200J0D01*
G02Y1490787I1664J1456D01*
G03X1701890Y1490919I-150J132D01*
G01Y1492861D01*
G03X1701840Y1492993I-200J0D01*
G02Y1495905I1664J1456D01*
G03X1701890Y1496037I-150J132D01*
G01Y1496659D01*
G02X1702093Y1496862I203J0D01*
G37*
G36*
G01X134456Y1501192D02*
X137276D01*
G02X137478Y1500989I-1J-203D01*
G01Y1500370D01*
G03X137528Y1500238I200J0D01*
G02Y1497322I-1661J-1458D01*
G03X137478Y1497190I150J-132D01*
G01Y1495252D01*
G03X137528Y1495120I200J0D01*
G02Y1492204I-1661J-1458D01*
G03X137478Y1492072I150J-132D01*
G01Y1491451D01*
G02X137276Y1491248I-202J-1D01*
G01X134456D01*
G02X134254Y1491451I1J203D01*
G01Y1492072D01*
G03X134204Y1492204I-200J0D01*
G02Y1495120I1661J1458D01*
G03X134254Y1495252I-150J132D01*
G01Y1497190D01*
G03X134204Y1497322I-200J0D01*
G02Y1500238I1661J1458D01*
G03X134254Y1500370I-150J132D01*
G01Y1500989D01*
G02X134456Y1501192I202J1D01*
G37*
G36*
G01X151779D02*
X154599D01*
G02X154802Y1500989I0J-203D01*
G01Y1500368D01*
G03X154852Y1500236I200J0D01*
G02Y1497324I-1664J-1456D01*
G03X154802Y1497192I150J-132D01*
G01Y1495250D01*
G03X154852Y1495118I200J0D01*
G02Y1492206I-1664J-1456D01*
G03X154802Y1492074I150J-132D01*
G01Y1491451D01*
G02X154599Y1491248I-203J0D01*
G01X151779D01*
G02X151576Y1491451I0J203D01*
G01Y1492074D01*
G03X151526Y1492206I-200J0D01*
G02Y1495118I1664J1456D01*
G03X151576Y1495250I-150J132D01*
G01Y1497192D01*
G03X151526Y1497324I-200J0D01*
G02Y1500236I1664J1456D01*
G03X151576Y1500368I-150J132D01*
G01Y1500989D01*
G02X151779Y1501192I203J0D01*
G37*
G36*
G01X169102D02*
X171922D01*
G02X172124Y1500989I-1J-203D01*
G01Y1500370D01*
G03X172174Y1500238I200J0D01*
G02Y1497322I-1661J-1458D01*
G03X172124Y1497190I150J-132D01*
G01Y1495252D01*
G03X172174Y1495120I200J0D01*
G02Y1492204I-1661J-1458D01*
G03X172124Y1492072I150J-132D01*
G01Y1491451D01*
G02X171922Y1491248I-202J-1D01*
G01X169102D01*
G02X168900Y1491451I1J203D01*
G01Y1492072D01*
G03X168850Y1492204I-200J0D01*
G02Y1495120I1661J1458D01*
G03X168900Y1495252I-150J132D01*
G01Y1497190D01*
G03X168850Y1497322I-200J0D01*
G02Y1500238I1661J1458D01*
G03X168900Y1500370I-150J132D01*
G01Y1500989D01*
G02X169102Y1501192I202J1D01*
G37*
G36*
G01X290361D02*
X293181D01*
G02X293384Y1500989I0J-203D01*
G01Y1500368D01*
G03X293434Y1500236I200J0D01*
G02Y1497324I-1664J-1456D01*
G03X293384Y1497192I150J-132D01*
G01Y1495250D01*
G03X293434Y1495118I200J0D01*
G02Y1492206I-1664J-1456D01*
G03X293384Y1492074I150J-132D01*
G01Y1491451D01*
G02X293181Y1491248I-203J0D01*
G01X290361D01*
G02X290158Y1491451I0J203D01*
G01Y1492074D01*
G03X290108Y1492206I-200J0D01*
G02Y1495118I1664J1456D01*
G03X290158Y1495250I-150J132D01*
G01Y1497192D01*
G03X290108Y1497324I-200J0D01*
G02Y1500236I1664J1456D01*
G03X290158Y1500368I-150J132D01*
G01Y1500989D01*
G02X290361Y1501192I203J0D01*
G37*
G36*
G01X463590D02*
X466410D01*
G02X466612Y1500989I-1J-203D01*
G01Y1500370D01*
G03X466662Y1500238I200J0D01*
G02Y1497322I-1661J-1458D01*
G03X466612Y1497190I150J-132D01*
G01Y1495252D01*
G03X466662Y1495120I200J0D01*
G02Y1492204I-1661J-1458D01*
G03X466612Y1492072I150J-132D01*
G01Y1491451D01*
G02X466410Y1491248I-202J-1D01*
G01X463590D01*
G02X463388Y1491451I1J203D01*
G01Y1492072D01*
G03X463338Y1492204I-200J0D01*
G02Y1495120I1661J1458D01*
G03X463388Y1495252I-150J132D01*
G01Y1497190D01*
G03X463338Y1497322I-200J0D01*
G02Y1500238I1661J1458D01*
G03X463388Y1500370I-150J132D01*
G01Y1500989D01*
G02X463590Y1501192I202J1D01*
G37*
G36*
G01X480913D02*
X483733D01*
G02X483936Y1500989I0J-203D01*
G01Y1500368D01*
G03X483986Y1500236I200J0D01*
G02Y1497324I-1664J-1456D01*
G03X483936Y1497192I150J-132D01*
G01Y1495250D01*
G03X483986Y1495118I200J0D01*
G02Y1492206I-1664J-1456D01*
G03X483936Y1492074I150J-132D01*
G01Y1491451D01*
G02X483733Y1491248I-203J0D01*
G01X480913D01*
G02X480710Y1491451I0J203D01*
G01Y1492074D01*
G03X480660Y1492206I-200J0D01*
G02Y1495118I1664J1456D01*
G03X480710Y1495250I-150J132D01*
G01Y1497192D01*
G03X480660Y1497324I-200J0D01*
G02Y1500236I1664J1456D01*
G03X480710Y1500368I-150J132D01*
G01Y1500989D01*
G02X480913Y1501192I203J0D01*
G37*
G36*
G01X498236D02*
X501056D01*
G02X501258Y1500989I-1J-203D01*
G01Y1500370D01*
G03X501308Y1500238I200J0D01*
G02Y1497322I-1661J-1458D01*
G03X501258Y1497190I150J-132D01*
G01Y1495252D01*
G03X501308Y1495120I200J0D01*
G02Y1492204I-1661J-1458D01*
G03X501258Y1492072I150J-132D01*
G01Y1491451D01*
G02X501056Y1491248I-202J-1D01*
G01X498236D01*
G02X498034Y1491451I1J203D01*
G01Y1492072D01*
G03X497984Y1492204I-200J0D01*
G02Y1495120I1661J1458D01*
G03X498034Y1495252I-150J132D01*
G01Y1497190D01*
G03X497984Y1497322I-200J0D01*
G02Y1500238I1661J1458D01*
G03X498034Y1500370I-150J132D01*
G01Y1500989D01*
G02X498236Y1501192I202J1D01*
G37*
G36*
G01X515559D02*
X518379D01*
G02X518582Y1500989I0J-203D01*
G01Y1500368D01*
G03X518632Y1500236I200J0D01*
G02Y1497324I-1664J-1456D01*
G03X518582Y1497192I150J-132D01*
G01Y1495250D01*
G03X518632Y1495118I200J0D01*
G02Y1492206I-1664J-1456D01*
G03X518582Y1492074I150J-132D01*
G01Y1491451D01*
G02X518379Y1491248I-203J0D01*
G01X515559D01*
G02X515356Y1491451I0J203D01*
G01Y1492074D01*
G03X515306Y1492206I-200J0D01*
G02Y1495118I1664J1456D01*
G03X515356Y1495250I-150J132D01*
G01Y1497192D01*
G03X515306Y1497324I-200J0D01*
G02Y1500236I1664J1456D01*
G03X515356Y1500368I-150J132D01*
G01Y1500989D01*
G02X515559Y1501192I203J0D01*
G37*
G36*
G01X654141D02*
X656961D01*
G02X657164Y1500989I0J-203D01*
G01Y1500368D01*
G03X657214Y1500236I200J0D01*
G02Y1497324I-1664J-1456D01*
G03X657164Y1497192I150J-132D01*
G01Y1495250D01*
G03X657214Y1495118I200J0D01*
G02Y1492206I-1664J-1456D01*
G03X657164Y1492074I150J-132D01*
G01Y1491451D01*
G02X656961Y1491248I-203J0D01*
G01X654141D01*
G02X653938Y1491451I0J203D01*
G01Y1492074D01*
G03X653888Y1492206I-200J0D01*
G02Y1495118I1664J1456D01*
G03X653938Y1495250I-150J132D01*
G01Y1497192D01*
G03X653888Y1497324I-200J0D01*
G02Y1500236I1664J1456D01*
G03X653938Y1500368I-150J132D01*
G01Y1500989D01*
G02X654141Y1501192I203J0D01*
G37*
G36*
G01X671464D02*
X674284D01*
G02X674486Y1500989I-1J-203D01*
G01Y1500370D01*
G03X674536Y1500238I200J0D01*
G02Y1497322I-1661J-1458D01*
G03X674486Y1497190I150J-132D01*
G01Y1495252D01*
G03X674536Y1495120I200J0D01*
G02Y1492204I-1661J-1458D01*
G03X674486Y1492072I150J-132D01*
G01Y1491451D01*
G02X674284Y1491248I-202J-1D01*
G01X671464D01*
G02X671262Y1491451I1J203D01*
G01Y1492072D01*
G03X671212Y1492204I-200J0D01*
G02Y1495120I1661J1458D01*
G03X671262Y1495252I-150J132D01*
G01Y1497190D01*
G03X671212Y1497322I-200J0D01*
G02Y1500238I1661J1458D01*
G03X671262Y1500370I-150J132D01*
G01Y1500989D01*
G02X671464Y1501192I202J1D01*
G37*
G36*
G01X688787D02*
X691607D01*
G02X691810Y1500989I0J-203D01*
G01Y1500368D01*
G03X691860Y1500236I200J0D01*
G02Y1497324I-1664J-1456D01*
G03X691810Y1497192I150J-132D01*
G01Y1495250D01*
G03X691860Y1495118I200J0D01*
G02Y1492206I-1664J-1456D01*
G03X691810Y1492074I150J-132D01*
G01Y1491451D01*
G02X691607Y1491248I-203J0D01*
G01X688787D01*
G02X688584Y1491451I0J203D01*
G01Y1492074D01*
G03X688534Y1492206I-200J0D01*
G02Y1495118I1664J1456D01*
G03X688584Y1495250I-150J132D01*
G01Y1497192D01*
G03X688534Y1497324I-200J0D01*
G02Y1500236I1664J1456D01*
G03X688584Y1500368I-150J132D01*
G01Y1500989D01*
G02X688787Y1501192I203J0D01*
G37*
G36*
G01X1173747D02*
X1176567D01*
G02X1176770Y1500989I0J-203D01*
G01Y1500368D01*
G03X1176820Y1500236I200J0D01*
G02Y1497324I-1664J-1456D01*
G03X1176770Y1497192I150J-132D01*
G01Y1495250D01*
G03X1176820Y1495118I200J0D01*
G02Y1492206I-1664J-1456D01*
G03X1176770Y1492074I150J-132D01*
G01Y1491451D01*
G02X1176567Y1491248I-203J0D01*
G01X1173747D01*
G02X1173544Y1491451I0J203D01*
G01Y1492074D01*
G03X1173494Y1492206I-200J0D01*
G02Y1495118I1664J1456D01*
G03X1173544Y1495250I-150J132D01*
G01Y1497192D01*
G03X1173494Y1497324I-200J0D01*
G02Y1500236I1664J1456D01*
G03X1173544Y1500368I-150J132D01*
G01Y1500989D01*
G02X1173747Y1501192I203J0D01*
G37*
G36*
G01X1191070D02*
X1193890D01*
G02X1194092Y1500989I-1J-203D01*
G01Y1500370D01*
G03X1194142Y1500238I200J0D01*
G02Y1497322I-1661J-1458D01*
G03X1194092Y1497190I150J-132D01*
G01Y1495252D01*
G03X1194142Y1495120I200J0D01*
G02Y1492204I-1661J-1458D01*
G03X1194092Y1492072I150J-132D01*
G01Y1491451D01*
G02X1193890Y1491248I-202J-1D01*
G01X1191070D01*
G02X1190868Y1491451I1J203D01*
G01Y1492072D01*
G03X1190818Y1492204I-200J0D01*
G02Y1495120I1661J1458D01*
G03X1190868Y1495252I-150J132D01*
G01Y1497190D01*
G03X1190818Y1497322I-200J0D01*
G02Y1500238I1661J1458D01*
G03X1190868Y1500370I-150J132D01*
G01Y1500989D01*
G02X1191070Y1501192I202J1D01*
G37*
G36*
G01X1312330D02*
X1315150D01*
G02X1315352Y1500989I-1J-203D01*
G01Y1500370D01*
G03X1315402Y1500238I200J0D01*
G02Y1497322I-1661J-1458D01*
G03X1315352Y1497190I150J-132D01*
G01Y1495252D01*
G03X1315402Y1495120I200J0D01*
G02Y1492204I-1661J-1458D01*
G03X1315352Y1492072I150J-132D01*
G01Y1491451D01*
G02X1315150Y1491248I-202J-1D01*
G01X1312330D01*
G02X1312128Y1491451I1J203D01*
G01Y1492072D01*
G03X1312078Y1492204I-200J0D01*
G02Y1495120I1661J1458D01*
G03X1312128Y1495252I-150J132D01*
G01Y1497190D01*
G03X1312078Y1497322I-200J0D01*
G02Y1500238I1661J1458D01*
G03X1312128Y1500370I-150J132D01*
G01Y1500989D01*
G02X1312330Y1501192I202J1D01*
G37*
G36*
G01X1329653D02*
X1332473D01*
G02X1332676Y1500989I0J-203D01*
G01Y1500368D01*
G03X1332726Y1500236I200J0D01*
G02Y1497324I-1664J-1456D01*
G03X1332676Y1497192I150J-132D01*
G01Y1495250D01*
G03X1332726Y1495118I200J0D01*
G02Y1492206I-1664J-1456D01*
G03X1332676Y1492074I150J-132D01*
G01Y1491451D01*
G02X1332473Y1491248I-203J0D01*
G01X1329653D01*
G02X1329450Y1491451I0J203D01*
G01Y1492074D01*
G03X1329400Y1492206I-200J0D01*
G02Y1495118I1664J1456D01*
G03X1329450Y1495250I-150J132D01*
G01Y1497192D01*
G03X1329400Y1497324I-200J0D01*
G02Y1500236I1664J1456D01*
G03X1329450Y1500368I-150J132D01*
G01Y1500989D01*
G02X1329653Y1501192I203J0D01*
G37*
G36*
G01X1346976D02*
X1349796D01*
G02X1349998Y1500989I-1J-203D01*
G01Y1500370D01*
G03X1350048Y1500238I200J0D01*
G02Y1497322I-1661J-1458D01*
G03X1349998Y1497190I150J-132D01*
G01Y1495252D01*
G03X1350048Y1495120I200J0D01*
G02Y1492204I-1661J-1458D01*
G03X1349998Y1492072I150J-132D01*
G01Y1491451D01*
G02X1349796Y1491248I-202J-1D01*
G01X1346976D01*
G02X1346774Y1491451I1J203D01*
G01Y1492072D01*
G03X1346724Y1492204I-200J0D01*
G02Y1495120I1661J1458D01*
G03X1346774Y1495252I-150J132D01*
G01Y1497190D01*
G03X1346724Y1497322I-200J0D01*
G02Y1500238I1661J1458D01*
G03X1346774Y1500370I-150J132D01*
G01Y1500989D01*
G02X1346976Y1501192I202J1D01*
G37*
G36*
G01X1364299D02*
X1367119D01*
G02X1367322Y1500989I0J-203D01*
G01Y1500368D01*
G03X1367372Y1500236I200J0D01*
G02Y1497324I-1664J-1456D01*
G03X1367322Y1497192I150J-132D01*
G01Y1495250D01*
G03X1367372Y1495118I200J0D01*
G02Y1492206I-1664J-1456D01*
G03X1367322Y1492074I150J-132D01*
G01Y1491451D01*
G02X1367119Y1491248I-203J0D01*
G01X1364299D01*
G02X1364096Y1491451I0J203D01*
G01Y1492074D01*
G03X1364046Y1492206I-200J0D01*
G02Y1495118I1664J1456D01*
G03X1364096Y1495250I-150J132D01*
G01Y1497192D01*
G03X1364046Y1497324I-200J0D01*
G02Y1500236I1664J1456D01*
G03X1364096Y1500368I-150J132D01*
G01Y1500989D01*
G02X1364299Y1501192I203J0D01*
G37*
G36*
G01X1485558D02*
X1488378D01*
G02X1488580Y1500989I-1J-203D01*
G01Y1500370D01*
G03X1488630Y1500238I200J0D01*
G02Y1497322I-1661J-1458D01*
G03X1488580Y1497190I150J-132D01*
G01Y1495252D01*
G03X1488630Y1495120I200J0D01*
G02Y1492204I-1661J-1458D01*
G03X1488580Y1492072I150J-132D01*
G01Y1491451D01*
G02X1488378Y1491248I-202J-1D01*
G01X1485558D01*
G02X1485356Y1491451I1J203D01*
G01Y1492072D01*
G03X1485306Y1492204I-200J0D01*
G02Y1495120I1661J1458D01*
G03X1485356Y1495252I-150J132D01*
G01Y1497190D01*
G03X1485306Y1497322I-200J0D01*
G02Y1500238I1661J1458D01*
G03X1485356Y1500370I-150J132D01*
G01Y1500989D01*
G02X1485558Y1501192I202J1D01*
G37*
G36*
G01X1502881D02*
X1505701D01*
G02X1505904Y1500989I0J-203D01*
G01Y1500368D01*
G03X1505954Y1500236I200J0D01*
G02Y1497324I-1664J-1456D01*
G03X1505904Y1497192I150J-132D01*
G01Y1495250D01*
G03X1505954Y1495118I200J0D01*
G02Y1492206I-1664J-1456D01*
G03X1505904Y1492074I150J-132D01*
G01Y1491451D01*
G02X1505701Y1491248I-203J0D01*
G01X1502881D01*
G02X1502678Y1491451I0J203D01*
G01Y1492074D01*
G03X1502628Y1492206I-200J0D01*
G02Y1495118I1664J1456D01*
G03X1502678Y1495250I-150J132D01*
G01Y1497192D01*
G03X1502628Y1497324I-200J0D01*
G02Y1500236I1664J1456D01*
G03X1502678Y1500368I-150J132D01*
G01Y1500989D01*
G02X1502881Y1501192I203J0D01*
G37*
G36*
G01X1520204D02*
X1523024D01*
G02X1523226Y1500989I-1J-203D01*
G01Y1500370D01*
G03X1523276Y1500238I200J0D01*
G02Y1497322I-1661J-1458D01*
G03X1523226Y1497190I150J-132D01*
G01Y1495252D01*
G03X1523276Y1495120I200J0D01*
G02Y1492204I-1661J-1458D01*
G03X1523226Y1492072I150J-132D01*
G01Y1491451D01*
G02X1523024Y1491248I-202J-1D01*
G01X1520204D01*
G02X1520002Y1491451I1J203D01*
G01Y1492072D01*
G03X1519952Y1492204I-200J0D01*
G02Y1495120I1661J1458D01*
G03X1520002Y1495252I-150J132D01*
G01Y1497190D01*
G03X1519952Y1497322I-200J0D01*
G02Y1500238I1661J1458D01*
G03X1520002Y1500370I-150J132D01*
G01Y1500989D01*
G02X1520204Y1501192I202J1D01*
G37*
G36*
G01X1537527D02*
X1540347D01*
G02X1540550Y1500989I0J-203D01*
G01Y1500368D01*
G03X1540600Y1500236I200J0D01*
G02Y1497324I-1664J-1456D01*
G03X1540550Y1497192I150J-132D01*
G01Y1495250D01*
G03X1540600Y1495118I200J0D01*
G02Y1492206I-1664J-1456D01*
G03X1540550Y1492074I150J-132D01*
G01Y1491451D01*
G02X1540347Y1491248I-203J0D01*
G01X1537527D01*
G02X1537324Y1491451I0J203D01*
G01Y1492074D01*
G03X1537274Y1492206I-200J0D01*
G02Y1495118I1664J1456D01*
G03X1537324Y1495250I-150J132D01*
G01Y1497192D01*
G03X1537274Y1497324I-200J0D01*
G02Y1500236I1664J1456D01*
G03X1537324Y1500368I-150J132D01*
G01Y1500989D01*
G02X1537527Y1501192I203J0D01*
G37*
G36*
G01X1693432D02*
X1696252D01*
G02X1696454Y1500989I-1J-203D01*
G01Y1500370D01*
G03X1696504Y1500238I200J0D01*
G02Y1497322I-1661J-1458D01*
G03X1696454Y1497190I150J-132D01*
G01Y1495252D01*
G03X1696504Y1495120I200J0D01*
G02Y1492204I-1661J-1458D01*
G03X1696454Y1492072I150J-132D01*
G01Y1491451D01*
G02X1696252Y1491248I-202J-1D01*
G01X1693432D01*
G02X1693230Y1491451I1J203D01*
G01Y1492072D01*
G03X1693180Y1492204I-200J0D01*
G02Y1495120I1661J1458D01*
G03X1693230Y1495252I-150J132D01*
G01Y1497190D01*
G03X1693180Y1497322I-200J0D01*
G02Y1500238I1661J1458D01*
G03X1693230Y1500370I-150J132D01*
G01Y1500989D01*
G02X1693432Y1501192I202J1D01*
G37*
G36*
G01X1710755D02*
X1713575D01*
G02X1713778Y1500989I0J-203D01*
G01Y1500368D01*
G03X1713828Y1500236I200J0D01*
G02Y1497324I-1664J-1456D01*
G03X1713778Y1497192I150J-132D01*
G01Y1495250D01*
G03X1713828Y1495118I200J0D01*
G02Y1492206I-1664J-1456D01*
G03X1713778Y1492074I150J-132D01*
G01Y1491451D01*
G02X1713575Y1491248I-203J0D01*
G01X1710755D01*
G02X1710552Y1491451I0J203D01*
G01Y1492074D01*
G03X1710502Y1492206I-200J0D01*
G02Y1495118I1664J1456D01*
G03X1710552Y1495250I-150J132D01*
G01Y1497192D01*
G03X1710502Y1497324I-200J0D01*
G02Y1500236I1664J1456D01*
G03X1710552Y1500368I-150J132D01*
G01Y1500989D01*
G02X1710755Y1501192I203J0D01*
G37*
G36*
G01X143118Y1512216D02*
X145938D01*
G02X146140Y1512014I0J-202D01*
G01Y1511394D01*
G03X146190Y1511262I200J0D01*
G02Y1508346I-1661J-1458D01*
G03X146140Y1508214I150J-132D01*
G01Y1506275D01*
G03X146190Y1506143I200J0D01*
G02Y1503227I-1661J-1458D01*
G03X146140Y1503095I150J-132D01*
G01Y1502476D01*
G02X145938Y1502274I-202J0D01*
G01X143118D01*
G02X142916Y1502476I0J202D01*
G01Y1503095D01*
G03X142866Y1503227I-200J0D01*
G02Y1506143I1661J1458D01*
G03X142916Y1506275I-150J132D01*
G01Y1508214D01*
G03X142866Y1508346I-200J0D01*
G02Y1511262I1661J1458D01*
G03X142916Y1511394I-150J132D01*
G01Y1512014D01*
G02X143118Y1512216I202J0D01*
G37*
G36*
G01X160440D02*
X163260D01*
G02X163462Y1512014I0J-202D01*
G01Y1511394D01*
G03X163512Y1511262I200J0D01*
G02Y1508346I-1661J-1458D01*
G03X163462Y1508214I150J-132D01*
G01Y1506275D01*
G03X163512Y1506143I200J0D01*
G02Y1503227I-1661J-1458D01*
G03X163462Y1503095I150J-132D01*
G01Y1502476D01*
G02X163260Y1502274I-202J0D01*
G01X160440D01*
G02X160238Y1502476I0J202D01*
G01Y1503095D01*
G03X160188Y1503227I-200J0D01*
G02Y1506143I1661J1458D01*
G03X160238Y1506275I-150J132D01*
G01Y1508214D01*
G03X160188Y1508346I-200J0D01*
G02Y1511262I1661J1458D01*
G03X160238Y1511394I-150J132D01*
G01Y1512014D01*
G02X160440Y1512216I202J0D01*
G37*
G36*
G01X281700D02*
X284520D01*
G02X284722Y1512014I0J-202D01*
G01Y1511394D01*
G03X284772Y1511262I200J0D01*
G02Y1508346I-1661J-1458D01*
G03X284722Y1508214I150J-132D01*
G01Y1506275D01*
G03X284772Y1506143I200J0D01*
G02Y1503227I-1661J-1458D01*
G03X284722Y1503095I150J-132D01*
G01Y1502476D01*
G02X284520Y1502274I-202J0D01*
G01X281700D01*
G02X281498Y1502476I0J202D01*
G01Y1503095D01*
G03X281448Y1503227I-200J0D01*
G02Y1506143I1661J1458D01*
G03X281498Y1506275I-150J132D01*
G01Y1508214D01*
G03X281448Y1508346I-200J0D01*
G02Y1511262I1661J1458D01*
G03X281498Y1511394I-150J132D01*
G01Y1512014D01*
G02X281700Y1512216I202J0D01*
G37*
G36*
G01X472252D02*
X475072D01*
G02X475274Y1512014I0J-202D01*
G01Y1511394D01*
G03X475324Y1511262I200J0D01*
G02Y1508346I-1661J-1458D01*
G03X475274Y1508214I150J-132D01*
G01Y1506275D01*
G03X475324Y1506143I200J0D01*
G02Y1503227I-1661J-1458D01*
G03X475274Y1503095I150J-132D01*
G01Y1502476D01*
G02X475072Y1502274I-202J0D01*
G01X472252D01*
G02X472050Y1502476I0J202D01*
G01Y1503095D01*
G03X472000Y1503227I-200J0D01*
G02Y1506143I1661J1458D01*
G03X472050Y1506275I-150J132D01*
G01Y1508214D01*
G03X472000Y1508346I-200J0D01*
G02Y1511262I1661J1458D01*
G03X472050Y1511394I-150J132D01*
G01Y1512014D01*
G02X472252Y1512216I202J0D01*
G37*
G36*
G01X645480D02*
X648300D01*
G02X648502Y1512014I0J-202D01*
G01Y1511394D01*
G03X648552Y1511262I200J0D01*
G02Y1508346I-1661J-1458D01*
G03X648502Y1508214I150J-132D01*
G01Y1506275D01*
G03X648552Y1506143I200J0D01*
G02Y1503227I-1661J-1458D01*
G03X648502Y1503095I150J-132D01*
G01Y1502476D01*
G02X648300Y1502274I-202J0D01*
G01X645480D01*
G02X645278Y1502476I0J202D01*
G01Y1503095D01*
G03X645228Y1503227I-200J0D01*
G02Y1506143I1661J1458D01*
G03X645278Y1506275I-150J132D01*
G01Y1508214D01*
G03X645228Y1508346I-200J0D01*
G02Y1511262I1661J1458D01*
G03X645278Y1511394I-150J132D01*
G01Y1512014D01*
G02X645480Y1512216I202J0D01*
G37*
G36*
G01X1165086D02*
X1167906D01*
G02X1168108Y1512014I0J-202D01*
G01Y1511394D01*
G03X1168158Y1511262I200J0D01*
G02Y1508346I-1661J-1458D01*
G03X1168108Y1508214I150J-132D01*
G01Y1506275D01*
G03X1168158Y1506143I200J0D01*
G02Y1503227I-1661J-1458D01*
G03X1168108Y1503095I150J-132D01*
G01Y1502476D01*
G02X1167906Y1502274I-202J0D01*
G01X1165086D01*
G02X1164884Y1502476I0J202D01*
G01Y1503095D01*
G03X1164834Y1503227I-200J0D01*
G02Y1506143I1661J1458D01*
G03X1164884Y1506275I-150J132D01*
G01Y1508214D01*
G03X1164834Y1508346I-200J0D01*
G02Y1511262I1661J1458D01*
G03X1164884Y1511394I-150J132D01*
G01Y1512014D01*
G02X1165086Y1512216I202J0D01*
G37*
G36*
G01X1182408D02*
X1185228D01*
G02X1185430Y1512014I0J-202D01*
G01Y1511394D01*
G03X1185480Y1511262I200J0D01*
G02Y1508346I-1661J-1458D01*
G03X1185430Y1508214I150J-132D01*
G01Y1506275D01*
G03X1185480Y1506143I200J0D01*
G02Y1503227I-1661J-1458D01*
G03X1185430Y1503095I150J-132D01*
G01Y1502476D01*
G02X1185228Y1502274I-202J0D01*
G01X1182408D01*
G02X1182206Y1502476I0J202D01*
G01Y1503095D01*
G03X1182156Y1503227I-200J0D01*
G02Y1506143I1661J1458D01*
G03X1182206Y1506275I-150J132D01*
G01Y1508214D01*
G03X1182156Y1508346I-200J0D01*
G02Y1511262I1661J1458D01*
G03X1182206Y1511394I-150J132D01*
G01Y1512014D01*
G02X1182408Y1512216I202J0D01*
G37*
G36*
G01X1320992D02*
X1323812D01*
G02X1324014Y1512014I0J-202D01*
G01Y1511394D01*
G03X1324064Y1511262I200J0D01*
G02Y1508346I-1661J-1458D01*
G03X1324014Y1508214I150J-132D01*
G01Y1506275D01*
G03X1324064Y1506143I200J0D01*
G02Y1503227I-1661J-1458D01*
G03X1324014Y1503095I150J-132D01*
G01Y1502476D01*
G02X1323812Y1502274I-202J0D01*
G01X1320992D01*
G02X1320790Y1502476I0J202D01*
G01Y1503095D01*
G03X1320740Y1503227I-200J0D01*
G02Y1506143I1661J1458D01*
G03X1320790Y1506275I-150J132D01*
G01Y1508214D01*
G03X1320740Y1508346I-200J0D01*
G02Y1511262I1661J1458D01*
G03X1320790Y1511394I-150J132D01*
G01Y1512014D01*
G02X1320992Y1512216I202J0D01*
G37*
G36*
G01X1494220D02*
X1497040D01*
G02X1497242Y1512014I0J-202D01*
G01Y1511394D01*
G03X1497292Y1511262I200J0D01*
G02Y1508346I-1661J-1458D01*
G03X1497242Y1508214I150J-132D01*
G01Y1506275D01*
G03X1497292Y1506143I200J0D01*
G02Y1503227I-1661J-1458D01*
G03X1497242Y1503095I150J-132D01*
G01Y1502476D01*
G02X1497040Y1502274I-202J0D01*
G01X1494220D01*
G02X1494018Y1502476I0J202D01*
G01Y1503095D01*
G03X1493968Y1503227I-200J0D01*
G02Y1506143I1661J1458D01*
G03X1494018Y1506275I-150J132D01*
G01Y1508214D01*
G03X1493968Y1508346I-200J0D01*
G02Y1511262I1661J1458D01*
G03X1494018Y1511394I-150J132D01*
G01Y1512014D01*
G02X1494220Y1512216I202J0D01*
G37*
G36*
G01X125795D02*
X128615D01*
G02X128818Y1512014I1J-202D01*
G01Y1511392D01*
G03X128868Y1511260I200J0D01*
G02Y1508348I-1664J-1456D01*
G03X128818Y1508216I150J-132D01*
G01Y1506273D01*
G03X128868Y1506141I200J0D01*
G02Y1503229I-1664J-1456D01*
G03X128818Y1503097I150J-132D01*
G01Y1502476D01*
G02X128615Y1502274I-203J1D01*
G01X125795D01*
G02X125592Y1502476I-1J202D01*
G01Y1503097D01*
G03X125542Y1503229I-200J0D01*
G02Y1506141I1664J1456D01*
G03X125592Y1506273I-150J132D01*
G01Y1508216D01*
G03X125542Y1508348I-200J0D01*
G02Y1511260I1664J1456D01*
G03X125592Y1511392I-150J132D01*
G01Y1512014D01*
G02X125795Y1512216I203J-1D01*
G37*
G36*
G01X299023D02*
X301843D01*
G02X302046Y1512014I1J-202D01*
G01Y1511392D01*
G03X302096Y1511260I200J0D01*
G02Y1508348I-1664J-1456D01*
G03X302046Y1508216I150J-132D01*
G01Y1506273D01*
G03X302096Y1506141I200J0D01*
G02Y1503229I-1664J-1456D01*
G03X302046Y1503097I150J-132D01*
G01Y1502476D01*
G02X301843Y1502274I-203J1D01*
G01X299023D01*
G02X298820Y1502476I-1J202D01*
G01Y1503097D01*
G03X298770Y1503229I-200J0D01*
G02Y1506141I1664J1456D01*
G03X298820Y1506273I-150J132D01*
G01Y1508216D01*
G03X298770Y1508348I-200J0D01*
G02Y1511260I1664J1456D01*
G03X298820Y1511392I-150J132D01*
G01Y1512014D01*
G02X299023Y1512216I203J-1D01*
G37*
G36*
G01X454929D02*
X457749D01*
G02X457952Y1512014I1J-202D01*
G01Y1511392D01*
G03X458002Y1511260I200J0D01*
G02Y1508348I-1664J-1456D01*
G03X457952Y1508216I150J-132D01*
G01Y1506273D01*
G03X458002Y1506141I200J0D01*
G02Y1503229I-1664J-1456D01*
G03X457952Y1503097I150J-132D01*
G01Y1502476D01*
G02X457749Y1502274I-203J1D01*
G01X454929D01*
G02X454726Y1502476I-1J202D01*
G01Y1503097D01*
G03X454676Y1503229I-200J0D01*
G02Y1506141I1664J1456D01*
G03X454726Y1506273I-150J132D01*
G01Y1508216D01*
G03X454676Y1508348I-200J0D01*
G02Y1511260I1664J1456D01*
G03X454726Y1511392I-150J132D01*
G01Y1512014D01*
G02X454929Y1512216I203J-1D01*
G37*
G36*
G01X489575D02*
X492395D01*
G02X492598Y1512014I1J-202D01*
G01Y1511392D01*
G03X492648Y1511260I200J0D01*
G02Y1508348I-1664J-1456D01*
G03X492598Y1508216I150J-132D01*
G01Y1506273D01*
G03X492648Y1506141I200J0D01*
G02Y1503229I-1664J-1456D01*
G03X492598Y1503097I150J-132D01*
G01Y1502476D01*
G02X492395Y1502274I-203J1D01*
G01X489575D01*
G02X489372Y1502476I-1J202D01*
G01Y1503097D01*
G03X489322Y1503229I-200J0D01*
G02Y1506141I1664J1456D01*
G03X489372Y1506273I-150J132D01*
G01Y1508216D01*
G03X489322Y1508348I-200J0D01*
G02Y1511260I1664J1456D01*
G03X489372Y1511392I-150J132D01*
G01Y1512014D01*
G02X489575Y1512216I203J-1D01*
G37*
G36*
G01X506897D02*
X509717D01*
G02X509920Y1512014I1J-202D01*
G01Y1511392D01*
G03X509970Y1511260I200J0D01*
G02Y1508348I-1664J-1456D01*
G03X509920Y1508216I150J-132D01*
G01Y1506273D01*
G03X509970Y1506141I200J0D01*
G02Y1503229I-1664J-1456D01*
G03X509920Y1503097I150J-132D01*
G01Y1502476D01*
G02X509717Y1502274I-203J1D01*
G01X506897D01*
G02X506694Y1502476I-1J202D01*
G01Y1503097D01*
G03X506644Y1503229I-200J0D01*
G02Y1506141I1664J1456D01*
G03X506694Y1506273I-150J132D01*
G01Y1508216D01*
G03X506644Y1508348I-200J0D01*
G02Y1511260I1664J1456D01*
G03X506694Y1511392I-150J132D01*
G01Y1512014D01*
G02X506897Y1512216I203J-1D01*
G37*
G36*
G01X662803D02*
X665623D01*
G02X665826Y1512014I1J-202D01*
G01Y1511392D01*
G03X665876Y1511260I200J0D01*
G02Y1508348I-1664J-1456D01*
G03X665826Y1508216I150J-132D01*
G01Y1506273D01*
G03X665876Y1506141I200J0D01*
G02Y1503229I-1664J-1456D01*
G03X665826Y1503097I150J-132D01*
G01Y1502476D01*
G02X665623Y1502274I-203J1D01*
G01X662803D01*
G02X662600Y1502476I-1J202D01*
G01Y1503097D01*
G03X662550Y1503229I-200J0D01*
G02Y1506141I1664J1456D01*
G03X662600Y1506273I-150J132D01*
G01Y1508216D01*
G03X662550Y1508348I-200J0D01*
G02Y1511260I1664J1456D01*
G03X662600Y1511392I-150J132D01*
G01Y1512014D01*
G02X662803Y1512216I203J-1D01*
G37*
G36*
G01X680125D02*
X682945D01*
G02X683148Y1512014I1J-202D01*
G01Y1511392D01*
G03X683198Y1511260I200J0D01*
G02Y1508348I-1664J-1456D01*
G03X683148Y1508216I150J-132D01*
G01Y1506273D01*
G03X683198Y1506141I200J0D01*
G02Y1503229I-1664J-1456D01*
G03X683148Y1503097I150J-132D01*
G01Y1502476D01*
G02X682945Y1502274I-203J1D01*
G01X680125D01*
G02X679922Y1502476I-1J202D01*
G01Y1503097D01*
G03X679872Y1503229I-200J0D01*
G02Y1506141I1664J1456D01*
G03X679922Y1506273I-150J132D01*
G01Y1508216D01*
G03X679872Y1508348I-200J0D01*
G02Y1511260I1664J1456D01*
G03X679922Y1511392I-150J132D01*
G01Y1512014D01*
G02X680125Y1512216I203J-1D01*
G37*
G36*
G01X1303669D02*
X1306489D01*
G02X1306692Y1512014I1J-202D01*
G01Y1511392D01*
G03X1306742Y1511260I200J0D01*
G02Y1508348I-1664J-1456D01*
G03X1306692Y1508216I150J-132D01*
G01Y1506273D01*
G03X1306742Y1506141I200J0D01*
G02Y1503229I-1664J-1456D01*
G03X1306692Y1503097I150J-132D01*
G01Y1502476D01*
G02X1306489Y1502274I-203J1D01*
G01X1303669D01*
G02X1303466Y1502476I-1J202D01*
G01Y1503097D01*
G03X1303416Y1503229I-200J0D01*
G02Y1506141I1664J1456D01*
G03X1303466Y1506273I-150J132D01*
G01Y1508216D01*
G03X1303416Y1508348I-200J0D01*
G02Y1511260I1664J1456D01*
G03X1303466Y1511392I-150J132D01*
G01Y1512014D01*
G02X1303669Y1512216I203J-1D01*
G37*
G36*
G01X1338315D02*
X1341135D01*
G02X1341338Y1512014I1J-202D01*
G01Y1511392D01*
G03X1341388Y1511260I200J0D01*
G02Y1508348I-1664J-1456D01*
G03X1341338Y1508216I150J-132D01*
G01Y1506273D01*
G03X1341388Y1506141I200J0D01*
G02Y1503229I-1664J-1456D01*
G03X1341338Y1503097I150J-132D01*
G01Y1502476D01*
G02X1341135Y1502274I-203J1D01*
G01X1338315D01*
G02X1338112Y1502476I-1J202D01*
G01Y1503097D01*
G03X1338062Y1503229I-200J0D01*
G02Y1506141I1664J1456D01*
G03X1338112Y1506273I-150J132D01*
G01Y1508216D01*
G03X1338062Y1508348I-200J0D01*
G02Y1511260I1664J1456D01*
G03X1338112Y1511392I-150J132D01*
G01Y1512014D01*
G02X1338315Y1512216I203J-1D01*
G37*
G36*
G01X1355637D02*
X1358457D01*
G02X1358660Y1512014I1J-202D01*
G01Y1511392D01*
G03X1358710Y1511260I200J0D01*
G02Y1508348I-1664J-1456D01*
G03X1358660Y1508216I150J-132D01*
G01Y1506273D01*
G03X1358710Y1506141I200J0D01*
G02Y1503229I-1664J-1456D01*
G03X1358660Y1503097I150J-132D01*
G01Y1502476D01*
G02X1358457Y1502274I-203J1D01*
G01X1355637D01*
G02X1355434Y1502476I-1J202D01*
G01Y1503097D01*
G03X1355384Y1503229I-200J0D01*
G02Y1506141I1664J1456D01*
G03X1355434Y1506273I-150J132D01*
G01Y1508216D01*
G03X1355384Y1508348I-200J0D01*
G02Y1511260I1664J1456D01*
G03X1355434Y1511392I-150J132D01*
G01Y1512014D01*
G02X1355637Y1512216I203J-1D01*
G37*
G36*
G01X1476897D02*
X1479717D01*
G02X1479920Y1512014I1J-202D01*
G01Y1511392D01*
G03X1479970Y1511260I200J0D01*
G02Y1508348I-1664J-1456D01*
G03X1479920Y1508216I150J-132D01*
G01Y1506273D01*
G03X1479970Y1506141I200J0D01*
G02Y1503229I-1664J-1456D01*
G03X1479920Y1503097I150J-132D01*
G01Y1502476D01*
G02X1479717Y1502274I-203J1D01*
G01X1476897D01*
G02X1476694Y1502476I-1J202D01*
G01Y1503097D01*
G03X1476644Y1503229I-200J0D01*
G02Y1506141I1664J1456D01*
G03X1476694Y1506273I-150J132D01*
G01Y1508216D01*
G03X1476644Y1508348I-200J0D01*
G02Y1511260I1664J1456D01*
G03X1476694Y1511392I-150J132D01*
G01Y1512014D01*
G02X1476897Y1512216I203J-1D01*
G37*
G36*
G01X1511543D02*
X1514363D01*
G02X1514566Y1512014I1J-202D01*
G01Y1511392D01*
G03X1514616Y1511260I200J0D01*
G02Y1508348I-1664J-1456D01*
G03X1514566Y1508216I150J-132D01*
G01Y1506273D01*
G03X1514616Y1506141I200J0D01*
G02Y1503229I-1664J-1456D01*
G03X1514566Y1503097I150J-132D01*
G01Y1502476D01*
G02X1514363Y1502274I-203J1D01*
G01X1511543D01*
G02X1511340Y1502476I-1J202D01*
G01Y1503097D01*
G03X1511290Y1503229I-200J0D01*
G02Y1506141I1664J1456D01*
G03X1511340Y1506273I-150J132D01*
G01Y1508216D01*
G03X1511290Y1508348I-200J0D01*
G02Y1511260I1664J1456D01*
G03X1511340Y1511392I-150J132D01*
G01Y1512014D01*
G02X1511543Y1512216I203J-1D01*
G37*
G36*
G01X1528865D02*
X1531685D01*
G02X1531888Y1512014I1J-202D01*
G01Y1511392D01*
G03X1531938Y1511260I200J0D01*
G02Y1508348I-1664J-1456D01*
G03X1531888Y1508216I150J-132D01*
G01Y1506273D01*
G03X1531938Y1506141I200J0D01*
G02Y1503229I-1664J-1456D01*
G03X1531888Y1503097I150J-132D01*
G01Y1502476D01*
G02X1531685Y1502274I-203J1D01*
G01X1528865D01*
G02X1528662Y1502476I-1J202D01*
G01Y1503097D01*
G03X1528612Y1503229I-200J0D01*
G02Y1506141I1664J1456D01*
G03X1528662Y1506273I-150J132D01*
G01Y1508216D01*
G03X1528612Y1508348I-200J0D01*
G02Y1511260I1664J1456D01*
G03X1528662Y1511392I-150J132D01*
G01Y1512014D01*
G02X1528865Y1512216I203J-1D01*
G37*
G36*
G01X1684771D02*
X1687591D01*
G02X1687794Y1512014I1J-202D01*
G01Y1511392D01*
G03X1687844Y1511260I200J0D01*
G02Y1508348I-1664J-1456D01*
G03X1687794Y1508216I150J-132D01*
G01Y1506273D01*
G03X1687844Y1506141I200J0D01*
G02Y1503229I-1664J-1456D01*
G03X1687794Y1503097I150J-132D01*
G01Y1502476D01*
G02X1687591Y1502274I-203J1D01*
G01X1684771D01*
G02X1684568Y1502476I-1J202D01*
G01Y1503097D01*
G03X1684518Y1503229I-200J0D01*
G02Y1506141I1664J1456D01*
G03X1684568Y1506273I-150J132D01*
G01Y1508216D01*
G03X1684518Y1508348I-200J0D01*
G02Y1511260I1664J1456D01*
G03X1684568Y1511392I-150J132D01*
G01Y1512014D01*
G02X1684771Y1512216I203J-1D01*
G37*
G36*
G01X1702093D02*
X1704913D01*
G02X1705116Y1512014I1J-202D01*
G01Y1511392D01*
G03X1705166Y1511260I200J0D01*
G02Y1508348I-1664J-1456D01*
G03X1705116Y1508216I150J-132D01*
G01Y1506273D01*
G03X1705166Y1506141I200J0D01*
G02Y1503229I-1664J-1456D01*
G03X1705116Y1503097I150J-132D01*
G01Y1502476D01*
G02X1704913Y1502274I-203J1D01*
G01X1702093D01*
G02X1701890Y1502476I-1J202D01*
G01Y1503097D01*
G03X1701840Y1503229I-200J0D01*
G02Y1506141I1664J1456D01*
G03X1701890Y1506273I-150J132D01*
G01Y1508216D01*
G03X1701840Y1508348I-200J0D01*
G02Y1511260I1664J1456D01*
G03X1701890Y1511392I-150J132D01*
G01Y1512014D01*
G02X1702093Y1512216I203J-1D01*
G37*
G36*
G01X134456Y1516546D02*
X137276D01*
G02X137478Y1516344I0J-202D01*
G01Y1515724D01*
G03X137528Y1515592I200J0D01*
G02Y1512676I-1661J-1458D01*
G03X137478Y1512544I150J-132D01*
G01Y1510606D01*
G03X137528Y1510474I200J0D01*
G02Y1507558I-1661J-1458D01*
G03X137478Y1507426I150J-132D01*
G01Y1506806D01*
G02X137276Y1506604I-202J0D01*
G01X134456D01*
G02X134254Y1506806I0J202D01*
G01Y1507426D01*
G03X134204Y1507558I-200J0D01*
G02Y1510474I1661J1458D01*
G03X134254Y1510606I-150J132D01*
G01Y1512544D01*
G03X134204Y1512676I-200J0D01*
G02Y1515592I1661J1458D01*
G03X134254Y1515724I-150J132D01*
G01Y1516344D01*
G02X134456Y1516546I202J0D01*
G37*
G36*
G01X169102D02*
X171922D01*
G02X172124Y1516344I0J-202D01*
G01Y1515724D01*
G03X172174Y1515592I200J0D01*
G02Y1512676I-1661J-1458D01*
G03X172124Y1512544I150J-132D01*
G01Y1510606D01*
G03X172174Y1510474I200J0D01*
G02Y1507558I-1661J-1458D01*
G03X172124Y1507426I150J-132D01*
G01Y1506806D01*
G02X171922Y1506604I-202J0D01*
G01X169102D01*
G02X168900Y1506806I0J202D01*
G01Y1507426D01*
G03X168850Y1507558I-200J0D01*
G02Y1510474I1661J1458D01*
G03X168900Y1510606I-150J132D01*
G01Y1512544D01*
G03X168850Y1512676I-200J0D01*
G02Y1515592I1661J1458D01*
G03X168900Y1515724I-150J132D01*
G01Y1516344D01*
G02X169102Y1516546I202J0D01*
G37*
G36*
G01X463590D02*
X466410D01*
G02X466612Y1516344I0J-202D01*
G01Y1515724D01*
G03X466662Y1515592I200J0D01*
G02Y1512676I-1661J-1458D01*
G03X466612Y1512544I150J-132D01*
G01Y1510606D01*
G03X466662Y1510474I200J0D01*
G02Y1507558I-1661J-1458D01*
G03X466612Y1507426I150J-132D01*
G01Y1506806D01*
G02X466410Y1506604I-202J0D01*
G01X463590D01*
G02X463388Y1506806I0J202D01*
G01Y1507426D01*
G03X463338Y1507558I-200J0D01*
G02Y1510474I1661J1458D01*
G03X463388Y1510606I-150J132D01*
G01Y1512544D01*
G03X463338Y1512676I-200J0D01*
G02Y1515592I1661J1458D01*
G03X463388Y1515724I-150J132D01*
G01Y1516344D01*
G02X463590Y1516546I202J0D01*
G37*
G36*
G01X498236D02*
X501056D01*
G02X501258Y1516344I0J-202D01*
G01Y1515724D01*
G03X501308Y1515592I200J0D01*
G02Y1512676I-1661J-1458D01*
G03X501258Y1512544I150J-132D01*
G01Y1510606D01*
G03X501308Y1510474I200J0D01*
G02Y1507558I-1661J-1458D01*
G03X501258Y1507426I150J-132D01*
G01Y1506806D01*
G02X501056Y1506604I-202J0D01*
G01X498236D01*
G02X498034Y1506806I0J202D01*
G01Y1507426D01*
G03X497984Y1507558I-200J0D01*
G02Y1510474I1661J1458D01*
G03X498034Y1510606I-150J132D01*
G01Y1512544D01*
G03X497984Y1512676I-200J0D01*
G02Y1515592I1661J1458D01*
G03X498034Y1515724I-150J132D01*
G01Y1516344D01*
G02X498236Y1516546I202J0D01*
G37*
G36*
G01X671464D02*
X674284D01*
G02X674486Y1516344I0J-202D01*
G01Y1515724D01*
G03X674536Y1515592I200J0D01*
G02Y1512676I-1661J-1458D01*
G03X674486Y1512544I150J-132D01*
G01Y1510606D01*
G03X674536Y1510474I200J0D01*
G02Y1507558I-1661J-1458D01*
G03X674486Y1507426I150J-132D01*
G01Y1506806D01*
G02X674284Y1506604I-202J0D01*
G01X671464D01*
G02X671262Y1506806I0J202D01*
G01Y1507426D01*
G03X671212Y1507558I-200J0D01*
G02Y1510474I1661J1458D01*
G03X671262Y1510606I-150J132D01*
G01Y1512544D01*
G03X671212Y1512676I-200J0D01*
G02Y1515592I1661J1458D01*
G03X671262Y1515724I-150J132D01*
G01Y1516344D01*
G02X671464Y1516546I202J0D01*
G37*
G36*
G01X1191070D02*
X1193890D01*
G02X1194092Y1516344I0J-202D01*
G01Y1515724D01*
G03X1194142Y1515592I200J0D01*
G02Y1512676I-1661J-1458D01*
G03X1194092Y1512544I150J-132D01*
G01Y1510606D01*
G03X1194142Y1510474I200J0D01*
G02Y1507558I-1661J-1458D01*
G03X1194092Y1507426I150J-132D01*
G01Y1506806D01*
G02X1193890Y1506604I-202J0D01*
G01X1191070D01*
G02X1190868Y1506806I0J202D01*
G01Y1507426D01*
G03X1190818Y1507558I-200J0D01*
G02Y1510474I1661J1458D01*
G03X1190868Y1510606I-150J132D01*
G01Y1512544D01*
G03X1190818Y1512676I-200J0D01*
G02Y1515592I1661J1458D01*
G03X1190868Y1515724I-150J132D01*
G01Y1516344D01*
G02X1191070Y1516546I202J0D01*
G37*
G36*
G01X1312330D02*
X1315150D01*
G02X1315352Y1516344I0J-202D01*
G01Y1515724D01*
G03X1315402Y1515592I200J0D01*
G02Y1512676I-1661J-1458D01*
G03X1315352Y1512544I150J-132D01*
G01Y1510606D01*
G03X1315402Y1510474I200J0D01*
G02Y1507558I-1661J-1458D01*
G03X1315352Y1507426I150J-132D01*
G01Y1506806D01*
G02X1315150Y1506604I-202J0D01*
G01X1312330D01*
G02X1312128Y1506806I0J202D01*
G01Y1507426D01*
G03X1312078Y1507558I-200J0D01*
G02Y1510474I1661J1458D01*
G03X1312128Y1510606I-150J132D01*
G01Y1512544D01*
G03X1312078Y1512676I-200J0D01*
G02Y1515592I1661J1458D01*
G03X1312128Y1515724I-150J132D01*
G01Y1516344D01*
G02X1312330Y1516546I202J0D01*
G37*
G36*
G01X1346976D02*
X1349796D01*
G02X1349998Y1516344I0J-202D01*
G01Y1515724D01*
G03X1350048Y1515592I200J0D01*
G02Y1512676I-1661J-1458D01*
G03X1349998Y1512544I150J-132D01*
G01Y1510606D01*
G03X1350048Y1510474I200J0D01*
G02Y1507558I-1661J-1458D01*
G03X1349998Y1507426I150J-132D01*
G01Y1506806D01*
G02X1349796Y1506604I-202J0D01*
G01X1346976D01*
G02X1346774Y1506806I0J202D01*
G01Y1507426D01*
G03X1346724Y1507558I-200J0D01*
G02Y1510474I1661J1458D01*
G03X1346774Y1510606I-150J132D01*
G01Y1512544D01*
G03X1346724Y1512676I-200J0D01*
G02Y1515592I1661J1458D01*
G03X1346774Y1515724I-150J132D01*
G01Y1516344D01*
G02X1346976Y1516546I202J0D01*
G37*
G36*
G01X1485558D02*
X1488378D01*
G02X1488580Y1516344I0J-202D01*
G01Y1515724D01*
G03X1488630Y1515592I200J0D01*
G02Y1512676I-1661J-1458D01*
G03X1488580Y1512544I150J-132D01*
G01Y1510606D01*
G03X1488630Y1510474I200J0D01*
G02Y1507558I-1661J-1458D01*
G03X1488580Y1507426I150J-132D01*
G01Y1506806D01*
G02X1488378Y1506604I-202J0D01*
G01X1485558D01*
G02X1485356Y1506806I0J202D01*
G01Y1507426D01*
G03X1485306Y1507558I-200J0D01*
G02Y1510474I1661J1458D01*
G03X1485356Y1510606I-150J132D01*
G01Y1512544D01*
G03X1485306Y1512676I-200J0D01*
G02Y1515592I1661J1458D01*
G03X1485356Y1515724I-150J132D01*
G01Y1516344D01*
G02X1485558Y1516546I202J0D01*
G37*
G36*
G01X1520204D02*
X1523024D01*
G02X1523226Y1516344I0J-202D01*
G01Y1515724D01*
G03X1523276Y1515592I200J0D01*
G02Y1512676I-1661J-1458D01*
G03X1523226Y1512544I150J-132D01*
G01Y1510606D01*
G03X1523276Y1510474I200J0D01*
G02Y1507558I-1661J-1458D01*
G03X1523226Y1507426I150J-132D01*
G01Y1506806D01*
G02X1523024Y1506604I-202J0D01*
G01X1520204D01*
G02X1520002Y1506806I0J202D01*
G01Y1507426D01*
G03X1519952Y1507558I-200J0D01*
G02Y1510474I1661J1458D01*
G03X1520002Y1510606I-150J132D01*
G01Y1512544D01*
G03X1519952Y1512676I-200J0D01*
G02Y1515592I1661J1458D01*
G03X1520002Y1515724I-150J132D01*
G01Y1516344D01*
G02X1520204Y1516546I202J0D01*
G37*
G36*
G01X1693432D02*
X1696252D01*
G02X1696454Y1516344I0J-202D01*
G01Y1515724D01*
G03X1696504Y1515592I200J0D01*
G02Y1512676I-1661J-1458D01*
G03X1696454Y1512544I150J-132D01*
G01Y1510606D01*
G03X1696504Y1510474I200J0D01*
G02Y1507558I-1661J-1458D01*
G03X1696454Y1507426I150J-132D01*
G01Y1506806D01*
G02X1696252Y1506604I-202J0D01*
G01X1693432D01*
G02X1693230Y1506806I0J202D01*
G01Y1507426D01*
G03X1693180Y1507558I-200J0D01*
G02Y1510474I1661J1458D01*
G03X1693230Y1510606I-150J132D01*
G01Y1512544D01*
G03X1693180Y1512676I-200J0D01*
G02Y1515592I1661J1458D01*
G03X1693230Y1515724I-150J132D01*
G01Y1516344D01*
G02X1693432Y1516546I202J0D01*
G37*
G36*
G01X151779D02*
X154599D01*
G02X154802Y1516344I1J-202D01*
G01Y1515722D01*
G03X154852Y1515590I200J0D01*
G02Y1512678I-1664J-1456D01*
G03X154802Y1512546I150J-132D01*
G01Y1510604D01*
G03X154852Y1510472I200J0D01*
G02Y1507560I-1664J-1456D01*
G03X154802Y1507428I150J-132D01*
G01Y1506806D01*
G02X154599Y1506604I-203J1D01*
G01X151779D01*
G02X151576Y1506806I-1J202D01*
G01Y1507428D01*
G03X151526Y1507560I-200J0D01*
G02Y1510472I1664J1456D01*
G03X151576Y1510604I-150J132D01*
G01Y1512546D01*
G03X151526Y1512678I-200J0D01*
G02Y1515590I1664J1456D01*
G03X151576Y1515722I-150J132D01*
G01Y1516344D01*
G02X151779Y1516546I203J-1D01*
G37*
G36*
G01X290361D02*
X293181D01*
G02X293384Y1516344I1J-202D01*
G01Y1515722D01*
G03X293434Y1515590I200J0D01*
G02Y1512678I-1664J-1456D01*
G03X293384Y1512546I150J-132D01*
G01Y1510604D01*
G03X293434Y1510472I200J0D01*
G02Y1507560I-1664J-1456D01*
G03X293384Y1507428I150J-132D01*
G01Y1506806D01*
G02X293181Y1506604I-203J1D01*
G01X290361D01*
G02X290158Y1506806I-1J202D01*
G01Y1507428D01*
G03X290108Y1507560I-200J0D01*
G02Y1510472I1664J1456D01*
G03X290158Y1510604I-150J132D01*
G01Y1512546D01*
G03X290108Y1512678I-200J0D01*
G02Y1515590I1664J1456D01*
G03X290158Y1515722I-150J132D01*
G01Y1516344D01*
G02X290361Y1516546I203J-1D01*
G37*
G36*
G01X480913D02*
X483733D01*
G02X483936Y1516344I1J-202D01*
G01Y1515722D01*
G03X483986Y1515590I200J0D01*
G02Y1512678I-1664J-1456D01*
G03X483936Y1512546I150J-132D01*
G01Y1510604D01*
G03X483986Y1510472I200J0D01*
G02Y1507560I-1664J-1456D01*
G03X483936Y1507428I150J-132D01*
G01Y1506806D01*
G02X483733Y1506604I-203J1D01*
G01X480913D01*
G02X480710Y1506806I-1J202D01*
G01Y1507428D01*
G03X480660Y1507560I-200J0D01*
G02Y1510472I1664J1456D01*
G03X480710Y1510604I-150J132D01*
G01Y1512546D01*
G03X480660Y1512678I-200J0D01*
G02Y1515590I1664J1456D01*
G03X480710Y1515722I-150J132D01*
G01Y1516344D01*
G02X480913Y1516546I203J-1D01*
G37*
G36*
G01X515559D02*
X518379D01*
G02X518582Y1516344I1J-202D01*
G01Y1515722D01*
G03X518632Y1515590I200J0D01*
G02Y1512678I-1664J-1456D01*
G03X518582Y1512546I150J-132D01*
G01Y1510604D01*
G03X518632Y1510472I200J0D01*
G02Y1507560I-1664J-1456D01*
G03X518582Y1507428I150J-132D01*
G01Y1506806D01*
G02X518379Y1506604I-203J1D01*
G01X515559D01*
G02X515356Y1506806I-1J202D01*
G01Y1507428D01*
G03X515306Y1507560I-200J0D01*
G02Y1510472I1664J1456D01*
G03X515356Y1510604I-150J132D01*
G01Y1512546D01*
G03X515306Y1512678I-200J0D01*
G02Y1515590I1664J1456D01*
G03X515356Y1515722I-150J132D01*
G01Y1516344D01*
G02X515559Y1516546I203J-1D01*
G37*
G36*
G01X654141D02*
X656961D01*
G02X657164Y1516344I1J-202D01*
G01Y1515722D01*
G03X657214Y1515590I200J0D01*
G02Y1512678I-1664J-1456D01*
G03X657164Y1512546I150J-132D01*
G01Y1510604D01*
G03X657214Y1510472I200J0D01*
G02Y1507560I-1664J-1456D01*
G03X657164Y1507428I150J-132D01*
G01Y1506806D01*
G02X656961Y1506604I-203J1D01*
G01X654141D01*
G02X653938Y1506806I-1J202D01*
G01Y1507428D01*
G03X653888Y1507560I-200J0D01*
G02Y1510472I1664J1456D01*
G03X653938Y1510604I-150J132D01*
G01Y1512546D01*
G03X653888Y1512678I-200J0D01*
G02Y1515590I1664J1456D01*
G03X653938Y1515722I-150J132D01*
G01Y1516344D01*
G02X654141Y1516546I203J-1D01*
G37*
G36*
G01X688787D02*
X691607D01*
G02X691810Y1516344I1J-202D01*
G01Y1515722D01*
G03X691860Y1515590I200J0D01*
G02Y1512678I-1664J-1456D01*
G03X691810Y1512546I150J-132D01*
G01Y1510604D01*
G03X691860Y1510472I200J0D01*
G02Y1507560I-1664J-1456D01*
G03X691810Y1507428I150J-132D01*
G01Y1506806D01*
G02X691607Y1506604I-203J1D01*
G01X688787D01*
G02X688584Y1506806I-1J202D01*
G01Y1507428D01*
G03X688534Y1507560I-200J0D01*
G02Y1510472I1664J1456D01*
G03X688584Y1510604I-150J132D01*
G01Y1512546D01*
G03X688534Y1512678I-200J0D01*
G02Y1515590I1664J1456D01*
G03X688584Y1515722I-150J132D01*
G01Y1516344D01*
G02X688787Y1516546I203J-1D01*
G37*
G36*
G01X1173747D02*
X1176567D01*
G02X1176770Y1516344I1J-202D01*
G01Y1515722D01*
G03X1176820Y1515590I200J0D01*
G02Y1512678I-1664J-1456D01*
G03X1176770Y1512546I150J-132D01*
G01Y1510604D01*
G03X1176820Y1510472I200J0D01*
G02Y1507560I-1664J-1456D01*
G03X1176770Y1507428I150J-132D01*
G01Y1506806D01*
G02X1176567Y1506604I-203J1D01*
G01X1173747D01*
G02X1173544Y1506806I-1J202D01*
G01Y1507428D01*
G03X1173494Y1507560I-200J0D01*
G02Y1510472I1664J1456D01*
G03X1173544Y1510604I-150J132D01*
G01Y1512546D01*
G03X1173494Y1512678I-200J0D01*
G02Y1515590I1664J1456D01*
G03X1173544Y1515722I-150J132D01*
G01Y1516344D01*
G02X1173747Y1516546I203J-1D01*
G37*
G36*
G01X1329653D02*
X1332473D01*
G02X1332676Y1516344I1J-202D01*
G01Y1515722D01*
G03X1332726Y1515590I200J0D01*
G02Y1512678I-1664J-1456D01*
G03X1332676Y1512546I150J-132D01*
G01Y1510604D01*
G03X1332726Y1510472I200J0D01*
G02Y1507560I-1664J-1456D01*
G03X1332676Y1507428I150J-132D01*
G01Y1506806D01*
G02X1332473Y1506604I-203J1D01*
G01X1329653D01*
G02X1329450Y1506806I-1J202D01*
G01Y1507428D01*
G03X1329400Y1507560I-200J0D01*
G02Y1510472I1664J1456D01*
G03X1329450Y1510604I-150J132D01*
G01Y1512546D01*
G03X1329400Y1512678I-200J0D01*
G02Y1515590I1664J1456D01*
G03X1329450Y1515722I-150J132D01*
G01Y1516344D01*
G02X1329653Y1516546I203J-1D01*
G37*
G36*
G01X1364299D02*
X1367119D01*
G02X1367322Y1516344I1J-202D01*
G01Y1515722D01*
G03X1367372Y1515590I200J0D01*
G02Y1512678I-1664J-1456D01*
G03X1367322Y1512546I150J-132D01*
G01Y1510604D01*
G03X1367372Y1510472I200J0D01*
G02Y1507560I-1664J-1456D01*
G03X1367322Y1507428I150J-132D01*
G01Y1506806D01*
G02X1367119Y1506604I-203J1D01*
G01X1364299D01*
G02X1364096Y1506806I-1J202D01*
G01Y1507428D01*
G03X1364046Y1507560I-200J0D01*
G02Y1510472I1664J1456D01*
G03X1364096Y1510604I-150J132D01*
G01Y1512546D01*
G03X1364046Y1512678I-200J0D01*
G02Y1515590I1664J1456D01*
G03X1364096Y1515722I-150J132D01*
G01Y1516344D01*
G02X1364299Y1516546I203J-1D01*
G37*
G36*
G01X1502881D02*
X1505701D01*
G02X1505904Y1516344I1J-202D01*
G01Y1515722D01*
G03X1505954Y1515590I200J0D01*
G02Y1512678I-1664J-1456D01*
G03X1505904Y1512546I150J-132D01*
G01Y1510604D01*
G03X1505954Y1510472I200J0D01*
G02Y1507560I-1664J-1456D01*
G03X1505904Y1507428I150J-132D01*
G01Y1506806D01*
G02X1505701Y1506604I-203J1D01*
G01X1502881D01*
G02X1502678Y1506806I-1J202D01*
G01Y1507428D01*
G03X1502628Y1507560I-200J0D01*
G02Y1510472I1664J1456D01*
G03X1502678Y1510604I-150J132D01*
G01Y1512546D01*
G03X1502628Y1512678I-200J0D01*
G02Y1515590I1664J1456D01*
G03X1502678Y1515722I-150J132D01*
G01Y1516344D01*
G02X1502881Y1516546I203J-1D01*
G37*
G36*
G01X1537527D02*
X1540347D01*
G02X1540550Y1516344I1J-202D01*
G01Y1515722D01*
G03X1540600Y1515590I200J0D01*
G02Y1512678I-1664J-1456D01*
G03X1540550Y1512546I150J-132D01*
G01Y1510604D01*
G03X1540600Y1510472I200J0D01*
G02Y1507560I-1664J-1456D01*
G03X1540550Y1507428I150J-132D01*
G01Y1506806D01*
G02X1540347Y1506604I-203J1D01*
G01X1537527D01*
G02X1537324Y1506806I-1J202D01*
G01Y1507428D01*
G03X1537274Y1507560I-200J0D01*
G02Y1510472I1664J1456D01*
G03X1537324Y1510604I-150J132D01*
G01Y1512546D01*
G03X1537274Y1512678I-200J0D01*
G02Y1515590I1664J1456D01*
G03X1537324Y1515722I-150J132D01*
G01Y1516344D01*
G02X1537527Y1516546I203J-1D01*
G37*
G36*
G01X1710755D02*
X1713575D01*
G02X1713778Y1516344I1J-202D01*
G01Y1515722D01*
G03X1713828Y1515590I200J0D01*
G02Y1512678I-1664J-1456D01*
G03X1713778Y1512546I150J-132D01*
G01Y1510604D01*
G03X1713828Y1510472I200J0D01*
G02Y1507560I-1664J-1456D01*
G03X1713778Y1507428I150J-132D01*
G01Y1506806D01*
G02X1713575Y1506604I-203J1D01*
G01X1710755D01*
G02X1710552Y1506806I-1J202D01*
G01Y1507428D01*
G03X1710502Y1507560I-200J0D01*
G02Y1510472I1664J1456D01*
G03X1710552Y1510604I-150J132D01*
G01Y1512546D01*
G03X1710502Y1512678I-200J0D01*
G02Y1515590I1664J1456D01*
G03X1710552Y1515722I-150J132D01*
G01Y1516344D01*
G02X1710755Y1516546I203J-1D01*
G37*
G36*
G01X108472Y1568516D02*
X111292D01*
G02X111494Y1568313I-1J-203D01*
G01Y1567693D01*
G03X111544Y1567561I200J0D01*
G02Y1564645I-1661J-1458D01*
G03X111494Y1564513I150J-132D01*
G01Y1562575D01*
G03X111544Y1562443I200J0D01*
G02Y1559527I-1661J-1458D01*
G03X111494Y1559395I150J-132D01*
G01Y1558775D01*
G02X111292Y1558572I-202J-1D01*
G01X108472D01*
G02X108270Y1558775I1J203D01*
G01Y1559395D01*
G03X108220Y1559527I-200J0D01*
G02Y1562443I1661J1458D01*
G03X108270Y1562575I-150J132D01*
G01Y1564513D01*
G03X108220Y1564645I-200J0D01*
G02Y1567561I1661J1458D01*
G03X108270Y1567693I-150J132D01*
G01Y1568313D01*
G02X108472Y1568516I202J1D01*
G37*
G36*
G01X125795D02*
X128615D01*
G02X128818Y1568313I0J-203D01*
G01Y1567691D01*
G03X128868Y1567559I200J0D01*
G02Y1564647I-1664J-1456D01*
G03X128818Y1564515I150J-132D01*
G01Y1562573D01*
G03X128868Y1562441I200J0D01*
G02Y1559529I-1664J-1456D01*
G03X128818Y1559397I150J-132D01*
G01Y1558775D01*
G02X128615Y1558572I-203J0D01*
G01X125795D01*
G02X125592Y1558775I0J203D01*
G01Y1559397D01*
G03X125542Y1559529I-200J0D01*
G02Y1562441I1664J1456D01*
G03X125592Y1562573I-150J132D01*
G01Y1564515D01*
G03X125542Y1564647I-200J0D01*
G02Y1567559I1664J1456D01*
G03X125592Y1567691I-150J132D01*
G01Y1568313D01*
G02X125795Y1568516I203J0D01*
G37*
G36*
G01X143118D02*
X145938D01*
G02X146140Y1568313I-1J-203D01*
G01Y1567693D01*
G03X146190Y1567561I200J0D01*
G02Y1564645I-1661J-1458D01*
G03X146140Y1564513I150J-132D01*
G01Y1562575D01*
G03X146190Y1562443I200J0D01*
G02Y1559527I-1661J-1458D01*
G03X146140Y1559395I150J-132D01*
G01Y1558775D01*
G02X145938Y1558572I-202J-1D01*
G01X143118D01*
G02X142916Y1558775I1J203D01*
G01Y1559395D01*
G03X142866Y1559527I-200J0D01*
G02Y1562443I1661J1458D01*
G03X142916Y1562575I-150J132D01*
G01Y1564513D01*
G03X142866Y1564645I-200J0D01*
G02Y1567561I1661J1458D01*
G03X142916Y1567693I-150J132D01*
G01Y1568313D01*
G02X143118Y1568516I202J1D01*
G37*
G36*
G01X160440D02*
X163260D01*
G02X163462Y1568313I-1J-203D01*
G01Y1567693D01*
G03X163512Y1567561I200J0D01*
G02Y1564645I-1661J-1458D01*
G03X163462Y1564513I150J-132D01*
G01Y1562575D01*
G03X163512Y1562443I200J0D01*
G02Y1559527I-1661J-1458D01*
G03X163462Y1559395I150J-132D01*
G01Y1558775D01*
G02X163260Y1558572I-202J-1D01*
G01X160440D01*
G02X160238Y1558775I1J203D01*
G01Y1559395D01*
G03X160188Y1559527I-200J0D01*
G02Y1562443I1661J1458D01*
G03X160238Y1562575I-150J132D01*
G01Y1564513D01*
G03X160188Y1564645I-200J0D01*
G02Y1567561I1661J1458D01*
G03X160238Y1567693I-150J132D01*
G01Y1568313D01*
G02X160440Y1568516I202J1D01*
G37*
G36*
G01X281700D02*
X284520D01*
G02X284722Y1568313I-1J-203D01*
G01Y1567693D01*
G03X284772Y1567561I200J0D01*
G02Y1564645I-1661J-1458D01*
G03X284722Y1564513I150J-132D01*
G01Y1562575D01*
G03X284772Y1562443I200J0D01*
G02Y1559527I-1661J-1458D01*
G03X284722Y1559395I150J-132D01*
G01Y1558775D01*
G02X284520Y1558572I-202J-1D01*
G01X281700D01*
G02X281498Y1558775I1J203D01*
G01Y1559395D01*
G03X281448Y1559527I-200J0D01*
G02Y1562443I1661J1458D01*
G03X281498Y1562575I-150J132D01*
G01Y1564513D01*
G03X281448Y1564645I-200J0D01*
G02Y1567561I1661J1458D01*
G03X281498Y1567693I-150J132D01*
G01Y1568313D01*
G02X281700Y1568516I202J1D01*
G37*
G36*
G01X299023D02*
X301843D01*
G02X302046Y1568313I0J-203D01*
G01Y1567691D01*
G03X302096Y1567559I200J0D01*
G02Y1564647I-1664J-1456D01*
G03X302046Y1564515I150J-132D01*
G01Y1562573D01*
G03X302096Y1562441I200J0D01*
G02Y1559529I-1664J-1456D01*
G03X302046Y1559397I150J-132D01*
G01Y1558775D01*
G02X301843Y1558572I-203J0D01*
G01X299023D01*
G02X298820Y1558775I0J203D01*
G01Y1559397D01*
G03X298770Y1559529I-200J0D01*
G02Y1562441I1664J1456D01*
G03X298820Y1562573I-150J132D01*
G01Y1564515D01*
G03X298770Y1564647I-200J0D01*
G02Y1567559I1664J1456D01*
G03X298820Y1567691I-150J132D01*
G01Y1568313D01*
G02X299023Y1568516I203J0D01*
G37*
G36*
G01X316346D02*
X319166D01*
G02X319368Y1568313I-1J-203D01*
G01Y1567693D01*
G03X319418Y1567561I200J0D01*
G02Y1564645I-1661J-1458D01*
G03X319368Y1564513I150J-132D01*
G01Y1562575D01*
G03X319418Y1562443I200J0D01*
G02Y1559527I-1661J-1458D01*
G03X319368Y1559395I150J-132D01*
G01Y1558775D01*
G02X319166Y1558572I-202J-1D01*
G01X316346D01*
G02X316144Y1558775I1J203D01*
G01Y1559395D01*
G03X316094Y1559527I-200J0D01*
G02Y1562443I1661J1458D01*
G03X316144Y1562575I-150J132D01*
G01Y1564513D01*
G03X316094Y1564645I-200J0D01*
G02Y1567561I1661J1458D01*
G03X316144Y1567693I-150J132D01*
G01Y1568313D01*
G02X316346Y1568516I202J1D01*
G37*
G36*
G01X333668D02*
X336488D01*
G02X336690Y1568313I-1J-203D01*
G01Y1567693D01*
G03X336740Y1567561I200J0D01*
G02Y1564645I-1661J-1458D01*
G03X336690Y1564513I150J-132D01*
G01Y1562575D01*
G03X336740Y1562443I200J0D01*
G02Y1559527I-1661J-1458D01*
G03X336690Y1559395I150J-132D01*
G01Y1558775D01*
G02X336488Y1558572I-202J-1D01*
G01X333668D01*
G02X333466Y1558775I1J203D01*
G01Y1559395D01*
G03X333416Y1559527I-200J0D01*
G02Y1562443I1661J1458D01*
G03X333466Y1562575I-150J132D01*
G01Y1564513D01*
G03X333416Y1564645I-200J0D01*
G02Y1567561I1661J1458D01*
G03X333466Y1567693I-150J132D01*
G01Y1568313D01*
G02X333668Y1568516I202J1D01*
G37*
G36*
G01X628157D02*
X630977D01*
G02X631180Y1568313I0J-203D01*
G01Y1567691D01*
G03X631230Y1567559I200J0D01*
G02Y1564647I-1664J-1456D01*
G03X631180Y1564515I150J-132D01*
G01Y1562573D01*
G03X631230Y1562441I200J0D01*
G02Y1559529I-1664J-1456D01*
G03X631180Y1559397I150J-132D01*
G01Y1558775D01*
G02X630977Y1558572I-203J0D01*
G01X628157D01*
G02X627954Y1558775I0J203D01*
G01Y1559397D01*
G03X627904Y1559529I-200J0D01*
G02Y1562441I1664J1456D01*
G03X627954Y1562573I-150J132D01*
G01Y1564515D01*
G03X627904Y1564647I-200J0D01*
G02Y1567559I1664J1456D01*
G03X627954Y1567691I-150J132D01*
G01Y1568313D01*
G02X628157Y1568516I203J0D01*
G37*
G36*
G01X645480D02*
X648300D01*
G02X648502Y1568313I-1J-203D01*
G01Y1567693D01*
G03X648552Y1567561I200J0D01*
G02Y1564645I-1661J-1458D01*
G03X648502Y1564513I150J-132D01*
G01Y1562575D01*
G03X648552Y1562443I200J0D01*
G02Y1559527I-1661J-1458D01*
G03X648502Y1559395I150J-132D01*
G01Y1558775D01*
G02X648300Y1558572I-202J-1D01*
G01X645480D01*
G02X645278Y1558775I1J203D01*
G01Y1559395D01*
G03X645228Y1559527I-200J0D01*
G02Y1562443I1661J1458D01*
G03X645278Y1562575I-150J132D01*
G01Y1564513D01*
G03X645228Y1564645I-200J0D01*
G02Y1567561I1661J1458D01*
G03X645278Y1567693I-150J132D01*
G01Y1568313D01*
G02X645480Y1568516I202J1D01*
G37*
G36*
G01X662803D02*
X665623D01*
G02X665826Y1568313I0J-203D01*
G01Y1567691D01*
G03X665876Y1567559I200J0D01*
G02Y1564647I-1664J-1456D01*
G03X665826Y1564515I150J-132D01*
G01Y1562573D01*
G03X665876Y1562441I200J0D01*
G02Y1559529I-1664J-1456D01*
G03X665826Y1559397I150J-132D01*
G01Y1558775D01*
G02X665623Y1558572I-203J0D01*
G01X662803D01*
G02X662600Y1558775I0J203D01*
G01Y1559397D01*
G03X662550Y1559529I-200J0D01*
G02Y1562441I1664J1456D01*
G03X662600Y1562573I-150J132D01*
G01Y1564515D01*
G03X662550Y1564647I-200J0D01*
G02Y1567559I1664J1456D01*
G03X662600Y1567691I-150J132D01*
G01Y1568313D01*
G02X662803Y1568516I203J0D01*
G37*
G36*
G01X680125D02*
X682945D01*
G02X683148Y1568313I0J-203D01*
G01Y1567691D01*
G03X683198Y1567559I200J0D01*
G02Y1564647I-1664J-1456D01*
G03X683148Y1564515I150J-132D01*
G01Y1562573D01*
G03X683198Y1562441I200J0D01*
G02Y1559529I-1664J-1456D01*
G03X683148Y1559397I150J-132D01*
G01Y1558775D01*
G02X682945Y1558572I-203J0D01*
G01X680125D01*
G02X679922Y1558775I0J203D01*
G01Y1559397D01*
G03X679872Y1559529I-200J0D01*
G02Y1562441I1664J1456D01*
G03X679922Y1562573I-150J132D01*
G01Y1564515D01*
G03X679872Y1564647I-200J0D01*
G02Y1567559I1664J1456D01*
G03X679922Y1567691I-150J132D01*
G01Y1568313D01*
G02X680125Y1568516I203J0D01*
G37*
G36*
G01X1130440D02*
X1133260D01*
G02X1133462Y1568313I-1J-203D01*
G01Y1567693D01*
G03X1133512Y1567561I200J0D01*
G02Y1564645I-1661J-1458D01*
G03X1133462Y1564513I150J-132D01*
G01Y1562575D01*
G03X1133512Y1562443I200J0D01*
G02Y1559527I-1661J-1458D01*
G03X1133462Y1559395I150J-132D01*
G01Y1558775D01*
G02X1133260Y1558572I-202J-1D01*
G01X1130440D01*
G02X1130238Y1558775I1J203D01*
G01Y1559395D01*
G03X1130188Y1559527I-200J0D01*
G02Y1562443I1661J1458D01*
G03X1130238Y1562575I-150J132D01*
G01Y1564513D01*
G03X1130188Y1564645I-200J0D01*
G02Y1567561I1661J1458D01*
G03X1130238Y1567693I-150J132D01*
G01Y1568313D01*
G02X1130440Y1568516I202J1D01*
G37*
G36*
G01X1147763D02*
X1150583D01*
G02X1150786Y1568313I0J-203D01*
G01Y1567691D01*
G03X1150836Y1567559I200J0D01*
G02Y1564647I-1664J-1456D01*
G03X1150786Y1564515I150J-132D01*
G01Y1562573D01*
G03X1150836Y1562441I200J0D01*
G02Y1559529I-1664J-1456D01*
G03X1150786Y1559397I150J-132D01*
G01Y1558775D01*
G02X1150583Y1558572I-203J0D01*
G01X1147763D01*
G02X1147560Y1558775I0J203D01*
G01Y1559397D01*
G03X1147510Y1559529I-200J0D01*
G02Y1562441I1664J1456D01*
G03X1147560Y1562573I-150J132D01*
G01Y1564515D01*
G03X1147510Y1564647I-200J0D01*
G02Y1567559I1664J1456D01*
G03X1147560Y1567691I-150J132D01*
G01Y1568313D01*
G02X1147763Y1568516I203J0D01*
G37*
G36*
G01X1165086D02*
X1167906D01*
G02X1168108Y1568313I-1J-203D01*
G01Y1567693D01*
G03X1168158Y1567561I200J0D01*
G02Y1564645I-1661J-1458D01*
G03X1168108Y1564513I150J-132D01*
G01Y1562575D01*
G03X1168158Y1562443I200J0D01*
G02Y1559527I-1661J-1458D01*
G03X1168108Y1559395I150J-132D01*
G01Y1558775D01*
G02X1167906Y1558572I-202J-1D01*
G01X1165086D01*
G02X1164884Y1558775I1J203D01*
G01Y1559395D01*
G03X1164834Y1559527I-200J0D01*
G02Y1562443I1661J1458D01*
G03X1164884Y1562575I-150J132D01*
G01Y1564513D01*
G03X1164834Y1564645I-200J0D01*
G02Y1567561I1661J1458D01*
G03X1164884Y1567693I-150J132D01*
G01Y1568313D01*
G02X1165086Y1568516I202J1D01*
G37*
G36*
G01X1182408D02*
X1185228D01*
G02X1185430Y1568313I-1J-203D01*
G01Y1567693D01*
G03X1185480Y1567561I200J0D01*
G02Y1564645I-1661J-1458D01*
G03X1185430Y1564513I150J-132D01*
G01Y1562575D01*
G03X1185480Y1562443I200J0D01*
G02Y1559527I-1661J-1458D01*
G03X1185430Y1559395I150J-132D01*
G01Y1558775D01*
G02X1185228Y1558572I-202J-1D01*
G01X1182408D01*
G02X1182206Y1558775I1J203D01*
G01Y1559395D01*
G03X1182156Y1559527I-200J0D01*
G02Y1562443I1661J1458D01*
G03X1182206Y1562575I-150J132D01*
G01Y1564513D01*
G03X1182156Y1564645I-200J0D01*
G02Y1567561I1661J1458D01*
G03X1182206Y1567693I-150J132D01*
G01Y1568313D01*
G02X1182408Y1568516I202J1D01*
G37*
G36*
G01X1303669D02*
X1306489D01*
G02X1306692Y1568313I0J-203D01*
G01Y1567691D01*
G03X1306742Y1567559I200J0D01*
G02Y1564647I-1664J-1456D01*
G03X1306692Y1564515I150J-132D01*
G01Y1562573D01*
G03X1306742Y1562441I200J0D01*
G02Y1559529I-1664J-1456D01*
G03X1306692Y1559397I150J-132D01*
G01Y1558775D01*
G02X1306489Y1558572I-203J0D01*
G01X1303669D01*
G02X1303466Y1558775I0J203D01*
G01Y1559397D01*
G03X1303416Y1559529I-200J0D01*
G02Y1562441I1664J1456D01*
G03X1303466Y1562573I-150J132D01*
G01Y1564515D01*
G03X1303416Y1564647I-200J0D01*
G02Y1567559I1664J1456D01*
G03X1303466Y1567691I-150J132D01*
G01Y1568313D01*
G02X1303669Y1568516I203J0D01*
G37*
G36*
G01X1320992D02*
X1323812D01*
G02X1324014Y1568313I-1J-203D01*
G01Y1567693D01*
G03X1324064Y1567561I200J0D01*
G02Y1564645I-1661J-1458D01*
G03X1324014Y1564513I150J-132D01*
G01Y1562575D01*
G03X1324064Y1562443I200J0D01*
G02Y1559527I-1661J-1458D01*
G03X1324014Y1559395I150J-132D01*
G01Y1558775D01*
G02X1323812Y1558572I-202J-1D01*
G01X1320992D01*
G02X1320790Y1558775I1J203D01*
G01Y1559395D01*
G03X1320740Y1559527I-200J0D01*
G02Y1562443I1661J1458D01*
G03X1320790Y1562575I-150J132D01*
G01Y1564513D01*
G03X1320740Y1564645I-200J0D01*
G02Y1567561I1661J1458D01*
G03X1320790Y1567693I-150J132D01*
G01Y1568313D01*
G02X1320992Y1568516I202J1D01*
G37*
G36*
G01X1338315D02*
X1341135D01*
G02X1341338Y1568313I0J-203D01*
G01Y1567691D01*
G03X1341388Y1567559I200J0D01*
G02Y1564647I-1664J-1456D01*
G03X1341338Y1564515I150J-132D01*
G01Y1562573D01*
G03X1341388Y1562441I200J0D01*
G02Y1559529I-1664J-1456D01*
G03X1341338Y1559397I150J-132D01*
G01Y1558775D01*
G02X1341135Y1558572I-203J0D01*
G01X1338315D01*
G02X1338112Y1558775I0J203D01*
G01Y1559397D01*
G03X1338062Y1559529I-200J0D01*
G02Y1562441I1664J1456D01*
G03X1338112Y1562573I-150J132D01*
G01Y1564515D01*
G03X1338062Y1564647I-200J0D01*
G02Y1567559I1664J1456D01*
G03X1338112Y1567691I-150J132D01*
G01Y1568313D01*
G02X1338315Y1568516I203J0D01*
G37*
G36*
G01X1355637D02*
X1358457D01*
G02X1358660Y1568313I0J-203D01*
G01Y1567691D01*
G03X1358710Y1567559I200J0D01*
G02Y1564647I-1664J-1456D01*
G03X1358660Y1564515I150J-132D01*
G01Y1562573D01*
G03X1358710Y1562441I200J0D01*
G02Y1559529I-1664J-1456D01*
G03X1358660Y1559397I150J-132D01*
G01Y1558775D01*
G02X1358457Y1558572I-203J0D01*
G01X1355637D01*
G02X1355434Y1558775I0J203D01*
G01Y1559397D01*
G03X1355384Y1559529I-200J0D01*
G02Y1562441I1664J1456D01*
G03X1355434Y1562573I-150J132D01*
G01Y1564515D01*
G03X1355384Y1564647I-200J0D01*
G02Y1567559I1664J1456D01*
G03X1355434Y1567691I-150J132D01*
G01Y1568313D01*
G02X1355637Y1568516I203J0D01*
G37*
G36*
G01X1476897D02*
X1479717D01*
G02X1479920Y1568313I0J-203D01*
G01Y1567691D01*
G03X1479970Y1567559I200J0D01*
G02Y1564647I-1664J-1456D01*
G03X1479920Y1564515I150J-132D01*
G01Y1562573D01*
G03X1479970Y1562441I200J0D01*
G02Y1559529I-1664J-1456D01*
G03X1479920Y1559397I150J-132D01*
G01Y1558775D01*
G02X1479717Y1558572I-203J0D01*
G01X1476897D01*
G02X1476694Y1558775I0J203D01*
G01Y1559397D01*
G03X1476644Y1559529I-200J0D01*
G02Y1562441I1664J1456D01*
G03X1476694Y1562573I-150J132D01*
G01Y1564515D01*
G03X1476644Y1564647I-200J0D01*
G02Y1567559I1664J1456D01*
G03X1476694Y1567691I-150J132D01*
G01Y1568313D01*
G02X1476897Y1568516I203J0D01*
G37*
G36*
G01X1650125D02*
X1652945D01*
G02X1653148Y1568313I0J-203D01*
G01Y1567691D01*
G03X1653198Y1567559I200J0D01*
G02Y1564647I-1664J-1456D01*
G03X1653148Y1564515I150J-132D01*
G01Y1562573D01*
G03X1653198Y1562441I200J0D01*
G02Y1559529I-1664J-1456D01*
G03X1653148Y1559397I150J-132D01*
G01Y1558775D01*
G02X1652945Y1558572I-203J0D01*
G01X1650125D01*
G02X1649922Y1558775I0J203D01*
G01Y1559397D01*
G03X1649872Y1559529I-200J0D01*
G02Y1562441I1664J1456D01*
G03X1649922Y1562573I-150J132D01*
G01Y1564515D01*
G03X1649872Y1564647I-200J0D01*
G02Y1567559I1664J1456D01*
G03X1649922Y1567691I-150J132D01*
G01Y1568313D01*
G02X1650125Y1568516I203J0D01*
G37*
G36*
G01X1667448D02*
X1670268D01*
G02X1670470Y1568313I-1J-203D01*
G01Y1567693D01*
G03X1670520Y1567561I200J0D01*
G02Y1564645I-1661J-1458D01*
G03X1670470Y1564513I150J-132D01*
G01Y1562575D01*
G03X1670520Y1562443I200J0D01*
G02Y1559527I-1661J-1458D01*
G03X1670470Y1559395I150J-132D01*
G01Y1558775D01*
G02X1670268Y1558572I-202J-1D01*
G01X1667448D01*
G02X1667246Y1558775I1J203D01*
G01Y1559395D01*
G03X1667196Y1559527I-200J0D01*
G02Y1562443I1661J1458D01*
G03X1667246Y1562575I-150J132D01*
G01Y1564513D01*
G03X1667196Y1564645I-200J0D01*
G02Y1567561I1661J1458D01*
G03X1667246Y1567693I-150J132D01*
G01Y1568313D01*
G02X1667448Y1568516I202J1D01*
G37*
G36*
G01X1684771D02*
X1687591D01*
G02X1687794Y1568313I0J-203D01*
G01Y1567691D01*
G03X1687844Y1567559I200J0D01*
G02Y1564647I-1664J-1456D01*
G03X1687794Y1564515I150J-132D01*
G01Y1562573D01*
G03X1687844Y1562441I200J0D01*
G02Y1559529I-1664J-1456D01*
G03X1687794Y1559397I150J-132D01*
G01Y1558775D01*
G02X1687591Y1558572I-203J0D01*
G01X1684771D01*
G02X1684568Y1558775I0J203D01*
G01Y1559397D01*
G03X1684518Y1559529I-200J0D01*
G02Y1562441I1664J1456D01*
G03X1684568Y1562573I-150J132D01*
G01Y1564515D01*
G03X1684518Y1564647I-200J0D01*
G02Y1567559I1664J1456D01*
G03X1684568Y1567691I-150J132D01*
G01Y1568313D01*
G02X1684771Y1568516I203J0D01*
G37*
G36*
G01X1702093D02*
X1704913D01*
G02X1705116Y1568313I0J-203D01*
G01Y1567691D01*
G03X1705166Y1567559I200J0D01*
G02Y1564647I-1664J-1456D01*
G03X1705116Y1564515I150J-132D01*
G01Y1562573D01*
G03X1705166Y1562441I200J0D01*
G02Y1559529I-1664J-1456D01*
G03X1705116Y1559397I150J-132D01*
G01Y1558775D01*
G02X1704913Y1558572I-203J0D01*
G01X1702093D01*
G02X1701890Y1558775I0J203D01*
G01Y1559397D01*
G03X1701840Y1559529I-200J0D01*
G02Y1562441I1664J1456D01*
G03X1701890Y1562573I-150J132D01*
G01Y1564515D01*
G03X1701840Y1564647I-200J0D01*
G02Y1567559I1664J1456D01*
G03X1701890Y1567691I-150J132D01*
G01Y1568313D01*
G02X1702093Y1568516I203J0D01*
G37*
G36*
G01X134456Y1572846D02*
X137276D01*
G02X137478Y1572644I0J-202D01*
G01Y1572024D01*
G03X137528Y1571892I200J0D01*
G02Y1568976I-1661J-1458D01*
G03X137478Y1568844I150J-132D01*
G01Y1566905D01*
G03X137528Y1566773I200J0D01*
G02Y1563857I-1661J-1458D01*
G03X137478Y1563725I150J-132D01*
G01Y1563106D01*
G02X137276Y1562904I-202J0D01*
G01X134456D01*
G02X134254Y1563106I0J202D01*
G01Y1563725D01*
G03X134204Y1563857I-200J0D01*
G02Y1566773I1661J1458D01*
G03X134254Y1566905I-150J132D01*
G01Y1568844D01*
G03X134204Y1568976I-200J0D01*
G02Y1571892I1661J1458D01*
G03X134254Y1572024I-150J132D01*
G01Y1572644D01*
G02X134456Y1572846I202J0D01*
G37*
G36*
G01X169102D02*
X171922D01*
G02X172124Y1572644I0J-202D01*
G01Y1572024D01*
G03X172174Y1571892I200J0D01*
G02Y1568976I-1661J-1458D01*
G03X172124Y1568844I150J-132D01*
G01Y1566905D01*
G03X172174Y1566773I200J0D01*
G02Y1563857I-1661J-1458D01*
G03X172124Y1563725I150J-132D01*
G01Y1563106D01*
G02X171922Y1562904I-202J0D01*
G01X169102D01*
G02X168900Y1563106I0J202D01*
G01Y1563725D01*
G03X168850Y1563857I-200J0D01*
G02Y1566773I1661J1458D01*
G03X168900Y1566905I-150J132D01*
G01Y1568844D01*
G03X168850Y1568976I-200J0D01*
G02Y1571892I1661J1458D01*
G03X168900Y1572024I-150J132D01*
G01Y1572644D01*
G02X169102Y1572846I202J0D01*
G37*
G36*
G01X307684D02*
X310504D01*
G02X310706Y1572644I0J-202D01*
G01Y1572024D01*
G03X310756Y1571892I200J0D01*
G02Y1568976I-1661J-1458D01*
G03X310706Y1568844I150J-132D01*
G01Y1566905D01*
G03X310756Y1566773I200J0D01*
G02Y1563857I-1661J-1458D01*
G03X310706Y1563725I150J-132D01*
G01Y1563106D01*
G02X310504Y1562904I-202J0D01*
G01X307684D01*
G02X307482Y1563106I0J202D01*
G01Y1563725D01*
G03X307432Y1563857I-200J0D01*
G02Y1566773I1661J1458D01*
G03X307482Y1566905I-150J132D01*
G01Y1568844D01*
G03X307432Y1568976I-200J0D01*
G02Y1571892I1661J1458D01*
G03X307482Y1572024I-150J132D01*
G01Y1572644D01*
G02X307684Y1572846I202J0D01*
G37*
G36*
G01X342330D02*
X345150D01*
G02X345352Y1572644I0J-202D01*
G01Y1572024D01*
G03X345402Y1571892I200J0D01*
G02Y1568976I-1661J-1458D01*
G03X345352Y1568844I150J-132D01*
G01Y1566905D01*
G03X345402Y1566773I200J0D01*
G02Y1563857I-1661J-1458D01*
G03X345352Y1563725I150J-132D01*
G01Y1563106D01*
G02X345150Y1562904I-202J0D01*
G01X342330D01*
G02X342128Y1563106I0J202D01*
G01Y1563725D01*
G03X342078Y1563857I-200J0D01*
G02Y1566773I1661J1458D01*
G03X342128Y1566905I-150J132D01*
G01Y1568844D01*
G03X342078Y1568976I-200J0D01*
G02Y1571892I1661J1458D01*
G03X342128Y1572024I-150J132D01*
G01Y1572644D01*
G02X342330Y1572846I202J0D01*
G37*
G36*
G01X636818D02*
X639638D01*
G02X639840Y1572644I0J-202D01*
G01Y1572024D01*
G03X639890Y1571892I200J0D01*
G02Y1568976I-1661J-1458D01*
G03X639840Y1568844I150J-132D01*
G01Y1566905D01*
G03X639890Y1566773I200J0D01*
G02Y1563857I-1661J-1458D01*
G03X639840Y1563725I150J-132D01*
G01Y1563106D01*
G02X639638Y1562904I-202J0D01*
G01X636818D01*
G02X636616Y1563106I0J202D01*
G01Y1563725D01*
G03X636566Y1563857I-200J0D01*
G02Y1566773I1661J1458D01*
G03X636616Y1566905I-150J132D01*
G01Y1568844D01*
G03X636566Y1568976I-200J0D01*
G02Y1571892I1661J1458D01*
G03X636616Y1572024I-150J132D01*
G01Y1572644D01*
G02X636818Y1572846I202J0D01*
G37*
G36*
G01X671464D02*
X674284D01*
G02X674486Y1572644I0J-202D01*
G01Y1572024D01*
G03X674536Y1571892I200J0D01*
G02Y1568976I-1661J-1458D01*
G03X674486Y1568844I150J-132D01*
G01Y1566905D01*
G03X674536Y1566773I200J0D01*
G02Y1563857I-1661J-1458D01*
G03X674486Y1563725I150J-132D01*
G01Y1563106D01*
G02X674284Y1562904I-202J0D01*
G01X671464D01*
G02X671262Y1563106I0J202D01*
G01Y1563725D01*
G03X671212Y1563857I-200J0D01*
G02Y1566773I1661J1458D01*
G03X671262Y1566905I-150J132D01*
G01Y1568844D01*
G03X671212Y1568976I-200J0D01*
G02Y1571892I1661J1458D01*
G03X671262Y1572024I-150J132D01*
G01Y1572644D01*
G02X671464Y1572846I202J0D01*
G37*
G36*
G01X1156424D02*
X1159244D01*
G02X1159446Y1572644I0J-202D01*
G01Y1572024D01*
G03X1159496Y1571892I200J0D01*
G02Y1568976I-1661J-1458D01*
G03X1159446Y1568844I150J-132D01*
G01Y1566905D01*
G03X1159496Y1566773I200J0D01*
G02Y1563857I-1661J-1458D01*
G03X1159446Y1563725I150J-132D01*
G01Y1563106D01*
G02X1159244Y1562904I-202J0D01*
G01X1156424D01*
G02X1156222Y1563106I0J202D01*
G01Y1563725D01*
G03X1156172Y1563857I-200J0D01*
G02Y1566773I1661J1458D01*
G03X1156222Y1566905I-150J132D01*
G01Y1568844D01*
G03X1156172Y1568976I-200J0D01*
G02Y1571892I1661J1458D01*
G03X1156222Y1572024I-150J132D01*
G01Y1572644D01*
G02X1156424Y1572846I202J0D01*
G37*
G36*
G01X1191070D02*
X1193890D01*
G02X1194092Y1572644I0J-202D01*
G01Y1572024D01*
G03X1194142Y1571892I200J0D01*
G02Y1568976I-1661J-1458D01*
G03X1194092Y1568844I150J-132D01*
G01Y1566905D01*
G03X1194142Y1566773I200J0D01*
G02Y1563857I-1661J-1458D01*
G03X1194092Y1563725I150J-132D01*
G01Y1563106D01*
G02X1193890Y1562904I-202J0D01*
G01X1191070D01*
G02X1190868Y1563106I0J202D01*
G01Y1563725D01*
G03X1190818Y1563857I-200J0D01*
G02Y1566773I1661J1458D01*
G03X1190868Y1566905I-150J132D01*
G01Y1568844D01*
G03X1190818Y1568976I-200J0D01*
G02Y1571892I1661J1458D01*
G03X1190868Y1572024I-150J132D01*
G01Y1572644D01*
G02X1191070Y1572846I202J0D01*
G37*
G36*
G01X1312330D02*
X1315150D01*
G02X1315352Y1572644I0J-202D01*
G01Y1572024D01*
G03X1315402Y1571892I200J0D01*
G02Y1568976I-1661J-1458D01*
G03X1315352Y1568844I150J-132D01*
G01Y1566905D01*
G03X1315402Y1566773I200J0D01*
G02Y1563857I-1661J-1458D01*
G03X1315352Y1563725I150J-132D01*
G01Y1563106D01*
G02X1315150Y1562904I-202J0D01*
G01X1312330D01*
G02X1312128Y1563106I0J202D01*
G01Y1563725D01*
G03X1312078Y1563857I-200J0D01*
G02Y1566773I1661J1458D01*
G03X1312128Y1566905I-150J132D01*
G01Y1568844D01*
G03X1312078Y1568976I-200J0D01*
G02Y1571892I1661J1458D01*
G03X1312128Y1572024I-150J132D01*
G01Y1572644D01*
G02X1312330Y1572846I202J0D01*
G37*
G36*
G01X1346976D02*
X1349796D01*
G02X1349998Y1572644I0J-202D01*
G01Y1572024D01*
G03X1350048Y1571892I200J0D01*
G02Y1568976I-1661J-1458D01*
G03X1349998Y1568844I150J-132D01*
G01Y1566905D01*
G03X1350048Y1566773I200J0D01*
G02Y1563857I-1661J-1458D01*
G03X1349998Y1563725I150J-132D01*
G01Y1563106D01*
G02X1349796Y1562904I-202J0D01*
G01X1346976D01*
G02X1346774Y1563106I0J202D01*
G01Y1563725D01*
G03X1346724Y1563857I-200J0D01*
G02Y1566773I1661J1458D01*
G03X1346774Y1566905I-150J132D01*
G01Y1568844D01*
G03X1346724Y1568976I-200J0D01*
G02Y1571892I1661J1458D01*
G03X1346774Y1572024I-150J132D01*
G01Y1572644D01*
G02X1346976Y1572846I202J0D01*
G37*
G36*
G01X1658786D02*
X1661606D01*
G02X1661808Y1572644I0J-202D01*
G01Y1572024D01*
G03X1661858Y1571892I200J0D01*
G02Y1568976I-1661J-1458D01*
G03X1661808Y1568844I150J-132D01*
G01Y1566905D01*
G03X1661858Y1566773I200J0D01*
G02Y1563857I-1661J-1458D01*
G03X1661808Y1563725I150J-132D01*
G01Y1563106D01*
G02X1661606Y1562904I-202J0D01*
G01X1658786D01*
G02X1658584Y1563106I0J202D01*
G01Y1563725D01*
G03X1658534Y1563857I-200J0D01*
G02Y1566773I1661J1458D01*
G03X1658584Y1566905I-150J132D01*
G01Y1568844D01*
G03X1658534Y1568976I-200J0D01*
G02Y1571892I1661J1458D01*
G03X1658584Y1572024I-150J132D01*
G01Y1572644D01*
G02X1658786Y1572846I202J0D01*
G37*
G36*
G01X1693432D02*
X1696252D01*
G02X1696454Y1572644I0J-202D01*
G01Y1572024D01*
G03X1696504Y1571892I200J0D01*
G02Y1568976I-1661J-1458D01*
G03X1696454Y1568844I150J-132D01*
G01Y1566905D01*
G03X1696504Y1566773I200J0D01*
G02Y1563857I-1661J-1458D01*
G03X1696454Y1563725I150J-132D01*
G01Y1563106D01*
G02X1696252Y1562904I-202J0D01*
G01X1693432D01*
G02X1693230Y1563106I0J202D01*
G01Y1563725D01*
G03X1693180Y1563857I-200J0D01*
G02Y1566773I1661J1458D01*
G03X1693230Y1566905I-150J132D01*
G01Y1568844D01*
G03X1693180Y1568976I-200J0D01*
G02Y1571892I1661J1458D01*
G03X1693230Y1572024I-150J132D01*
G01Y1572644D01*
G02X1693432Y1572846I202J0D01*
G37*
G36*
G01X117133D02*
X119953D01*
G02X120156Y1572644I1J-202D01*
G01Y1572022D01*
G03X120206Y1571890I200J0D01*
G02Y1568978I-1664J-1456D01*
G03X120156Y1568846I150J-132D01*
G01Y1566903D01*
G03X120206Y1566771I200J0D01*
G02Y1563859I-1664J-1456D01*
G03X120156Y1563727I150J-132D01*
G01Y1563106D01*
G02X119953Y1562904I-203J1D01*
G01X117133D01*
G02X116930Y1563106I-1J202D01*
G01Y1563727D01*
G03X116880Y1563859I-200J0D01*
G02Y1566771I1664J1456D01*
G03X116930Y1566903I-150J132D01*
G01Y1568846D01*
G03X116880Y1568978I-200J0D01*
G02Y1571890I1664J1456D01*
G03X116930Y1572022I-150J132D01*
G01Y1572644D01*
G02X117133Y1572846I203J-1D01*
G37*
G36*
G01X151779D02*
X154599D01*
G02X154802Y1572644I1J-202D01*
G01Y1572022D01*
G03X154852Y1571890I200J0D01*
G02Y1568978I-1664J-1456D01*
G03X154802Y1568846I150J-132D01*
G01Y1566903D01*
G03X154852Y1566771I200J0D01*
G02Y1563859I-1664J-1456D01*
G03X154802Y1563727I150J-132D01*
G01Y1563106D01*
G02X154599Y1562904I-203J1D01*
G01X151779D01*
G02X151576Y1563106I-1J202D01*
G01Y1563727D01*
G03X151526Y1563859I-200J0D01*
G02Y1566771I1664J1456D01*
G03X151576Y1566903I-150J132D01*
G01Y1568846D01*
G03X151526Y1568978I-200J0D01*
G02Y1571890I1664J1456D01*
G03X151576Y1572022I-150J132D01*
G01Y1572644D01*
G02X151779Y1572846I203J-1D01*
G37*
G36*
G01X290361D02*
X293181D01*
G02X293384Y1572644I1J-202D01*
G01Y1572022D01*
G03X293434Y1571890I200J0D01*
G02Y1568978I-1664J-1456D01*
G03X293384Y1568846I150J-132D01*
G01Y1566903D01*
G03X293434Y1566771I200J0D01*
G02Y1563859I-1664J-1456D01*
G03X293384Y1563727I150J-132D01*
G01Y1563106D01*
G02X293181Y1562904I-203J1D01*
G01X290361D01*
G02X290158Y1563106I-1J202D01*
G01Y1563727D01*
G03X290108Y1563859I-200J0D01*
G02Y1566771I1664J1456D01*
G03X290158Y1566903I-150J132D01*
G01Y1568846D01*
G03X290108Y1568978I-200J0D01*
G02Y1571890I1664J1456D01*
G03X290158Y1572022I-150J132D01*
G01Y1572644D01*
G02X290361Y1572846I203J-1D01*
G37*
G36*
G01X325007D02*
X327827D01*
G02X328030Y1572644I1J-202D01*
G01Y1572022D01*
G03X328080Y1571890I200J0D01*
G02Y1568978I-1664J-1456D01*
G03X328030Y1568846I150J-132D01*
G01Y1566903D01*
G03X328080Y1566771I200J0D01*
G02Y1563859I-1664J-1456D01*
G03X328030Y1563727I150J-132D01*
G01Y1563106D01*
G02X327827Y1562904I-203J1D01*
G01X325007D01*
G02X324804Y1563106I-1J202D01*
G01Y1563727D01*
G03X324754Y1563859I-200J0D01*
G02Y1566771I1664J1456D01*
G03X324804Y1566903I-150J132D01*
G01Y1568846D01*
G03X324754Y1568978I-200J0D01*
G02Y1571890I1664J1456D01*
G03X324804Y1572022I-150J132D01*
G01Y1572644D01*
G02X325007Y1572846I203J-1D01*
G37*
G36*
G01X515559D02*
X518379D01*
G02X518582Y1572644I1J-202D01*
G01Y1572022D01*
G03X518632Y1571890I200J0D01*
G02Y1568978I-1664J-1456D01*
G03X518582Y1568846I150J-132D01*
G01Y1566903D01*
G03X518632Y1566771I200J0D01*
G02Y1563859I-1664J-1456D01*
G03X518582Y1563727I150J-132D01*
G01Y1563106D01*
G02X518379Y1562904I-203J1D01*
G01X515559D01*
G02X515356Y1563106I-1J202D01*
G01Y1563727D01*
G03X515306Y1563859I-200J0D01*
G02Y1566771I1664J1456D01*
G03X515356Y1566903I-150J132D01*
G01Y1568846D01*
G03X515306Y1568978I-200J0D01*
G02Y1571890I1664J1456D01*
G03X515356Y1572022I-150J132D01*
G01Y1572644D01*
G02X515559Y1572846I203J-1D01*
G37*
G36*
G01X654141D02*
X656961D01*
G02X657164Y1572644I1J-202D01*
G01Y1572022D01*
G03X657214Y1571890I200J0D01*
G02Y1568978I-1664J-1456D01*
G03X657164Y1568846I150J-132D01*
G01Y1566903D01*
G03X657214Y1566771I200J0D01*
G02Y1563859I-1664J-1456D01*
G03X657164Y1563727I150J-132D01*
G01Y1563106D01*
G02X656961Y1562904I-203J1D01*
G01X654141D01*
G02X653938Y1563106I-1J202D01*
G01Y1563727D01*
G03X653888Y1563859I-200J0D01*
G02Y1566771I1664J1456D01*
G03X653938Y1566903I-150J132D01*
G01Y1568846D01*
G03X653888Y1568978I-200J0D01*
G02Y1571890I1664J1456D01*
G03X653938Y1572022I-150J132D01*
G01Y1572644D01*
G02X654141Y1572846I203J-1D01*
G37*
G36*
G01X688787D02*
X691607D01*
G02X691810Y1572644I1J-202D01*
G01Y1572022D01*
G03X691860Y1571890I200J0D01*
G02Y1568978I-1664J-1456D01*
G03X691810Y1568846I150J-132D01*
G01Y1566903D01*
G03X691860Y1566771I200J0D01*
G02Y1563859I-1664J-1456D01*
G03X691810Y1563727I150J-132D01*
G01Y1563106D01*
G02X691607Y1562904I-203J1D01*
G01X688787D01*
G02X688584Y1563106I-1J202D01*
G01Y1563727D01*
G03X688534Y1563859I-200J0D01*
G02Y1566771I1664J1456D01*
G03X688584Y1566903I-150J132D01*
G01Y1568846D01*
G03X688534Y1568978I-200J0D01*
G02Y1571890I1664J1456D01*
G03X688584Y1572022I-150J132D01*
G01Y1572644D01*
G02X688787Y1572846I203J-1D01*
G37*
G36*
G01X1139101D02*
X1141921D01*
G02X1142124Y1572644I1J-202D01*
G01Y1572022D01*
G03X1142174Y1571890I200J0D01*
G02Y1568978I-1664J-1456D01*
G03X1142124Y1568846I150J-132D01*
G01Y1566903D01*
G03X1142174Y1566771I200J0D01*
G02Y1563859I-1664J-1456D01*
G03X1142124Y1563727I150J-132D01*
G01Y1563106D01*
G02X1141921Y1562904I-203J1D01*
G01X1139101D01*
G02X1138898Y1563106I-1J202D01*
G01Y1563727D01*
G03X1138848Y1563859I-200J0D01*
G02Y1566771I1664J1456D01*
G03X1138898Y1566903I-150J132D01*
G01Y1568846D01*
G03X1138848Y1568978I-200J0D01*
G02Y1571890I1664J1456D01*
G03X1138898Y1572022I-150J132D01*
G01Y1572644D01*
G02X1139101Y1572846I203J-1D01*
G37*
G36*
G01X1173747D02*
X1176567D01*
G02X1176770Y1572644I1J-202D01*
G01Y1572022D01*
G03X1176820Y1571890I200J0D01*
G02Y1568978I-1664J-1456D01*
G03X1176770Y1568846I150J-132D01*
G01Y1566903D01*
G03X1176820Y1566771I200J0D01*
G02Y1563859I-1664J-1456D01*
G03X1176770Y1563727I150J-132D01*
G01Y1563106D01*
G02X1176567Y1562904I-203J1D01*
G01X1173747D01*
G02X1173544Y1563106I-1J202D01*
G01Y1563727D01*
G03X1173494Y1563859I-200J0D01*
G02Y1566771I1664J1456D01*
G03X1173544Y1566903I-150J132D01*
G01Y1568846D01*
G03X1173494Y1568978I-200J0D01*
G02Y1571890I1664J1456D01*
G03X1173544Y1572022I-150J132D01*
G01Y1572644D01*
G02X1173747Y1572846I203J-1D01*
G37*
G36*
G01X1329653D02*
X1332473D01*
G02X1332676Y1572644I1J-202D01*
G01Y1572022D01*
G03X1332726Y1571890I200J0D01*
G02Y1568978I-1664J-1456D01*
G03X1332676Y1568846I150J-132D01*
G01Y1566903D01*
G03X1332726Y1566771I200J0D01*
G02Y1563859I-1664J-1456D01*
G03X1332676Y1563727I150J-132D01*
G01Y1563106D01*
G02X1332473Y1562904I-203J1D01*
G01X1329653D01*
G02X1329450Y1563106I-1J202D01*
G01Y1563727D01*
G03X1329400Y1563859I-200J0D01*
G02Y1566771I1664J1456D01*
G03X1329450Y1566903I-150J132D01*
G01Y1568846D01*
G03X1329400Y1568978I-200J0D01*
G02Y1571890I1664J1456D01*
G03X1329450Y1572022I-150J132D01*
G01Y1572644D01*
G02X1329653Y1572846I203J-1D01*
G37*
G36*
G01X1364299D02*
X1367119D01*
G02X1367322Y1572644I1J-202D01*
G01Y1572022D01*
G03X1367372Y1571890I200J0D01*
G02Y1568978I-1664J-1456D01*
G03X1367322Y1568846I150J-132D01*
G01Y1566903D01*
G03X1367372Y1566771I200J0D01*
G02Y1563859I-1664J-1456D01*
G03X1367322Y1563727I150J-132D01*
G01Y1563106D01*
G02X1367119Y1562904I-203J1D01*
G01X1364299D01*
G02X1364096Y1563106I-1J202D01*
G01Y1563727D01*
G03X1364046Y1563859I-200J0D01*
G02Y1566771I1664J1456D01*
G03X1364096Y1566903I-150J132D01*
G01Y1568846D01*
G03X1364046Y1568978I-200J0D01*
G02Y1571890I1664J1456D01*
G03X1364096Y1572022I-150J132D01*
G01Y1572644D01*
G02X1364299Y1572846I203J-1D01*
G37*
G36*
G01X1676109D02*
X1678929D01*
G02X1679132Y1572644I1J-202D01*
G01Y1572022D01*
G03X1679182Y1571890I200J0D01*
G02Y1568978I-1664J-1456D01*
G03X1679132Y1568846I150J-132D01*
G01Y1566903D01*
G03X1679182Y1566771I200J0D01*
G02Y1563859I-1664J-1456D01*
G03X1679132Y1563727I150J-132D01*
G01Y1563106D01*
G02X1678929Y1562904I-203J1D01*
G01X1676109D01*
G02X1675906Y1563106I-1J202D01*
G01Y1563727D01*
G03X1675856Y1563859I-200J0D01*
G02Y1566771I1664J1456D01*
G03X1675906Y1566903I-150J132D01*
G01Y1568846D01*
G03X1675856Y1568978I-200J0D01*
G02Y1571890I1664J1456D01*
G03X1675906Y1572022I-150J132D01*
G01Y1572644D01*
G02X1676109Y1572846I203J-1D01*
G37*
G36*
G01X1710755D02*
X1713575D01*
G02X1713778Y1572644I1J-202D01*
G01Y1572022D01*
G03X1713828Y1571890I200J0D01*
G02Y1568978I-1664J-1456D01*
G03X1713778Y1568846I150J-132D01*
G01Y1566903D01*
G03X1713828Y1566771I200J0D01*
G02Y1563859I-1664J-1456D01*
G03X1713778Y1563727I150J-132D01*
G01Y1563106D01*
G02X1713575Y1562904I-203J1D01*
G01X1710755D01*
G02X1710552Y1563106I-1J202D01*
G01Y1563727D01*
G03X1710502Y1563859I-200J0D01*
G02Y1566771I1664J1456D01*
G03X1710552Y1566903I-150J132D01*
G01Y1568846D01*
G03X1710502Y1568978I-200J0D01*
G02Y1571890I1664J1456D01*
G03X1710552Y1572022I-150J132D01*
G01Y1572644D01*
G02X1710755Y1572846I203J-1D01*
G37*
G36*
G01X108472Y1583870D02*
X111292D01*
G02X111494Y1583667I-1J-203D01*
G01Y1583047D01*
G03X111544Y1582915I200J0D01*
G02Y1579999I-1661J-1458D01*
G03X111494Y1579867I150J-132D01*
G01Y1577929D01*
G03X111544Y1577797I200J0D01*
G02Y1574881I-1661J-1458D01*
G03X111494Y1574749I150J-132D01*
G01Y1574129D01*
G02X111292Y1573926I-202J-1D01*
G01X108472D01*
G02X108270Y1574129I1J203D01*
G01Y1574749D01*
G03X108220Y1574881I-200J0D01*
G02Y1577797I1661J1458D01*
G03X108270Y1577929I-150J132D01*
G01Y1579867D01*
G03X108220Y1579999I-200J0D01*
G02Y1582915I1661J1458D01*
G03X108270Y1583047I-150J132D01*
G01Y1583667D01*
G02X108472Y1583870I202J1D01*
G37*
G36*
G01X125795D02*
X128615D01*
G02X128818Y1583667I0J-203D01*
G01Y1583045D01*
G03X128868Y1582913I200J0D01*
G02Y1580001I-1664J-1456D01*
G03X128818Y1579869I150J-132D01*
G01Y1577927D01*
G03X128868Y1577795I200J0D01*
G02Y1574883I-1664J-1456D01*
G03X128818Y1574751I150J-132D01*
G01Y1574129D01*
G02X128615Y1573926I-203J0D01*
G01X125795D01*
G02X125592Y1574129I0J203D01*
G01Y1574751D01*
G03X125542Y1574883I-200J0D01*
G02Y1577795I1664J1456D01*
G03X125592Y1577927I-150J132D01*
G01Y1579869D01*
G03X125542Y1580001I-200J0D01*
G02Y1582913I1664J1456D01*
G03X125592Y1583045I-150J132D01*
G01Y1583667D01*
G02X125795Y1583870I203J0D01*
G37*
G36*
G01X143118D02*
X145938D01*
G02X146140Y1583667I-1J-203D01*
G01Y1583047D01*
G03X146190Y1582915I200J0D01*
G02Y1579999I-1661J-1458D01*
G03X146140Y1579867I150J-132D01*
G01Y1577929D01*
G03X146190Y1577797I200J0D01*
G02Y1574881I-1661J-1458D01*
G03X146140Y1574749I150J-132D01*
G01Y1574129D01*
G02X145938Y1573926I-202J-1D01*
G01X143118D01*
G02X142916Y1574129I1J203D01*
G01Y1574749D01*
G03X142866Y1574881I-200J0D01*
G02Y1577797I1661J1458D01*
G03X142916Y1577929I-150J132D01*
G01Y1579867D01*
G03X142866Y1579999I-200J0D01*
G02Y1582915I1661J1458D01*
G03X142916Y1583047I-150J132D01*
G01Y1583667D01*
G02X143118Y1583870I202J1D01*
G37*
G36*
G01X160440D02*
X163260D01*
G02X163462Y1583667I-1J-203D01*
G01Y1583047D01*
G03X163512Y1582915I200J0D01*
G02Y1579999I-1661J-1458D01*
G03X163462Y1579867I150J-132D01*
G01Y1577929D01*
G03X163512Y1577797I200J0D01*
G02Y1574881I-1661J-1458D01*
G03X163462Y1574749I150J-132D01*
G01Y1574129D01*
G02X163260Y1573926I-202J-1D01*
G01X160440D01*
G02X160238Y1574129I1J203D01*
G01Y1574749D01*
G03X160188Y1574881I-200J0D01*
G02Y1577797I1661J1458D01*
G03X160238Y1577929I-150J132D01*
G01Y1579867D01*
G03X160188Y1579999I-200J0D01*
G02Y1582915I1661J1458D01*
G03X160238Y1583047I-150J132D01*
G01Y1583667D01*
G02X160440Y1583870I202J1D01*
G37*
G36*
G01X281700D02*
X284520D01*
G02X284722Y1583667I-1J-203D01*
G01Y1583047D01*
G03X284772Y1582915I200J0D01*
G02Y1579999I-1661J-1458D01*
G03X284722Y1579867I150J-132D01*
G01Y1577929D01*
G03X284772Y1577797I200J0D01*
G02Y1574881I-1661J-1458D01*
G03X284722Y1574749I150J-132D01*
G01Y1574129D01*
G02X284520Y1573926I-202J-1D01*
G01X281700D01*
G02X281498Y1574129I1J203D01*
G01Y1574749D01*
G03X281448Y1574881I-200J0D01*
G02Y1577797I1661J1458D01*
G03X281498Y1577929I-150J132D01*
G01Y1579867D01*
G03X281448Y1579999I-200J0D01*
G02Y1582915I1661J1458D01*
G03X281498Y1583047I-150J132D01*
G01Y1583667D01*
G02X281700Y1583870I202J1D01*
G37*
G36*
G01X299023D02*
X301843D01*
G02X302046Y1583667I0J-203D01*
G01Y1583045D01*
G03X302096Y1582913I200J0D01*
G02Y1580001I-1664J-1456D01*
G03X302046Y1579869I150J-132D01*
G01Y1577927D01*
G03X302096Y1577795I200J0D01*
G02Y1574883I-1664J-1456D01*
G03X302046Y1574751I150J-132D01*
G01Y1574129D01*
G02X301843Y1573926I-203J0D01*
G01X299023D01*
G02X298820Y1574129I0J203D01*
G01Y1574751D01*
G03X298770Y1574883I-200J0D01*
G02Y1577795I1664J1456D01*
G03X298820Y1577927I-150J132D01*
G01Y1579869D01*
G03X298770Y1580001I-200J0D01*
G02Y1582913I1664J1456D01*
G03X298820Y1583045I-150J132D01*
G01Y1583667D01*
G02X299023Y1583870I203J0D01*
G37*
G36*
G01X316346D02*
X319166D01*
G02X319368Y1583667I-1J-203D01*
G01Y1583047D01*
G03X319418Y1582915I200J0D01*
G02Y1579999I-1661J-1458D01*
G03X319368Y1579867I150J-132D01*
G01Y1577929D01*
G03X319418Y1577797I200J0D01*
G02Y1574881I-1661J-1458D01*
G03X319368Y1574749I150J-132D01*
G01Y1574129D01*
G02X319166Y1573926I-202J-1D01*
G01X316346D01*
G02X316144Y1574129I1J203D01*
G01Y1574749D01*
G03X316094Y1574881I-200J0D01*
G02Y1577797I1661J1458D01*
G03X316144Y1577929I-150J132D01*
G01Y1579867D01*
G03X316094Y1579999I-200J0D01*
G02Y1582915I1661J1458D01*
G03X316144Y1583047I-150J132D01*
G01Y1583667D01*
G02X316346Y1583870I202J1D01*
G37*
G36*
G01X333668D02*
X336488D01*
G02X336690Y1583667I-1J-203D01*
G01Y1583047D01*
G03X336740Y1582915I200J0D01*
G02Y1579999I-1661J-1458D01*
G03X336690Y1579867I150J-132D01*
G01Y1577929D01*
G03X336740Y1577797I200J0D01*
G02Y1574881I-1661J-1458D01*
G03X336690Y1574749I150J-132D01*
G01Y1574129D01*
G02X336488Y1573926I-202J-1D01*
G01X333668D01*
G02X333466Y1574129I1J203D01*
G01Y1574749D01*
G03X333416Y1574881I-200J0D01*
G02Y1577797I1661J1458D01*
G03X333466Y1577929I-150J132D01*
G01Y1579867D01*
G03X333416Y1579999I-200J0D01*
G02Y1582915I1661J1458D01*
G03X333466Y1583047I-150J132D01*
G01Y1583667D01*
G02X333668Y1583870I202J1D01*
G37*
G36*
G01X628157D02*
X630977D01*
G02X631180Y1583667I0J-203D01*
G01Y1583045D01*
G03X631230Y1582913I200J0D01*
G02Y1580001I-1664J-1456D01*
G03X631180Y1579869I150J-132D01*
G01Y1577927D01*
G03X631230Y1577795I200J0D01*
G02Y1574883I-1664J-1456D01*
G03X631180Y1574751I150J-132D01*
G01Y1574129D01*
G02X630977Y1573926I-203J0D01*
G01X628157D01*
G02X627954Y1574129I0J203D01*
G01Y1574751D01*
G03X627904Y1574883I-200J0D01*
G02Y1577795I1664J1456D01*
G03X627954Y1577927I-150J132D01*
G01Y1579869D01*
G03X627904Y1580001I-200J0D01*
G02Y1582913I1664J1456D01*
G03X627954Y1583045I-150J132D01*
G01Y1583667D01*
G02X628157Y1583870I203J0D01*
G37*
G36*
G01X645480D02*
X648300D01*
G02X648502Y1583667I-1J-203D01*
G01Y1583047D01*
G03X648552Y1582915I200J0D01*
G02Y1579999I-1661J-1458D01*
G03X648502Y1579867I150J-132D01*
G01Y1577929D01*
G03X648552Y1577797I200J0D01*
G02Y1574881I-1661J-1458D01*
G03X648502Y1574749I150J-132D01*
G01Y1574129D01*
G02X648300Y1573926I-202J-1D01*
G01X645480D01*
G02X645278Y1574129I1J203D01*
G01Y1574749D01*
G03X645228Y1574881I-200J0D01*
G02Y1577797I1661J1458D01*
G03X645278Y1577929I-150J132D01*
G01Y1579867D01*
G03X645228Y1579999I-200J0D01*
G02Y1582915I1661J1458D01*
G03X645278Y1583047I-150J132D01*
G01Y1583667D01*
G02X645480Y1583870I202J1D01*
G37*
G36*
G01X662803D02*
X665623D01*
G02X665826Y1583667I0J-203D01*
G01Y1583045D01*
G03X665876Y1582913I200J0D01*
G02Y1580001I-1664J-1456D01*
G03X665826Y1579869I150J-132D01*
G01Y1577927D01*
G03X665876Y1577795I200J0D01*
G02Y1574883I-1664J-1456D01*
G03X665826Y1574751I150J-132D01*
G01Y1574129D01*
G02X665623Y1573926I-203J0D01*
G01X662803D01*
G02X662600Y1574129I0J203D01*
G01Y1574751D01*
G03X662550Y1574883I-200J0D01*
G02Y1577795I1664J1456D01*
G03X662600Y1577927I-150J132D01*
G01Y1579869D01*
G03X662550Y1580001I-200J0D01*
G02Y1582913I1664J1456D01*
G03X662600Y1583045I-150J132D01*
G01Y1583667D01*
G02X662803Y1583870I203J0D01*
G37*
G36*
G01X680125D02*
X682945D01*
G02X683148Y1583667I0J-203D01*
G01Y1583045D01*
G03X683198Y1582913I200J0D01*
G02Y1580001I-1664J-1456D01*
G03X683148Y1579869I150J-132D01*
G01Y1577927D01*
G03X683198Y1577795I200J0D01*
G02Y1574883I-1664J-1456D01*
G03X683148Y1574751I150J-132D01*
G01Y1574129D01*
G02X682945Y1573926I-203J0D01*
G01X680125D01*
G02X679922Y1574129I0J203D01*
G01Y1574751D01*
G03X679872Y1574883I-200J0D01*
G02Y1577795I1664J1456D01*
G03X679922Y1577927I-150J132D01*
G01Y1579869D01*
G03X679872Y1580001I-200J0D01*
G02Y1582913I1664J1456D01*
G03X679922Y1583045I-150J132D01*
G01Y1583667D01*
G02X680125Y1583870I203J0D01*
G37*
G36*
G01X1130440D02*
X1133260D01*
G02X1133462Y1583667I-1J-203D01*
G01Y1583047D01*
G03X1133512Y1582915I200J0D01*
G02Y1579999I-1661J-1458D01*
G03X1133462Y1579867I150J-132D01*
G01Y1577929D01*
G03X1133512Y1577797I200J0D01*
G02Y1574881I-1661J-1458D01*
G03X1133462Y1574749I150J-132D01*
G01Y1574129D01*
G02X1133260Y1573926I-202J-1D01*
G01X1130440D01*
G02X1130238Y1574129I1J203D01*
G01Y1574749D01*
G03X1130188Y1574881I-200J0D01*
G02Y1577797I1661J1458D01*
G03X1130238Y1577929I-150J132D01*
G01Y1579867D01*
G03X1130188Y1579999I-200J0D01*
G02Y1582915I1661J1458D01*
G03X1130238Y1583047I-150J132D01*
G01Y1583667D01*
G02X1130440Y1583870I202J1D01*
G37*
G36*
G01X1147763D02*
X1150583D01*
G02X1150786Y1583667I0J-203D01*
G01Y1583045D01*
G03X1150836Y1582913I200J0D01*
G02Y1580001I-1664J-1456D01*
G03X1150786Y1579869I150J-132D01*
G01Y1577927D01*
G03X1150836Y1577795I200J0D01*
G02Y1574883I-1664J-1456D01*
G03X1150786Y1574751I150J-132D01*
G01Y1574129D01*
G02X1150583Y1573926I-203J0D01*
G01X1147763D01*
G02X1147560Y1574129I0J203D01*
G01Y1574751D01*
G03X1147510Y1574883I-200J0D01*
G02Y1577795I1664J1456D01*
G03X1147560Y1577927I-150J132D01*
G01Y1579869D01*
G03X1147510Y1580001I-200J0D01*
G02Y1582913I1664J1456D01*
G03X1147560Y1583045I-150J132D01*
G01Y1583667D01*
G02X1147763Y1583870I203J0D01*
G37*
G36*
G01X1165086D02*
X1167906D01*
G02X1168108Y1583667I-1J-203D01*
G01Y1583047D01*
G03X1168158Y1582915I200J0D01*
G02Y1579999I-1661J-1458D01*
G03X1168108Y1579867I150J-132D01*
G01Y1577929D01*
G03X1168158Y1577797I200J0D01*
G02Y1574881I-1661J-1458D01*
G03X1168108Y1574749I150J-132D01*
G01Y1574129D01*
G02X1167906Y1573926I-202J-1D01*
G01X1165086D01*
G02X1164884Y1574129I1J203D01*
G01Y1574749D01*
G03X1164834Y1574881I-200J0D01*
G02Y1577797I1661J1458D01*
G03X1164884Y1577929I-150J132D01*
G01Y1579867D01*
G03X1164834Y1579999I-200J0D01*
G02Y1582915I1661J1458D01*
G03X1164884Y1583047I-150J132D01*
G01Y1583667D01*
G02X1165086Y1583870I202J1D01*
G37*
G36*
G01X1182408D02*
X1185228D01*
G02X1185430Y1583667I-1J-203D01*
G01Y1583047D01*
G03X1185480Y1582915I200J0D01*
G02Y1579999I-1661J-1458D01*
G03X1185430Y1579867I150J-132D01*
G01Y1577929D01*
G03X1185480Y1577797I200J0D01*
G02Y1574881I-1661J-1458D01*
G03X1185430Y1574749I150J-132D01*
G01Y1574129D01*
G02X1185228Y1573926I-202J-1D01*
G01X1182408D01*
G02X1182206Y1574129I1J203D01*
G01Y1574749D01*
G03X1182156Y1574881I-200J0D01*
G02Y1577797I1661J1458D01*
G03X1182206Y1577929I-150J132D01*
G01Y1579867D01*
G03X1182156Y1579999I-200J0D01*
G02Y1582915I1661J1458D01*
G03X1182206Y1583047I-150J132D01*
G01Y1583667D01*
G02X1182408Y1583870I202J1D01*
G37*
G36*
G01X1303669D02*
X1306489D01*
G02X1306692Y1583667I0J-203D01*
G01Y1583045D01*
G03X1306742Y1582913I200J0D01*
G02Y1580001I-1664J-1456D01*
G03X1306692Y1579869I150J-132D01*
G01Y1577927D01*
G03X1306742Y1577795I200J0D01*
G02Y1574883I-1664J-1456D01*
G03X1306692Y1574751I150J-132D01*
G01Y1574129D01*
G02X1306489Y1573926I-203J0D01*
G01X1303669D01*
G02X1303466Y1574129I0J203D01*
G01Y1574751D01*
G03X1303416Y1574883I-200J0D01*
G02Y1577795I1664J1456D01*
G03X1303466Y1577927I-150J132D01*
G01Y1579869D01*
G03X1303416Y1580001I-200J0D01*
G02Y1582913I1664J1456D01*
G03X1303466Y1583045I-150J132D01*
G01Y1583667D01*
G02X1303669Y1583870I203J0D01*
G37*
G36*
G01X1320992D02*
X1323812D01*
G02X1324014Y1583667I-1J-203D01*
G01Y1583047D01*
G03X1324064Y1582915I200J0D01*
G02Y1579999I-1661J-1458D01*
G03X1324014Y1579867I150J-132D01*
G01Y1577929D01*
G03X1324064Y1577797I200J0D01*
G02Y1574881I-1661J-1458D01*
G03X1324014Y1574749I150J-132D01*
G01Y1574129D01*
G02X1323812Y1573926I-202J-1D01*
G01X1320992D01*
G02X1320790Y1574129I1J203D01*
G01Y1574749D01*
G03X1320740Y1574881I-200J0D01*
G02Y1577797I1661J1458D01*
G03X1320790Y1577929I-150J132D01*
G01Y1579867D01*
G03X1320740Y1579999I-200J0D01*
G02Y1582915I1661J1458D01*
G03X1320790Y1583047I-150J132D01*
G01Y1583667D01*
G02X1320992Y1583870I202J1D01*
G37*
G36*
G01X1338315D02*
X1341135D01*
G02X1341338Y1583667I0J-203D01*
G01Y1583045D01*
G03X1341388Y1582913I200J0D01*
G02Y1580001I-1664J-1456D01*
G03X1341338Y1579869I150J-132D01*
G01Y1577927D01*
G03X1341388Y1577795I200J0D01*
G02Y1574883I-1664J-1456D01*
G03X1341338Y1574751I150J-132D01*
G01Y1574129D01*
G02X1341135Y1573926I-203J0D01*
G01X1338315D01*
G02X1338112Y1574129I0J203D01*
G01Y1574751D01*
G03X1338062Y1574883I-200J0D01*
G02Y1577795I1664J1456D01*
G03X1338112Y1577927I-150J132D01*
G01Y1579869D01*
G03X1338062Y1580001I-200J0D01*
G02Y1582913I1664J1456D01*
G03X1338112Y1583045I-150J132D01*
G01Y1583667D01*
G02X1338315Y1583870I203J0D01*
G37*
G36*
G01X1355637D02*
X1358457D01*
G02X1358660Y1583667I0J-203D01*
G01Y1583045D01*
G03X1358710Y1582913I200J0D01*
G02Y1580001I-1664J-1456D01*
G03X1358660Y1579869I150J-132D01*
G01Y1577927D01*
G03X1358710Y1577795I200J0D01*
G02Y1574883I-1664J-1456D01*
G03X1358660Y1574751I150J-132D01*
G01Y1574129D01*
G02X1358457Y1573926I-203J0D01*
G01X1355637D01*
G02X1355434Y1574129I0J203D01*
G01Y1574751D01*
G03X1355384Y1574883I-200J0D01*
G02Y1577795I1664J1456D01*
G03X1355434Y1577927I-150J132D01*
G01Y1579869D01*
G03X1355384Y1580001I-200J0D01*
G02Y1582913I1664J1456D01*
G03X1355434Y1583045I-150J132D01*
G01Y1583667D01*
G02X1355637Y1583870I203J0D01*
G37*
G36*
G01X1476897D02*
X1479717D01*
G02X1479920Y1583667I0J-203D01*
G01Y1583045D01*
G03X1479970Y1582913I200J0D01*
G02Y1580001I-1664J-1456D01*
G03X1479920Y1579869I150J-132D01*
G01Y1577927D01*
G03X1479970Y1577795I200J0D01*
G02Y1574883I-1664J-1456D01*
G03X1479920Y1574751I150J-132D01*
G01Y1574129D01*
G02X1479717Y1573926I-203J0D01*
G01X1476897D01*
G02X1476694Y1574129I0J203D01*
G01Y1574751D01*
G03X1476644Y1574883I-200J0D01*
G02Y1577795I1664J1456D01*
G03X1476694Y1577927I-150J132D01*
G01Y1579869D01*
G03X1476644Y1580001I-200J0D01*
G02Y1582913I1664J1456D01*
G03X1476694Y1583045I-150J132D01*
G01Y1583667D01*
G02X1476897Y1583870I203J0D01*
G37*
G36*
G01X1650125D02*
X1652945D01*
G02X1653148Y1583667I0J-203D01*
G01Y1583045D01*
G03X1653198Y1582913I200J0D01*
G02Y1580001I-1664J-1456D01*
G03X1653148Y1579869I150J-132D01*
G01Y1577927D01*
G03X1653198Y1577795I200J0D01*
G02Y1574883I-1664J-1456D01*
G03X1653148Y1574751I150J-132D01*
G01Y1574129D01*
G02X1652945Y1573926I-203J0D01*
G01X1650125D01*
G02X1649922Y1574129I0J203D01*
G01Y1574751D01*
G03X1649872Y1574883I-200J0D01*
G02Y1577795I1664J1456D01*
G03X1649922Y1577927I-150J132D01*
G01Y1579869D01*
G03X1649872Y1580001I-200J0D01*
G02Y1582913I1664J1456D01*
G03X1649922Y1583045I-150J132D01*
G01Y1583667D01*
G02X1650125Y1583870I203J0D01*
G37*
G36*
G01X1667448D02*
X1670268D01*
G02X1670470Y1583667I-1J-203D01*
G01Y1583047D01*
G03X1670520Y1582915I200J0D01*
G02Y1579999I-1661J-1458D01*
G03X1670470Y1579867I150J-132D01*
G01Y1577929D01*
G03X1670520Y1577797I200J0D01*
G02Y1574881I-1661J-1458D01*
G03X1670470Y1574749I150J-132D01*
G01Y1574129D01*
G02X1670268Y1573926I-202J-1D01*
G01X1667448D01*
G02X1667246Y1574129I1J203D01*
G01Y1574749D01*
G03X1667196Y1574881I-200J0D01*
G02Y1577797I1661J1458D01*
G03X1667246Y1577929I-150J132D01*
G01Y1579867D01*
G03X1667196Y1579999I-200J0D01*
G02Y1582915I1661J1458D01*
G03X1667246Y1583047I-150J132D01*
G01Y1583667D01*
G02X1667448Y1583870I202J1D01*
G37*
G36*
G01X1684771D02*
X1687591D01*
G02X1687794Y1583667I0J-203D01*
G01Y1583045D01*
G03X1687844Y1582913I200J0D01*
G02Y1580001I-1664J-1456D01*
G03X1687794Y1579869I150J-132D01*
G01Y1577927D01*
G03X1687844Y1577795I200J0D01*
G02Y1574883I-1664J-1456D01*
G03X1687794Y1574751I150J-132D01*
G01Y1574129D01*
G02X1687591Y1573926I-203J0D01*
G01X1684771D01*
G02X1684568Y1574129I0J203D01*
G01Y1574751D01*
G03X1684518Y1574883I-200J0D01*
G02Y1577795I1664J1456D01*
G03X1684568Y1577927I-150J132D01*
G01Y1579869D01*
G03X1684518Y1580001I-200J0D01*
G02Y1582913I1664J1456D01*
G03X1684568Y1583045I-150J132D01*
G01Y1583667D01*
G02X1684771Y1583870I203J0D01*
G37*
G36*
G01X1702093D02*
X1704913D01*
G02X1705116Y1583667I0J-203D01*
G01Y1583045D01*
G03X1705166Y1582913I200J0D01*
G02Y1580001I-1664J-1456D01*
G03X1705116Y1579869I150J-132D01*
G01Y1577927D01*
G03X1705166Y1577795I200J0D01*
G02Y1574883I-1664J-1456D01*
G03X1705116Y1574751I150J-132D01*
G01Y1574129D01*
G02X1704913Y1573926I-203J0D01*
G01X1702093D01*
G02X1701890Y1574129I0J203D01*
G01Y1574751D01*
G03X1701840Y1574883I-200J0D01*
G02Y1577795I1664J1456D01*
G03X1701890Y1577927I-150J132D01*
G01Y1579869D01*
G03X1701840Y1580001I-200J0D01*
G02Y1582913I1664J1456D01*
G03X1701890Y1583045I-150J132D01*
G01Y1583667D01*
G02X1702093Y1583870I203J0D01*
G37*
G36*
G01X134456Y1588200D02*
X137276D01*
G02X137478Y1587998I0J-202D01*
G01Y1587378D01*
G03X137528Y1587246I200J0D01*
G02Y1584330I-1661J-1458D01*
G03X137478Y1584198I150J-132D01*
G01Y1582260D01*
G03X137528Y1582128I200J0D01*
G02Y1579212I-1661J-1458D01*
G03X137478Y1579080I150J-132D01*
G01Y1578460D01*
G02X137276Y1578258I-202J0D01*
G01X134456D01*
G02X134254Y1578460I0J202D01*
G01Y1579080D01*
G03X134204Y1579212I-200J0D01*
G02Y1582128I1661J1458D01*
G03X134254Y1582260I-150J132D01*
G01Y1584198D01*
G03X134204Y1584330I-200J0D01*
G02Y1587246I1661J1458D01*
G03X134254Y1587378I-150J132D01*
G01Y1587998D01*
G02X134456Y1588200I202J0D01*
G37*
G36*
G01X169102D02*
X171922D01*
G02X172124Y1587998I0J-202D01*
G01Y1587378D01*
G03X172174Y1587246I200J0D01*
G02Y1584330I-1661J-1458D01*
G03X172124Y1584198I150J-132D01*
G01Y1582260D01*
G03X172174Y1582128I200J0D01*
G02Y1579212I-1661J-1458D01*
G03X172124Y1579080I150J-132D01*
G01Y1578460D01*
G02X171922Y1578258I-202J0D01*
G01X169102D01*
G02X168900Y1578460I0J202D01*
G01Y1579080D01*
G03X168850Y1579212I-200J0D01*
G02Y1582128I1661J1458D01*
G03X168900Y1582260I-150J132D01*
G01Y1584198D01*
G03X168850Y1584330I-200J0D01*
G02Y1587246I1661J1458D01*
G03X168900Y1587378I-150J132D01*
G01Y1587998D01*
G02X169102Y1588200I202J0D01*
G37*
G36*
G01X307684D02*
X310504D01*
G02X310706Y1587998I0J-202D01*
G01Y1587378D01*
G03X310756Y1587246I200J0D01*
G02Y1584330I-1661J-1458D01*
G03X310706Y1584198I150J-132D01*
G01Y1582260D01*
G03X310756Y1582128I200J0D01*
G02Y1579212I-1661J-1458D01*
G03X310706Y1579080I150J-132D01*
G01Y1578460D01*
G02X310504Y1578258I-202J0D01*
G01X307684D01*
G02X307482Y1578460I0J202D01*
G01Y1579080D01*
G03X307432Y1579212I-200J0D01*
G02Y1582128I1661J1458D01*
G03X307482Y1582260I-150J132D01*
G01Y1584198D01*
G03X307432Y1584330I-200J0D01*
G02Y1587246I1661J1458D01*
G03X307482Y1587378I-150J132D01*
G01Y1587998D01*
G02X307684Y1588200I202J0D01*
G37*
G36*
G01X342330D02*
X345150D01*
G02X345352Y1587998I0J-202D01*
G01Y1587378D01*
G03X345402Y1587246I200J0D01*
G02Y1584330I-1661J-1458D01*
G03X345352Y1584198I150J-132D01*
G01Y1582260D01*
G03X345402Y1582128I200J0D01*
G02Y1579212I-1661J-1458D01*
G03X345352Y1579080I150J-132D01*
G01Y1578460D01*
G02X345150Y1578258I-202J0D01*
G01X342330D01*
G02X342128Y1578460I0J202D01*
G01Y1579080D01*
G03X342078Y1579212I-200J0D01*
G02Y1582128I1661J1458D01*
G03X342128Y1582260I-150J132D01*
G01Y1584198D01*
G03X342078Y1584330I-200J0D01*
G02Y1587246I1661J1458D01*
G03X342128Y1587378I-150J132D01*
G01Y1587998D01*
G02X342330Y1588200I202J0D01*
G37*
G36*
G01X636818D02*
X639638D01*
G02X639840Y1587998I0J-202D01*
G01Y1587378D01*
G03X639890Y1587246I200J0D01*
G02Y1584330I-1661J-1458D01*
G03X639840Y1584198I150J-132D01*
G01Y1582260D01*
G03X639890Y1582128I200J0D01*
G02Y1579212I-1661J-1458D01*
G03X639840Y1579080I150J-132D01*
G01Y1578460D01*
G02X639638Y1578258I-202J0D01*
G01X636818D01*
G02X636616Y1578460I0J202D01*
G01Y1579080D01*
G03X636566Y1579212I-200J0D01*
G02Y1582128I1661J1458D01*
G03X636616Y1582260I-150J132D01*
G01Y1584198D01*
G03X636566Y1584330I-200J0D01*
G02Y1587246I1661J1458D01*
G03X636616Y1587378I-150J132D01*
G01Y1587998D01*
G02X636818Y1588200I202J0D01*
G37*
G36*
G01X671464D02*
X674284D01*
G02X674486Y1587998I0J-202D01*
G01Y1587378D01*
G03X674536Y1587246I200J0D01*
G02Y1584330I-1661J-1458D01*
G03X674486Y1584198I150J-132D01*
G01Y1582260D01*
G03X674536Y1582128I200J0D01*
G02Y1579212I-1661J-1458D01*
G03X674486Y1579080I150J-132D01*
G01Y1578460D01*
G02X674284Y1578258I-202J0D01*
G01X671464D01*
G02X671262Y1578460I0J202D01*
G01Y1579080D01*
G03X671212Y1579212I-200J0D01*
G02Y1582128I1661J1458D01*
G03X671262Y1582260I-150J132D01*
G01Y1584198D01*
G03X671212Y1584330I-200J0D01*
G02Y1587246I1661J1458D01*
G03X671262Y1587378I-150J132D01*
G01Y1587998D01*
G02X671464Y1588200I202J0D01*
G37*
G36*
G01X1156424D02*
X1159244D01*
G02X1159446Y1587998I0J-202D01*
G01Y1587378D01*
G03X1159496Y1587246I200J0D01*
G02Y1584330I-1661J-1458D01*
G03X1159446Y1584198I150J-132D01*
G01Y1582260D01*
G03X1159496Y1582128I200J0D01*
G02Y1579212I-1661J-1458D01*
G03X1159446Y1579080I150J-132D01*
G01Y1578460D01*
G02X1159244Y1578258I-202J0D01*
G01X1156424D01*
G02X1156222Y1578460I0J202D01*
G01Y1579080D01*
G03X1156172Y1579212I-200J0D01*
G02Y1582128I1661J1458D01*
G03X1156222Y1582260I-150J132D01*
G01Y1584198D01*
G03X1156172Y1584330I-200J0D01*
G02Y1587246I1661J1458D01*
G03X1156222Y1587378I-150J132D01*
G01Y1587998D01*
G02X1156424Y1588200I202J0D01*
G37*
G36*
G01X1191070D02*
X1193890D01*
G02X1194092Y1587998I0J-202D01*
G01Y1587378D01*
G03X1194142Y1587246I200J0D01*
G02Y1584330I-1661J-1458D01*
G03X1194092Y1584198I150J-132D01*
G01Y1582260D01*
G03X1194142Y1582128I200J0D01*
G02Y1579212I-1661J-1458D01*
G03X1194092Y1579080I150J-132D01*
G01Y1578460D01*
G02X1193890Y1578258I-202J0D01*
G01X1191070D01*
G02X1190868Y1578460I0J202D01*
G01Y1579080D01*
G03X1190818Y1579212I-200J0D01*
G02Y1582128I1661J1458D01*
G03X1190868Y1582260I-150J132D01*
G01Y1584198D01*
G03X1190818Y1584330I-200J0D01*
G02Y1587246I1661J1458D01*
G03X1190868Y1587378I-150J132D01*
G01Y1587998D01*
G02X1191070Y1588200I202J0D01*
G37*
G36*
G01X1312330D02*
X1315150D01*
G02X1315352Y1587998I0J-202D01*
G01Y1587378D01*
G03X1315402Y1587246I200J0D01*
G02Y1584330I-1661J-1458D01*
G03X1315352Y1584198I150J-132D01*
G01Y1582260D01*
G03X1315402Y1582128I200J0D01*
G02Y1579212I-1661J-1458D01*
G03X1315352Y1579080I150J-132D01*
G01Y1578460D01*
G02X1315150Y1578258I-202J0D01*
G01X1312330D01*
G02X1312128Y1578460I0J202D01*
G01Y1579080D01*
G03X1312078Y1579212I-200J0D01*
G02Y1582128I1661J1458D01*
G03X1312128Y1582260I-150J132D01*
G01Y1584198D01*
G03X1312078Y1584330I-200J0D01*
G02Y1587246I1661J1458D01*
G03X1312128Y1587378I-150J132D01*
G01Y1587998D01*
G02X1312330Y1588200I202J0D01*
G37*
G36*
G01X1346976D02*
X1349796D01*
G02X1349998Y1587998I0J-202D01*
G01Y1587378D01*
G03X1350048Y1587246I200J0D01*
G02Y1584330I-1661J-1458D01*
G03X1349998Y1584198I150J-132D01*
G01Y1582260D01*
G03X1350048Y1582128I200J0D01*
G02Y1579212I-1661J-1458D01*
G03X1349998Y1579080I150J-132D01*
G01Y1578460D01*
G02X1349796Y1578258I-202J0D01*
G01X1346976D01*
G02X1346774Y1578460I0J202D01*
G01Y1579080D01*
G03X1346724Y1579212I-200J0D01*
G02Y1582128I1661J1458D01*
G03X1346774Y1582260I-150J132D01*
G01Y1584198D01*
G03X1346724Y1584330I-200J0D01*
G02Y1587246I1661J1458D01*
G03X1346774Y1587378I-150J132D01*
G01Y1587998D01*
G02X1346976Y1588200I202J0D01*
G37*
G36*
G01X1658786D02*
X1661606D01*
G02X1661808Y1587998I0J-202D01*
G01Y1587378D01*
G03X1661858Y1587246I200J0D01*
G02Y1584330I-1661J-1458D01*
G03X1661808Y1584198I150J-132D01*
G01Y1582260D01*
G03X1661858Y1582128I200J0D01*
G02Y1579212I-1661J-1458D01*
G03X1661808Y1579080I150J-132D01*
G01Y1578460D01*
G02X1661606Y1578258I-202J0D01*
G01X1658786D01*
G02X1658584Y1578460I0J202D01*
G01Y1579080D01*
G03X1658534Y1579212I-200J0D01*
G02Y1582128I1661J1458D01*
G03X1658584Y1582260I-150J132D01*
G01Y1584198D01*
G03X1658534Y1584330I-200J0D01*
G02Y1587246I1661J1458D01*
G03X1658584Y1587378I-150J132D01*
G01Y1587998D01*
G02X1658786Y1588200I202J0D01*
G37*
G36*
G01X1693432D02*
X1696252D01*
G02X1696454Y1587998I0J-202D01*
G01Y1587378D01*
G03X1696504Y1587246I200J0D01*
G02Y1584330I-1661J-1458D01*
G03X1696454Y1584198I150J-132D01*
G01Y1582260D01*
G03X1696504Y1582128I200J0D01*
G02Y1579212I-1661J-1458D01*
G03X1696454Y1579080I150J-132D01*
G01Y1578460D01*
G02X1696252Y1578258I-202J0D01*
G01X1693432D01*
G02X1693230Y1578460I0J202D01*
G01Y1579080D01*
G03X1693180Y1579212I-200J0D01*
G02Y1582128I1661J1458D01*
G03X1693230Y1582260I-150J132D01*
G01Y1584198D01*
G03X1693180Y1584330I-200J0D01*
G02Y1587246I1661J1458D01*
G03X1693230Y1587378I-150J132D01*
G01Y1587998D01*
G02X1693432Y1588200I202J0D01*
G37*
G36*
G01X117133D02*
X119953D01*
G02X120156Y1587998I1J-202D01*
G01Y1587376D01*
G03X120206Y1587244I200J0D01*
G02Y1584332I-1664J-1456D01*
G03X120156Y1584200I150J-132D01*
G01Y1582258D01*
G03X120206Y1582126I200J0D01*
G02Y1579214I-1664J-1456D01*
G03X120156Y1579082I150J-132D01*
G01Y1578460D01*
G02X119953Y1578258I-203J1D01*
G01X117133D01*
G02X116930Y1578460I-1J202D01*
G01Y1579082D01*
G03X116880Y1579214I-200J0D01*
G02Y1582126I1664J1456D01*
G03X116930Y1582258I-150J132D01*
G01Y1584200D01*
G03X116880Y1584332I-200J0D01*
G02Y1587244I1664J1456D01*
G03X116930Y1587376I-150J132D01*
G01Y1587998D01*
G02X117133Y1588200I203J-1D01*
G37*
G36*
G01X151779D02*
X154599D01*
G02X154802Y1587998I1J-202D01*
G01Y1587376D01*
G03X154852Y1587244I200J0D01*
G02Y1584332I-1664J-1456D01*
G03X154802Y1584200I150J-132D01*
G01Y1582258D01*
G03X154852Y1582126I200J0D01*
G02Y1579214I-1664J-1456D01*
G03X154802Y1579082I150J-132D01*
G01Y1578460D01*
G02X154599Y1578258I-203J1D01*
G01X151779D01*
G02X151576Y1578460I-1J202D01*
G01Y1579082D01*
G03X151526Y1579214I-200J0D01*
G02Y1582126I1664J1456D01*
G03X151576Y1582258I-150J132D01*
G01Y1584200D01*
G03X151526Y1584332I-200J0D01*
G02Y1587244I1664J1456D01*
G03X151576Y1587376I-150J132D01*
G01Y1587998D01*
G02X151779Y1588200I203J-1D01*
G37*
G36*
G01X290361D02*
X293181D01*
G02X293384Y1587998I1J-202D01*
G01Y1587376D01*
G03X293434Y1587244I200J0D01*
G02Y1584332I-1664J-1456D01*
G03X293384Y1584200I150J-132D01*
G01Y1582258D01*
G03X293434Y1582126I200J0D01*
G02Y1579214I-1664J-1456D01*
G03X293384Y1579082I150J-132D01*
G01Y1578460D01*
G02X293181Y1578258I-203J1D01*
G01X290361D01*
G02X290158Y1578460I-1J202D01*
G01Y1579082D01*
G03X290108Y1579214I-200J0D01*
G02Y1582126I1664J1456D01*
G03X290158Y1582258I-150J132D01*
G01Y1584200D01*
G03X290108Y1584332I-200J0D01*
G02Y1587244I1664J1456D01*
G03X290158Y1587376I-150J132D01*
G01Y1587998D01*
G02X290361Y1588200I203J-1D01*
G37*
G36*
G01X325007D02*
X327827D01*
G02X328030Y1587998I1J-202D01*
G01Y1587376D01*
G03X328080Y1587244I200J0D01*
G02Y1584332I-1664J-1456D01*
G03X328030Y1584200I150J-132D01*
G01Y1582258D01*
G03X328080Y1582126I200J0D01*
G02Y1579214I-1664J-1456D01*
G03X328030Y1579082I150J-132D01*
G01Y1578460D01*
G02X327827Y1578258I-203J1D01*
G01X325007D01*
G02X324804Y1578460I-1J202D01*
G01Y1579082D01*
G03X324754Y1579214I-200J0D01*
G02Y1582126I1664J1456D01*
G03X324804Y1582258I-150J132D01*
G01Y1584200D01*
G03X324754Y1584332I-200J0D01*
G02Y1587244I1664J1456D01*
G03X324804Y1587376I-150J132D01*
G01Y1587998D01*
G02X325007Y1588200I203J-1D01*
G37*
G36*
G01X515559D02*
X518379D01*
G02X518582Y1587998I1J-202D01*
G01Y1587376D01*
G03X518632Y1587244I200J0D01*
G02Y1584332I-1664J-1456D01*
G03X518582Y1584200I150J-132D01*
G01Y1582258D01*
G03X518632Y1582126I200J0D01*
G02Y1579214I-1664J-1456D01*
G03X518582Y1579082I150J-132D01*
G01Y1578460D01*
G02X518379Y1578258I-203J1D01*
G01X515559D01*
G02X515356Y1578460I-1J202D01*
G01Y1579082D01*
G03X515306Y1579214I-200J0D01*
G02Y1582126I1664J1456D01*
G03X515356Y1582258I-150J132D01*
G01Y1584200D01*
G03X515306Y1584332I-200J0D01*
G02Y1587244I1664J1456D01*
G03X515356Y1587376I-150J132D01*
G01Y1587998D01*
G02X515559Y1588200I203J-1D01*
G37*
G36*
G01X654141D02*
X656961D01*
G02X657164Y1587998I1J-202D01*
G01Y1587376D01*
G03X657214Y1587244I200J0D01*
G02Y1584332I-1664J-1456D01*
G03X657164Y1584200I150J-132D01*
G01Y1582258D01*
G03X657214Y1582126I200J0D01*
G02Y1579214I-1664J-1456D01*
G03X657164Y1579082I150J-132D01*
G01Y1578460D01*
G02X656961Y1578258I-203J1D01*
G01X654141D01*
G02X653938Y1578460I-1J202D01*
G01Y1579082D01*
G03X653888Y1579214I-200J0D01*
G02Y1582126I1664J1456D01*
G03X653938Y1582258I-150J132D01*
G01Y1584200D01*
G03X653888Y1584332I-200J0D01*
G02Y1587244I1664J1456D01*
G03X653938Y1587376I-150J132D01*
G01Y1587998D01*
G02X654141Y1588200I203J-1D01*
G37*
G36*
G01X688787D02*
X691607D01*
G02X691810Y1587998I1J-202D01*
G01Y1587376D01*
G03X691860Y1587244I200J0D01*
G02Y1584332I-1664J-1456D01*
G03X691810Y1584200I150J-132D01*
G01Y1582258D01*
G03X691860Y1582126I200J0D01*
G02Y1579214I-1664J-1456D01*
G03X691810Y1579082I150J-132D01*
G01Y1578460D01*
G02X691607Y1578258I-203J1D01*
G01X688787D01*
G02X688584Y1578460I-1J202D01*
G01Y1579082D01*
G03X688534Y1579214I-200J0D01*
G02Y1582126I1664J1456D01*
G03X688584Y1582258I-150J132D01*
G01Y1584200D01*
G03X688534Y1584332I-200J0D01*
G02Y1587244I1664J1456D01*
G03X688584Y1587376I-150J132D01*
G01Y1587998D01*
G02X688787Y1588200I203J-1D01*
G37*
G36*
G01X1139101D02*
X1141921D01*
G02X1142124Y1587998I1J-202D01*
G01Y1587376D01*
G03X1142174Y1587244I200J0D01*
G02Y1584332I-1664J-1456D01*
G03X1142124Y1584200I150J-132D01*
G01Y1582258D01*
G03X1142174Y1582126I200J0D01*
G02Y1579214I-1664J-1456D01*
G03X1142124Y1579082I150J-132D01*
G01Y1578460D01*
G02X1141921Y1578258I-203J1D01*
G01X1139101D01*
G02X1138898Y1578460I-1J202D01*
G01Y1579082D01*
G03X1138848Y1579214I-200J0D01*
G02Y1582126I1664J1456D01*
G03X1138898Y1582258I-150J132D01*
G01Y1584200D01*
G03X1138848Y1584332I-200J0D01*
G02Y1587244I1664J1456D01*
G03X1138898Y1587376I-150J132D01*
G01Y1587998D01*
G02X1139101Y1588200I203J-1D01*
G37*
G36*
G01X1173747D02*
X1176567D01*
G02X1176770Y1587998I1J-202D01*
G01Y1587376D01*
G03X1176820Y1587244I200J0D01*
G02Y1584332I-1664J-1456D01*
G03X1176770Y1584200I150J-132D01*
G01Y1582258D01*
G03X1176820Y1582126I200J0D01*
G02Y1579214I-1664J-1456D01*
G03X1176770Y1579082I150J-132D01*
G01Y1578460D01*
G02X1176567Y1578258I-203J1D01*
G01X1173747D01*
G02X1173544Y1578460I-1J202D01*
G01Y1579082D01*
G03X1173494Y1579214I-200J0D01*
G02Y1582126I1664J1456D01*
G03X1173544Y1582258I-150J132D01*
G01Y1584200D01*
G03X1173494Y1584332I-200J0D01*
G02Y1587244I1664J1456D01*
G03X1173544Y1587376I-150J132D01*
G01Y1587998D01*
G02X1173747Y1588200I203J-1D01*
G37*
G36*
G01X1329653D02*
X1332473D01*
G02X1332676Y1587998I1J-202D01*
G01Y1587376D01*
G03X1332726Y1587244I200J0D01*
G02Y1584332I-1664J-1456D01*
G03X1332676Y1584200I150J-132D01*
G01Y1582258D01*
G03X1332726Y1582126I200J0D01*
G02Y1579214I-1664J-1456D01*
G03X1332676Y1579082I150J-132D01*
G01Y1578460D01*
G02X1332473Y1578258I-203J1D01*
G01X1329653D01*
G02X1329450Y1578460I-1J202D01*
G01Y1579082D01*
G03X1329400Y1579214I-200J0D01*
G02Y1582126I1664J1456D01*
G03X1329450Y1582258I-150J132D01*
G01Y1584200D01*
G03X1329400Y1584332I-200J0D01*
G02Y1587244I1664J1456D01*
G03X1329450Y1587376I-150J132D01*
G01Y1587998D01*
G02X1329653Y1588200I203J-1D01*
G37*
G36*
G01X1364299D02*
X1367119D01*
G02X1367322Y1587998I1J-202D01*
G01Y1587376D01*
G03X1367372Y1587244I200J0D01*
G02Y1584332I-1664J-1456D01*
G03X1367322Y1584200I150J-132D01*
G01Y1582258D01*
G03X1367372Y1582126I200J0D01*
G02Y1579214I-1664J-1456D01*
G03X1367322Y1579082I150J-132D01*
G01Y1578460D01*
G02X1367119Y1578258I-203J1D01*
G01X1364299D01*
G02X1364096Y1578460I-1J202D01*
G01Y1579082D01*
G03X1364046Y1579214I-200J0D01*
G02Y1582126I1664J1456D01*
G03X1364096Y1582258I-150J132D01*
G01Y1584200D01*
G03X1364046Y1584332I-200J0D01*
G02Y1587244I1664J1456D01*
G03X1364096Y1587376I-150J132D01*
G01Y1587998D01*
G02X1364299Y1588200I203J-1D01*
G37*
G36*
G01X1676109D02*
X1678929D01*
G02X1679132Y1587998I1J-202D01*
G01Y1587376D01*
G03X1679182Y1587244I200J0D01*
G02Y1584332I-1664J-1456D01*
G03X1679132Y1584200I150J-132D01*
G01Y1582258D01*
G03X1679182Y1582126I200J0D01*
G02Y1579214I-1664J-1456D01*
G03X1679132Y1579082I150J-132D01*
G01Y1578460D01*
G02X1678929Y1578258I-203J1D01*
G01X1676109D01*
G02X1675906Y1578460I-1J202D01*
G01Y1579082D01*
G03X1675856Y1579214I-200J0D01*
G02Y1582126I1664J1456D01*
G03X1675906Y1582258I-150J132D01*
G01Y1584200D01*
G03X1675856Y1584332I-200J0D01*
G02Y1587244I1664J1456D01*
G03X1675906Y1587376I-150J132D01*
G01Y1587998D01*
G02X1676109Y1588200I203J-1D01*
G37*
G36*
G01X1710755D02*
X1713575D01*
G02X1713778Y1587998I1J-202D01*
G01Y1587376D01*
G03X1713828Y1587244I200J0D01*
G02Y1584332I-1664J-1456D01*
G03X1713778Y1584200I150J-132D01*
G01Y1582258D01*
G03X1713828Y1582126I200J0D01*
G02Y1579214I-1664J-1456D01*
G03X1713778Y1579082I150J-132D01*
G01Y1578460D01*
G02X1713575Y1578258I-203J1D01*
G01X1710755D01*
G02X1710552Y1578460I-1J202D01*
G01Y1579082D01*
G03X1710502Y1579214I-200J0D01*
G02Y1582126I1664J1456D01*
G03X1710552Y1582258I-150J132D01*
G01Y1584200D01*
G03X1710502Y1584332I-200J0D01*
G02Y1587244I1664J1456D01*
G03X1710552Y1587376I-150J132D01*
G01Y1587998D01*
G02X1710755Y1588200I203J-1D01*
G37*
G36*
G01X108472Y1599224D02*
X111292D01*
G02X111494Y1599021I-1J-203D01*
G01Y1598401D01*
G03X111544Y1598269I200J0D01*
G02Y1595353I-1661J-1458D01*
G03X111494Y1595221I150J-132D01*
G01Y1593283D01*
G03X111544Y1593151I200J0D01*
G02Y1590235I-1661J-1458D01*
G03X111494Y1590103I150J-132D01*
G01Y1589483D01*
G02X111292Y1589280I-202J-1D01*
G01X108472D01*
G02X108270Y1589483I1J203D01*
G01Y1590103D01*
G03X108220Y1590235I-200J0D01*
G02Y1593151I1661J1458D01*
G03X108270Y1593283I-150J132D01*
G01Y1595221D01*
G03X108220Y1595353I-200J0D01*
G02Y1598269I1661J1458D01*
G03X108270Y1598401I-150J132D01*
G01Y1599021D01*
G02X108472Y1599224I202J1D01*
G37*
G36*
G01X125795D02*
X128615D01*
G02X128818Y1599021I0J-203D01*
G01Y1598399D01*
G03X128868Y1598267I200J0D01*
G02Y1595355I-1664J-1456D01*
G03X128818Y1595223I150J-132D01*
G01Y1593281D01*
G03X128868Y1593149I200J0D01*
G02Y1590237I-1664J-1456D01*
G03X128818Y1590105I150J-132D01*
G01Y1589483D01*
G02X128615Y1589280I-203J0D01*
G01X125795D01*
G02X125592Y1589483I0J203D01*
G01Y1590105D01*
G03X125542Y1590237I-200J0D01*
G02Y1593149I1664J1456D01*
G03X125592Y1593281I-150J132D01*
G01Y1595223D01*
G03X125542Y1595355I-200J0D01*
G02Y1598267I1664J1456D01*
G03X125592Y1598399I-150J132D01*
G01Y1599021D01*
G02X125795Y1599224I203J0D01*
G37*
G36*
G01X143118D02*
X145938D01*
G02X146140Y1599021I-1J-203D01*
G01Y1598401D01*
G03X146190Y1598269I200J0D01*
G02Y1595353I-1661J-1458D01*
G03X146140Y1595221I150J-132D01*
G01Y1593283D01*
G03X146190Y1593151I200J0D01*
G02Y1590235I-1661J-1458D01*
G03X146140Y1590103I150J-132D01*
G01Y1589483D01*
G02X145938Y1589280I-202J-1D01*
G01X143118D01*
G02X142916Y1589483I1J203D01*
G01Y1590103D01*
G03X142866Y1590235I-200J0D01*
G02Y1593151I1661J1458D01*
G03X142916Y1593283I-150J132D01*
G01Y1595221D01*
G03X142866Y1595353I-200J0D01*
G02Y1598269I1661J1458D01*
G03X142916Y1598401I-150J132D01*
G01Y1599021D01*
G02X143118Y1599224I202J1D01*
G37*
G36*
G01X160440D02*
X163260D01*
G02X163462Y1599021I-1J-203D01*
G01Y1598401D01*
G03X163512Y1598269I200J0D01*
G02Y1595353I-1661J-1458D01*
G03X163462Y1595221I150J-132D01*
G01Y1593283D01*
G03X163512Y1593151I200J0D01*
G02Y1590235I-1661J-1458D01*
G03X163462Y1590103I150J-132D01*
G01Y1589483D01*
G02X163260Y1589280I-202J-1D01*
G01X160440D01*
G02X160238Y1589483I1J203D01*
G01Y1590103D01*
G03X160188Y1590235I-200J0D01*
G02Y1593151I1661J1458D01*
G03X160238Y1593283I-150J132D01*
G01Y1595221D01*
G03X160188Y1595353I-200J0D01*
G02Y1598269I1661J1458D01*
G03X160238Y1598401I-150J132D01*
G01Y1599021D01*
G02X160440Y1599224I202J1D01*
G37*
G36*
G01X281700D02*
X284520D01*
G02X284722Y1599021I-1J-203D01*
G01Y1598401D01*
G03X284772Y1598269I200J0D01*
G02Y1595353I-1661J-1458D01*
G03X284722Y1595221I150J-132D01*
G01Y1593283D01*
G03X284772Y1593151I200J0D01*
G02Y1590235I-1661J-1458D01*
G03X284722Y1590103I150J-132D01*
G01Y1589483D01*
G02X284520Y1589280I-202J-1D01*
G01X281700D01*
G02X281498Y1589483I1J203D01*
G01Y1590103D01*
G03X281448Y1590235I-200J0D01*
G02Y1593151I1661J1458D01*
G03X281498Y1593283I-150J132D01*
G01Y1595221D01*
G03X281448Y1595353I-200J0D01*
G02Y1598269I1661J1458D01*
G03X281498Y1598401I-150J132D01*
G01Y1599021D01*
G02X281700Y1599224I202J1D01*
G37*
G36*
G01X299023D02*
X301843D01*
G02X302046Y1599021I0J-203D01*
G01Y1598399D01*
G03X302096Y1598267I200J0D01*
G02Y1595355I-1664J-1456D01*
G03X302046Y1595223I150J-132D01*
G01Y1593281D01*
G03X302096Y1593149I200J0D01*
G02Y1590237I-1664J-1456D01*
G03X302046Y1590105I150J-132D01*
G01Y1589483D01*
G02X301843Y1589280I-203J0D01*
G01X299023D01*
G02X298820Y1589483I0J203D01*
G01Y1590105D01*
G03X298770Y1590237I-200J0D01*
G02Y1593149I1664J1456D01*
G03X298820Y1593281I-150J132D01*
G01Y1595223D01*
G03X298770Y1595355I-200J0D01*
G02Y1598267I1664J1456D01*
G03X298820Y1598399I-150J132D01*
G01Y1599021D01*
G02X299023Y1599224I203J0D01*
G37*
G36*
G01X316346D02*
X319166D01*
G02X319368Y1599021I-1J-203D01*
G01Y1598401D01*
G03X319418Y1598269I200J0D01*
G02Y1595353I-1661J-1458D01*
G03X319368Y1595221I150J-132D01*
G01Y1593283D01*
G03X319418Y1593151I200J0D01*
G02Y1590235I-1661J-1458D01*
G03X319368Y1590103I150J-132D01*
G01Y1589483D01*
G02X319166Y1589280I-202J-1D01*
G01X316346D01*
G02X316144Y1589483I1J203D01*
G01Y1590103D01*
G03X316094Y1590235I-200J0D01*
G02Y1593151I1661J1458D01*
G03X316144Y1593283I-150J132D01*
G01Y1595221D01*
G03X316094Y1595353I-200J0D01*
G02Y1598269I1661J1458D01*
G03X316144Y1598401I-150J132D01*
G01Y1599021D01*
G02X316346Y1599224I202J1D01*
G37*
G36*
G01X333668D02*
X336488D01*
G02X336690Y1599021I-1J-203D01*
G01Y1598401D01*
G03X336740Y1598269I200J0D01*
G02Y1595353I-1661J-1458D01*
G03X336690Y1595221I150J-132D01*
G01Y1593283D01*
G03X336740Y1593151I200J0D01*
G02Y1590235I-1661J-1458D01*
G03X336690Y1590103I150J-132D01*
G01Y1589483D01*
G02X336488Y1589280I-202J-1D01*
G01X333668D01*
G02X333466Y1589483I1J203D01*
G01Y1590103D01*
G03X333416Y1590235I-200J0D01*
G02Y1593151I1661J1458D01*
G03X333466Y1593283I-150J132D01*
G01Y1595221D01*
G03X333416Y1595353I-200J0D01*
G02Y1598269I1661J1458D01*
G03X333466Y1598401I-150J132D01*
G01Y1599021D01*
G02X333668Y1599224I202J1D01*
G37*
G36*
G01X628157D02*
X630977D01*
G02X631180Y1599021I0J-203D01*
G01Y1598399D01*
G03X631230Y1598267I200J0D01*
G02Y1595355I-1664J-1456D01*
G03X631180Y1595223I150J-132D01*
G01Y1593281D01*
G03X631230Y1593149I200J0D01*
G02Y1590237I-1664J-1456D01*
G03X631180Y1590105I150J-132D01*
G01Y1589483D01*
G02X630977Y1589280I-203J0D01*
G01X628157D01*
G02X627954Y1589483I0J203D01*
G01Y1590105D01*
G03X627904Y1590237I-200J0D01*
G02Y1593149I1664J1456D01*
G03X627954Y1593281I-150J132D01*
G01Y1595223D01*
G03X627904Y1595355I-200J0D01*
G02Y1598267I1664J1456D01*
G03X627954Y1598399I-150J132D01*
G01Y1599021D01*
G02X628157Y1599224I203J0D01*
G37*
G36*
G01X645480D02*
X648300D01*
G02X648502Y1599021I-1J-203D01*
G01Y1598401D01*
G03X648552Y1598269I200J0D01*
G02Y1595353I-1661J-1458D01*
G03X648502Y1595221I150J-132D01*
G01Y1593283D01*
G03X648552Y1593151I200J0D01*
G02Y1590235I-1661J-1458D01*
G03X648502Y1590103I150J-132D01*
G01Y1589483D01*
G02X648300Y1589280I-202J-1D01*
G01X645480D01*
G02X645278Y1589483I1J203D01*
G01Y1590103D01*
G03X645228Y1590235I-200J0D01*
G02Y1593151I1661J1458D01*
G03X645278Y1593283I-150J132D01*
G01Y1595221D01*
G03X645228Y1595353I-200J0D01*
G02Y1598269I1661J1458D01*
G03X645278Y1598401I-150J132D01*
G01Y1599021D01*
G02X645480Y1599224I202J1D01*
G37*
G36*
G01X662803D02*
X665623D01*
G02X665826Y1599021I0J-203D01*
G01Y1598399D01*
G03X665876Y1598267I200J0D01*
G02Y1595355I-1664J-1456D01*
G03X665826Y1595223I150J-132D01*
G01Y1593281D01*
G03X665876Y1593149I200J0D01*
G02Y1590237I-1664J-1456D01*
G03X665826Y1590105I150J-132D01*
G01Y1589483D01*
G02X665623Y1589280I-203J0D01*
G01X662803D01*
G02X662600Y1589483I0J203D01*
G01Y1590105D01*
G03X662550Y1590237I-200J0D01*
G02Y1593149I1664J1456D01*
G03X662600Y1593281I-150J132D01*
G01Y1595223D01*
G03X662550Y1595355I-200J0D01*
G02Y1598267I1664J1456D01*
G03X662600Y1598399I-150J132D01*
G01Y1599021D01*
G02X662803Y1599224I203J0D01*
G37*
G36*
G01X680125D02*
X682945D01*
G02X683148Y1599021I0J-203D01*
G01Y1598399D01*
G03X683198Y1598267I200J0D01*
G02Y1595355I-1664J-1456D01*
G03X683148Y1595223I150J-132D01*
G01Y1593281D01*
G03X683198Y1593149I200J0D01*
G02Y1590237I-1664J-1456D01*
G03X683148Y1590105I150J-132D01*
G01Y1589483D01*
G02X682945Y1589280I-203J0D01*
G01X680125D01*
G02X679922Y1589483I0J203D01*
G01Y1590105D01*
G03X679872Y1590237I-200J0D01*
G02Y1593149I1664J1456D01*
G03X679922Y1593281I-150J132D01*
G01Y1595223D01*
G03X679872Y1595355I-200J0D01*
G02Y1598267I1664J1456D01*
G03X679922Y1598399I-150J132D01*
G01Y1599021D01*
G02X680125Y1599224I203J0D01*
G37*
G36*
G01X1130440D02*
X1133260D01*
G02X1133462Y1599021I-1J-203D01*
G01Y1598401D01*
G03X1133512Y1598269I200J0D01*
G02Y1595353I-1661J-1458D01*
G03X1133462Y1595221I150J-132D01*
G01Y1593283D01*
G03X1133512Y1593151I200J0D01*
G02Y1590235I-1661J-1458D01*
G03X1133462Y1590103I150J-132D01*
G01Y1589483D01*
G02X1133260Y1589280I-202J-1D01*
G01X1130440D01*
G02X1130238Y1589483I1J203D01*
G01Y1590103D01*
G03X1130188Y1590235I-200J0D01*
G02Y1593151I1661J1458D01*
G03X1130238Y1593283I-150J132D01*
G01Y1595221D01*
G03X1130188Y1595353I-200J0D01*
G02Y1598269I1661J1458D01*
G03X1130238Y1598401I-150J132D01*
G01Y1599021D01*
G02X1130440Y1599224I202J1D01*
G37*
G36*
G01X1147763D02*
X1150583D01*
G02X1150786Y1599021I0J-203D01*
G01Y1598399D01*
G03X1150836Y1598267I200J0D01*
G02Y1595355I-1664J-1456D01*
G03X1150786Y1595223I150J-132D01*
G01Y1593281D01*
G03X1150836Y1593149I200J0D01*
G02Y1590237I-1664J-1456D01*
G03X1150786Y1590105I150J-132D01*
G01Y1589483D01*
G02X1150583Y1589280I-203J0D01*
G01X1147763D01*
G02X1147560Y1589483I0J203D01*
G01Y1590105D01*
G03X1147510Y1590237I-200J0D01*
G02Y1593149I1664J1456D01*
G03X1147560Y1593281I-150J132D01*
G01Y1595223D01*
G03X1147510Y1595355I-200J0D01*
G02Y1598267I1664J1456D01*
G03X1147560Y1598399I-150J132D01*
G01Y1599021D01*
G02X1147763Y1599224I203J0D01*
G37*
G36*
G01X1165086D02*
X1167906D01*
G02X1168108Y1599021I-1J-203D01*
G01Y1598401D01*
G03X1168158Y1598269I200J0D01*
G02Y1595353I-1661J-1458D01*
G03X1168108Y1595221I150J-132D01*
G01Y1593283D01*
G03X1168158Y1593151I200J0D01*
G02Y1590235I-1661J-1458D01*
G03X1168108Y1590103I150J-132D01*
G01Y1589483D01*
G02X1167906Y1589280I-202J-1D01*
G01X1165086D01*
G02X1164884Y1589483I1J203D01*
G01Y1590103D01*
G03X1164834Y1590235I-200J0D01*
G02Y1593151I1661J1458D01*
G03X1164884Y1593283I-150J132D01*
G01Y1595221D01*
G03X1164834Y1595353I-200J0D01*
G02Y1598269I1661J1458D01*
G03X1164884Y1598401I-150J132D01*
G01Y1599021D01*
G02X1165086Y1599224I202J1D01*
G37*
G36*
G01X1182408D02*
X1185228D01*
G02X1185430Y1599021I-1J-203D01*
G01Y1598401D01*
G03X1185480Y1598269I200J0D01*
G02Y1595353I-1661J-1458D01*
G03X1185430Y1595221I150J-132D01*
G01Y1593283D01*
G03X1185480Y1593151I200J0D01*
G02Y1590235I-1661J-1458D01*
G03X1185430Y1590103I150J-132D01*
G01Y1589483D01*
G02X1185228Y1589280I-202J-1D01*
G01X1182408D01*
G02X1182206Y1589483I1J203D01*
G01Y1590103D01*
G03X1182156Y1590235I-200J0D01*
G02Y1593151I1661J1458D01*
G03X1182206Y1593283I-150J132D01*
G01Y1595221D01*
G03X1182156Y1595353I-200J0D01*
G02Y1598269I1661J1458D01*
G03X1182206Y1598401I-150J132D01*
G01Y1599021D01*
G02X1182408Y1599224I202J1D01*
G37*
G36*
G01X1303669D02*
X1306489D01*
G02X1306692Y1599021I0J-203D01*
G01Y1598399D01*
G03X1306742Y1598267I200J0D01*
G02Y1595355I-1664J-1456D01*
G03X1306692Y1595223I150J-132D01*
G01Y1593281D01*
G03X1306742Y1593149I200J0D01*
G02Y1590237I-1664J-1456D01*
G03X1306692Y1590105I150J-132D01*
G01Y1589483D01*
G02X1306489Y1589280I-203J0D01*
G01X1303669D01*
G02X1303466Y1589483I0J203D01*
G01Y1590105D01*
G03X1303416Y1590237I-200J0D01*
G02Y1593149I1664J1456D01*
G03X1303466Y1593281I-150J132D01*
G01Y1595223D01*
G03X1303416Y1595355I-200J0D01*
G02Y1598267I1664J1456D01*
G03X1303466Y1598399I-150J132D01*
G01Y1599021D01*
G02X1303669Y1599224I203J0D01*
G37*
G36*
G01X1320992D02*
X1323812D01*
G02X1324014Y1599021I-1J-203D01*
G01Y1598401D01*
G03X1324064Y1598269I200J0D01*
G02Y1595353I-1661J-1458D01*
G03X1324014Y1595221I150J-132D01*
G01Y1593283D01*
G03X1324064Y1593151I200J0D01*
G02Y1590235I-1661J-1458D01*
G03X1324014Y1590103I150J-132D01*
G01Y1589483D01*
G02X1323812Y1589280I-202J-1D01*
G01X1320992D01*
G02X1320790Y1589483I1J203D01*
G01Y1590103D01*
G03X1320740Y1590235I-200J0D01*
G02Y1593151I1661J1458D01*
G03X1320790Y1593283I-150J132D01*
G01Y1595221D01*
G03X1320740Y1595353I-200J0D01*
G02Y1598269I1661J1458D01*
G03X1320790Y1598401I-150J132D01*
G01Y1599021D01*
G02X1320992Y1599224I202J1D01*
G37*
G36*
G01X1338315D02*
X1341135D01*
G02X1341338Y1599021I0J-203D01*
G01Y1598399D01*
G03X1341388Y1598267I200J0D01*
G02Y1595355I-1664J-1456D01*
G03X1341338Y1595223I150J-132D01*
G01Y1593281D01*
G03X1341388Y1593149I200J0D01*
G02Y1590237I-1664J-1456D01*
G03X1341338Y1590105I150J-132D01*
G01Y1589483D01*
G02X1341135Y1589280I-203J0D01*
G01X1338315D01*
G02X1338112Y1589483I0J203D01*
G01Y1590105D01*
G03X1338062Y1590237I-200J0D01*
G02Y1593149I1664J1456D01*
G03X1338112Y1593281I-150J132D01*
G01Y1595223D01*
G03X1338062Y1595355I-200J0D01*
G02Y1598267I1664J1456D01*
G03X1338112Y1598399I-150J132D01*
G01Y1599021D01*
G02X1338315Y1599224I203J0D01*
G37*
G36*
G01X1355637D02*
X1358457D01*
G02X1358660Y1599021I0J-203D01*
G01Y1598399D01*
G03X1358710Y1598267I200J0D01*
G02Y1595355I-1664J-1456D01*
G03X1358660Y1595223I150J-132D01*
G01Y1593281D01*
G03X1358710Y1593149I200J0D01*
G02Y1590237I-1664J-1456D01*
G03X1358660Y1590105I150J-132D01*
G01Y1589483D01*
G02X1358457Y1589280I-203J0D01*
G01X1355637D01*
G02X1355434Y1589483I0J203D01*
G01Y1590105D01*
G03X1355384Y1590237I-200J0D01*
G02Y1593149I1664J1456D01*
G03X1355434Y1593281I-150J132D01*
G01Y1595223D01*
G03X1355384Y1595355I-200J0D01*
G02Y1598267I1664J1456D01*
G03X1355434Y1598399I-150J132D01*
G01Y1599021D01*
G02X1355637Y1599224I203J0D01*
G37*
G36*
G01X1476897D02*
X1479717D01*
G02X1479920Y1599021I0J-203D01*
G01Y1598399D01*
G03X1479970Y1598267I200J0D01*
G02Y1595355I-1664J-1456D01*
G03X1479920Y1595223I150J-132D01*
G01Y1593281D01*
G03X1479970Y1593149I200J0D01*
G02Y1590237I-1664J-1456D01*
G03X1479920Y1590105I150J-132D01*
G01Y1589483D01*
G02X1479717Y1589280I-203J0D01*
G01X1476897D01*
G02X1476694Y1589483I0J203D01*
G01Y1590105D01*
G03X1476644Y1590237I-200J0D01*
G02Y1593149I1664J1456D01*
G03X1476694Y1593281I-150J132D01*
G01Y1595223D01*
G03X1476644Y1595355I-200J0D01*
G02Y1598267I1664J1456D01*
G03X1476694Y1598399I-150J132D01*
G01Y1599021D01*
G02X1476897Y1599224I203J0D01*
G37*
G36*
G01X1650125D02*
X1652945D01*
G02X1653148Y1599021I0J-203D01*
G01Y1598399D01*
G03X1653198Y1598267I200J0D01*
G02Y1595355I-1664J-1456D01*
G03X1653148Y1595223I150J-132D01*
G01Y1593281D01*
G03X1653198Y1593149I200J0D01*
G02Y1590237I-1664J-1456D01*
G03X1653148Y1590105I150J-132D01*
G01Y1589483D01*
G02X1652945Y1589280I-203J0D01*
G01X1650125D01*
G02X1649922Y1589483I0J203D01*
G01Y1590105D01*
G03X1649872Y1590237I-200J0D01*
G02Y1593149I1664J1456D01*
G03X1649922Y1593281I-150J132D01*
G01Y1595223D01*
G03X1649872Y1595355I-200J0D01*
G02Y1598267I1664J1456D01*
G03X1649922Y1598399I-150J132D01*
G01Y1599021D01*
G02X1650125Y1599224I203J0D01*
G37*
G36*
G01X1667448D02*
X1670268D01*
G02X1670470Y1599021I-1J-203D01*
G01Y1598401D01*
G03X1670520Y1598269I200J0D01*
G02Y1595353I-1661J-1458D01*
G03X1670470Y1595221I150J-132D01*
G01Y1593283D01*
G03X1670520Y1593151I200J0D01*
G02Y1590235I-1661J-1458D01*
G03X1670470Y1590103I150J-132D01*
G01Y1589483D01*
G02X1670268Y1589280I-202J-1D01*
G01X1667448D01*
G02X1667246Y1589483I1J203D01*
G01Y1590103D01*
G03X1667196Y1590235I-200J0D01*
G02Y1593151I1661J1458D01*
G03X1667246Y1593283I-150J132D01*
G01Y1595221D01*
G03X1667196Y1595353I-200J0D01*
G02Y1598269I1661J1458D01*
G03X1667246Y1598401I-150J132D01*
G01Y1599021D01*
G02X1667448Y1599224I202J1D01*
G37*
G36*
G01X1684771D02*
X1687591D01*
G02X1687794Y1599021I0J-203D01*
G01Y1598399D01*
G03X1687844Y1598267I200J0D01*
G02Y1595355I-1664J-1456D01*
G03X1687794Y1595223I150J-132D01*
G01Y1593281D01*
G03X1687844Y1593149I200J0D01*
G02Y1590237I-1664J-1456D01*
G03X1687794Y1590105I150J-132D01*
G01Y1589483D01*
G02X1687591Y1589280I-203J0D01*
G01X1684771D01*
G02X1684568Y1589483I0J203D01*
G01Y1590105D01*
G03X1684518Y1590237I-200J0D01*
G02Y1593149I1664J1456D01*
G03X1684568Y1593281I-150J132D01*
G01Y1595223D01*
G03X1684518Y1595355I-200J0D01*
G02Y1598267I1664J1456D01*
G03X1684568Y1598399I-150J132D01*
G01Y1599021D01*
G02X1684771Y1599224I203J0D01*
G37*
G36*
G01X1702093D02*
X1704913D01*
G02X1705116Y1599021I0J-203D01*
G01Y1598399D01*
G03X1705166Y1598267I200J0D01*
G02Y1595355I-1664J-1456D01*
G03X1705116Y1595223I150J-132D01*
G01Y1593281D01*
G03X1705166Y1593149I200J0D01*
G02Y1590237I-1664J-1456D01*
G03X1705116Y1590105I150J-132D01*
G01Y1589483D01*
G02X1704913Y1589280I-203J0D01*
G01X1702093D01*
G02X1701890Y1589483I0J203D01*
G01Y1590105D01*
G03X1701840Y1590237I-200J0D01*
G02Y1593149I1664J1456D01*
G03X1701890Y1593281I-150J132D01*
G01Y1595223D01*
G03X1701840Y1595355I-200J0D01*
G02Y1598267I1664J1456D01*
G03X1701890Y1598399I-150J132D01*
G01Y1599021D01*
G02X1702093Y1599224I203J0D01*
G37*
G36*
G01X134456Y1603554D02*
X137276D01*
G02X137478Y1603352I0J-202D01*
G01Y1602732D01*
G03X137528Y1602600I200J0D01*
G02Y1599684I-1661J-1458D01*
G03X137478Y1599552I150J-132D01*
G01Y1597614D01*
G03X137528Y1597482I200J0D01*
G02Y1594566I-1661J-1458D01*
G03X137478Y1594434I150J-132D01*
G01Y1593814D01*
G02X137276Y1593612I-202J0D01*
G01X134456D01*
G02X134254Y1593814I0J202D01*
G01Y1594434D01*
G03X134204Y1594566I-200J0D01*
G02Y1597482I1661J1458D01*
G03X134254Y1597614I-150J132D01*
G01Y1599552D01*
G03X134204Y1599684I-200J0D01*
G02Y1602600I1661J1458D01*
G03X134254Y1602732I-150J132D01*
G01Y1603352D01*
G02X134456Y1603554I202J0D01*
G37*
G36*
G01X169102D02*
X171922D01*
G02X172124Y1603352I0J-202D01*
G01Y1602732D01*
G03X172174Y1602600I200J0D01*
G02Y1599684I-1661J-1458D01*
G03X172124Y1599552I150J-132D01*
G01Y1597614D01*
G03X172174Y1597482I200J0D01*
G02Y1594566I-1661J-1458D01*
G03X172124Y1594434I150J-132D01*
G01Y1593814D01*
G02X171922Y1593612I-202J0D01*
G01X169102D01*
G02X168900Y1593814I0J202D01*
G01Y1594434D01*
G03X168850Y1594566I-200J0D01*
G02Y1597482I1661J1458D01*
G03X168900Y1597614I-150J132D01*
G01Y1599552D01*
G03X168850Y1599684I-200J0D01*
G02Y1602600I1661J1458D01*
G03X168900Y1602732I-150J132D01*
G01Y1603352D01*
G02X169102Y1603554I202J0D01*
G37*
G36*
G01X307684D02*
X310504D01*
G02X310706Y1603352I0J-202D01*
G01Y1602732D01*
G03X310756Y1602600I200J0D01*
G02Y1599684I-1661J-1458D01*
G03X310706Y1599552I150J-132D01*
G01Y1597614D01*
G03X310756Y1597482I200J0D01*
G02Y1594566I-1661J-1458D01*
G03X310706Y1594434I150J-132D01*
G01Y1593814D01*
G02X310504Y1593612I-202J0D01*
G01X307684D01*
G02X307482Y1593814I0J202D01*
G01Y1594434D01*
G03X307432Y1594566I-200J0D01*
G02Y1597482I1661J1458D01*
G03X307482Y1597614I-150J132D01*
G01Y1599552D01*
G03X307432Y1599684I-200J0D01*
G02Y1602600I1661J1458D01*
G03X307482Y1602732I-150J132D01*
G01Y1603352D01*
G02X307684Y1603554I202J0D01*
G37*
G36*
G01X342330D02*
X345150D01*
G02X345352Y1603352I0J-202D01*
G01Y1602732D01*
G03X345402Y1602600I200J0D01*
G02Y1599684I-1661J-1458D01*
G03X345352Y1599552I150J-132D01*
G01Y1597614D01*
G03X345402Y1597482I200J0D01*
G02Y1594566I-1661J-1458D01*
G03X345352Y1594434I150J-132D01*
G01Y1593814D01*
G02X345150Y1593612I-202J0D01*
G01X342330D01*
G02X342128Y1593814I0J202D01*
G01Y1594434D01*
G03X342078Y1594566I-200J0D01*
G02Y1597482I1661J1458D01*
G03X342128Y1597614I-150J132D01*
G01Y1599552D01*
G03X342078Y1599684I-200J0D01*
G02Y1602600I1661J1458D01*
G03X342128Y1602732I-150J132D01*
G01Y1603352D01*
G02X342330Y1603554I202J0D01*
G37*
G36*
G01X636818D02*
X639638D01*
G02X639840Y1603352I0J-202D01*
G01Y1602732D01*
G03X639890Y1602600I200J0D01*
G02Y1599684I-1661J-1458D01*
G03X639840Y1599552I150J-132D01*
G01Y1597614D01*
G03X639890Y1597482I200J0D01*
G02Y1594566I-1661J-1458D01*
G03X639840Y1594434I150J-132D01*
G01Y1593814D01*
G02X639638Y1593612I-202J0D01*
G01X636818D01*
G02X636616Y1593814I0J202D01*
G01Y1594434D01*
G03X636566Y1594566I-200J0D01*
G02Y1597482I1661J1458D01*
G03X636616Y1597614I-150J132D01*
G01Y1599552D01*
G03X636566Y1599684I-200J0D01*
G02Y1602600I1661J1458D01*
G03X636616Y1602732I-150J132D01*
G01Y1603352D01*
G02X636818Y1603554I202J0D01*
G37*
G36*
G01X671464D02*
X674284D01*
G02X674486Y1603352I0J-202D01*
G01Y1602732D01*
G03X674536Y1602600I200J0D01*
G02Y1599684I-1661J-1458D01*
G03X674486Y1599552I150J-132D01*
G01Y1597614D01*
G03X674536Y1597482I200J0D01*
G02Y1594566I-1661J-1458D01*
G03X674486Y1594434I150J-132D01*
G01Y1593814D01*
G02X674284Y1593612I-202J0D01*
G01X671464D01*
G02X671262Y1593814I0J202D01*
G01Y1594434D01*
G03X671212Y1594566I-200J0D01*
G02Y1597482I1661J1458D01*
G03X671262Y1597614I-150J132D01*
G01Y1599552D01*
G03X671212Y1599684I-200J0D01*
G02Y1602600I1661J1458D01*
G03X671262Y1602732I-150J132D01*
G01Y1603352D01*
G02X671464Y1603554I202J0D01*
G37*
G36*
G01X1156424D02*
X1159244D01*
G02X1159446Y1603352I0J-202D01*
G01Y1602732D01*
G03X1159496Y1602600I200J0D01*
G02Y1599684I-1661J-1458D01*
G03X1159446Y1599552I150J-132D01*
G01Y1597614D01*
G03X1159496Y1597482I200J0D01*
G02Y1594566I-1661J-1458D01*
G03X1159446Y1594434I150J-132D01*
G01Y1593814D01*
G02X1159244Y1593612I-202J0D01*
G01X1156424D01*
G02X1156222Y1593814I0J202D01*
G01Y1594434D01*
G03X1156172Y1594566I-200J0D01*
G02Y1597482I1661J1458D01*
G03X1156222Y1597614I-150J132D01*
G01Y1599552D01*
G03X1156172Y1599684I-200J0D01*
G02Y1602600I1661J1458D01*
G03X1156222Y1602732I-150J132D01*
G01Y1603352D01*
G02X1156424Y1603554I202J0D01*
G37*
G36*
G01X1191070D02*
X1193890D01*
G02X1194092Y1603352I0J-202D01*
G01Y1602732D01*
G03X1194142Y1602600I200J0D01*
G02Y1599684I-1661J-1458D01*
G03X1194092Y1599552I150J-132D01*
G01Y1597614D01*
G03X1194142Y1597482I200J0D01*
G02Y1594566I-1661J-1458D01*
G03X1194092Y1594434I150J-132D01*
G01Y1593814D01*
G02X1193890Y1593612I-202J0D01*
G01X1191070D01*
G02X1190868Y1593814I0J202D01*
G01Y1594434D01*
G03X1190818Y1594566I-200J0D01*
G02Y1597482I1661J1458D01*
G03X1190868Y1597614I-150J132D01*
G01Y1599552D01*
G03X1190818Y1599684I-200J0D01*
G02Y1602600I1661J1458D01*
G03X1190868Y1602732I-150J132D01*
G01Y1603352D01*
G02X1191070Y1603554I202J0D01*
G37*
G36*
G01X1312330D02*
X1315150D01*
G02X1315352Y1603352I0J-202D01*
G01Y1602732D01*
G03X1315402Y1602600I200J0D01*
G02Y1599684I-1661J-1458D01*
G03X1315352Y1599552I150J-132D01*
G01Y1597614D01*
G03X1315402Y1597482I200J0D01*
G02Y1594566I-1661J-1458D01*
G03X1315352Y1594434I150J-132D01*
G01Y1593814D01*
G02X1315150Y1593612I-202J0D01*
G01X1312330D01*
G02X1312128Y1593814I0J202D01*
G01Y1594434D01*
G03X1312078Y1594566I-200J0D01*
G02Y1597482I1661J1458D01*
G03X1312128Y1597614I-150J132D01*
G01Y1599552D01*
G03X1312078Y1599684I-200J0D01*
G02Y1602600I1661J1458D01*
G03X1312128Y1602732I-150J132D01*
G01Y1603352D01*
G02X1312330Y1603554I202J0D01*
G37*
G36*
G01X1346976D02*
X1349796D01*
G02X1349998Y1603352I0J-202D01*
G01Y1602732D01*
G03X1350048Y1602600I200J0D01*
G02Y1599684I-1661J-1458D01*
G03X1349998Y1599552I150J-132D01*
G01Y1597614D01*
G03X1350048Y1597482I200J0D01*
G02Y1594566I-1661J-1458D01*
G03X1349998Y1594434I150J-132D01*
G01Y1593814D01*
G02X1349796Y1593612I-202J0D01*
G01X1346976D01*
G02X1346774Y1593814I0J202D01*
G01Y1594434D01*
G03X1346724Y1594566I-200J0D01*
G02Y1597482I1661J1458D01*
G03X1346774Y1597614I-150J132D01*
G01Y1599552D01*
G03X1346724Y1599684I-200J0D01*
G02Y1602600I1661J1458D01*
G03X1346774Y1602732I-150J132D01*
G01Y1603352D01*
G02X1346976Y1603554I202J0D01*
G37*
G36*
G01X1658786D02*
X1661606D01*
G02X1661808Y1603352I0J-202D01*
G01Y1602732D01*
G03X1661858Y1602600I200J0D01*
G02Y1599684I-1661J-1458D01*
G03X1661808Y1599552I150J-132D01*
G01Y1597614D01*
G03X1661858Y1597482I200J0D01*
G02Y1594566I-1661J-1458D01*
G03X1661808Y1594434I150J-132D01*
G01Y1593814D01*
G02X1661606Y1593612I-202J0D01*
G01X1658786D01*
G02X1658584Y1593814I0J202D01*
G01Y1594434D01*
G03X1658534Y1594566I-200J0D01*
G02Y1597482I1661J1458D01*
G03X1658584Y1597614I-150J132D01*
G01Y1599552D01*
G03X1658534Y1599684I-200J0D01*
G02Y1602600I1661J1458D01*
G03X1658584Y1602732I-150J132D01*
G01Y1603352D01*
G02X1658786Y1603554I202J0D01*
G37*
G36*
G01X1693432D02*
X1696252D01*
G02X1696454Y1603352I0J-202D01*
G01Y1602732D01*
G03X1696504Y1602600I200J0D01*
G02Y1599684I-1661J-1458D01*
G03X1696454Y1599552I150J-132D01*
G01Y1597614D01*
G03X1696504Y1597482I200J0D01*
G02Y1594566I-1661J-1458D01*
G03X1696454Y1594434I150J-132D01*
G01Y1593814D01*
G02X1696252Y1593612I-202J0D01*
G01X1693432D01*
G02X1693230Y1593814I0J202D01*
G01Y1594434D01*
G03X1693180Y1594566I-200J0D01*
G02Y1597482I1661J1458D01*
G03X1693230Y1597614I-150J132D01*
G01Y1599552D01*
G03X1693180Y1599684I-200J0D01*
G02Y1602600I1661J1458D01*
G03X1693230Y1602732I-150J132D01*
G01Y1603352D01*
G02X1693432Y1603554I202J0D01*
G37*
G36*
G01X117133D02*
X119953D01*
G02X120156Y1603352I1J-202D01*
G01Y1602730D01*
G03X120206Y1602598I200J0D01*
G02Y1599686I-1664J-1456D01*
G03X120156Y1599554I150J-132D01*
G01Y1597612D01*
G03X120206Y1597480I200J0D01*
G02Y1594568I-1664J-1456D01*
G03X120156Y1594436I150J-132D01*
G01Y1593814D01*
G02X119953Y1593612I-203J1D01*
G01X117133D01*
G02X116930Y1593814I-1J202D01*
G01Y1594436D01*
G03X116880Y1594568I-200J0D01*
G02Y1597480I1664J1456D01*
G03X116930Y1597612I-150J132D01*
G01Y1599554D01*
G03X116880Y1599686I-200J0D01*
G02Y1602598I1664J1456D01*
G03X116930Y1602730I-150J132D01*
G01Y1603352D01*
G02X117133Y1603554I203J-1D01*
G37*
G36*
G01X151779D02*
X154599D01*
G02X154802Y1603352I1J-202D01*
G01Y1602730D01*
G03X154852Y1602598I200J0D01*
G02Y1599686I-1664J-1456D01*
G03X154802Y1599554I150J-132D01*
G01Y1597612D01*
G03X154852Y1597480I200J0D01*
G02Y1594568I-1664J-1456D01*
G03X154802Y1594436I150J-132D01*
G01Y1593814D01*
G02X154599Y1593612I-203J1D01*
G01X151779D01*
G02X151576Y1593814I-1J202D01*
G01Y1594436D01*
G03X151526Y1594568I-200J0D01*
G02Y1597480I1664J1456D01*
G03X151576Y1597612I-150J132D01*
G01Y1599554D01*
G03X151526Y1599686I-200J0D01*
G02Y1602598I1664J1456D01*
G03X151576Y1602730I-150J132D01*
G01Y1603352D01*
G02X151779Y1603554I203J-1D01*
G37*
G36*
G01X186425D02*
X189245D01*
G02X189448Y1603352I1J-202D01*
G01Y1602730D01*
G03X189498Y1602598I200J0D01*
G02Y1599686I-1664J-1456D01*
G03X189448Y1599554I150J-132D01*
G01Y1597612D01*
G03X189498Y1597480I200J0D01*
G02Y1594568I-1664J-1456D01*
G03X189448Y1594436I150J-132D01*
G01Y1593814D01*
G02X189245Y1593612I-203J1D01*
G01X186425D01*
G02X186222Y1593814I-1J202D01*
G01Y1594436D01*
G03X186172Y1594568I-200J0D01*
G02Y1597480I1664J1456D01*
G03X186222Y1597612I-150J132D01*
G01Y1599554D01*
G03X186172Y1599686I-200J0D01*
G02Y1602598I1664J1456D01*
G03X186222Y1602730I-150J132D01*
G01Y1603352D01*
G02X186425Y1603554I203J-1D01*
G37*
G36*
G01X290361D02*
X293181D01*
G02X293384Y1603352I1J-202D01*
G01Y1602730D01*
G03X293434Y1602598I200J0D01*
G02Y1599686I-1664J-1456D01*
G03X293384Y1599554I150J-132D01*
G01Y1597612D01*
G03X293434Y1597480I200J0D01*
G02Y1594568I-1664J-1456D01*
G03X293384Y1594436I150J-132D01*
G01Y1593814D01*
G02X293181Y1593612I-203J1D01*
G01X290361D01*
G02X290158Y1593814I-1J202D01*
G01Y1594436D01*
G03X290108Y1594568I-200J0D01*
G02Y1597480I1664J1456D01*
G03X290158Y1597612I-150J132D01*
G01Y1599554D01*
G03X290108Y1599686I-200J0D01*
G02Y1602598I1664J1456D01*
G03X290158Y1602730I-150J132D01*
G01Y1603352D01*
G02X290361Y1603554I203J-1D01*
G37*
G36*
G01X325007D02*
X327827D01*
G02X328030Y1603352I1J-202D01*
G01Y1602730D01*
G03X328080Y1602598I200J0D01*
G02Y1599686I-1664J-1456D01*
G03X328030Y1599554I150J-132D01*
G01Y1597612D01*
G03X328080Y1597480I200J0D01*
G02Y1594568I-1664J-1456D01*
G03X328030Y1594436I150J-132D01*
G01Y1593814D01*
G02X327827Y1593612I-203J1D01*
G01X325007D01*
G02X324804Y1593814I-1J202D01*
G01Y1594436D01*
G03X324754Y1594568I-200J0D01*
G02Y1597480I1664J1456D01*
G03X324804Y1597612I-150J132D01*
G01Y1599554D01*
G03X324754Y1599686I-200J0D01*
G02Y1602598I1664J1456D01*
G03X324804Y1602730I-150J132D01*
G01Y1603352D01*
G02X325007Y1603554I203J-1D01*
G37*
G36*
G01X359653D02*
X362473D01*
G02X362676Y1603352I1J-202D01*
G01Y1602730D01*
G03X362726Y1602598I200J0D01*
G02Y1599686I-1664J-1456D01*
G03X362676Y1599554I150J-132D01*
G01Y1597612D01*
G03X362726Y1597480I200J0D01*
G02Y1594568I-1664J-1456D01*
G03X362676Y1594436I150J-132D01*
G01Y1593814D01*
G02X362473Y1593612I-203J1D01*
G01X359653D01*
G02X359450Y1593814I-1J202D01*
G01Y1594436D01*
G03X359400Y1594568I-200J0D01*
G02Y1597480I1664J1456D01*
G03X359450Y1597612I-150J132D01*
G01Y1599554D01*
G03X359400Y1599686I-200J0D01*
G02Y1602598I1664J1456D01*
G03X359450Y1602730I-150J132D01*
G01Y1603352D01*
G02X359653Y1603554I203J-1D01*
G37*
G36*
G01X515559D02*
X518379D01*
G02X518582Y1603352I1J-202D01*
G01Y1602730D01*
G03X518632Y1602598I200J0D01*
G02Y1599686I-1664J-1456D01*
G03X518582Y1599554I150J-132D01*
G01Y1597612D01*
G03X518632Y1597480I200J0D01*
G02Y1594568I-1664J-1456D01*
G03X518582Y1594436I150J-132D01*
G01Y1593814D01*
G02X518379Y1593612I-203J1D01*
G01X515559D01*
G02X515356Y1593814I-1J202D01*
G01Y1594436D01*
G03X515306Y1594568I-200J0D01*
G02Y1597480I1664J1456D01*
G03X515356Y1597612I-150J132D01*
G01Y1599554D01*
G03X515306Y1599686I-200J0D01*
G02Y1602598I1664J1456D01*
G03X515356Y1602730I-150J132D01*
G01Y1603352D01*
G02X515559Y1603554I203J-1D01*
G37*
G36*
G01X654141D02*
X656961D01*
G02X657164Y1603352I1J-202D01*
G01Y1602730D01*
G03X657214Y1602598I200J0D01*
G02Y1599686I-1664J-1456D01*
G03X657164Y1599554I150J-132D01*
G01Y1597612D01*
G03X657214Y1597480I200J0D01*
G02Y1594568I-1664J-1456D01*
G03X657164Y1594436I150J-132D01*
G01Y1593814D01*
G02X656961Y1593612I-203J1D01*
G01X654141D01*
G02X653938Y1593814I-1J202D01*
G01Y1594436D01*
G03X653888Y1594568I-200J0D01*
G02Y1597480I1664J1456D01*
G03X653938Y1597612I-150J132D01*
G01Y1599554D01*
G03X653888Y1599686I-200J0D01*
G02Y1602598I1664J1456D01*
G03X653938Y1602730I-150J132D01*
G01Y1603352D01*
G02X654141Y1603554I203J-1D01*
G37*
G36*
G01X688787D02*
X691607D01*
G02X691810Y1603352I1J-202D01*
G01Y1602730D01*
G03X691860Y1602598I200J0D01*
G02Y1599686I-1664J-1456D01*
G03X691810Y1599554I150J-132D01*
G01Y1597612D01*
G03X691860Y1597480I200J0D01*
G02Y1594568I-1664J-1456D01*
G03X691810Y1594436I150J-132D01*
G01Y1593814D01*
G02X691607Y1593612I-203J1D01*
G01X688787D01*
G02X688584Y1593814I-1J202D01*
G01Y1594436D01*
G03X688534Y1594568I-200J0D01*
G02Y1597480I1664J1456D01*
G03X688584Y1597612I-150J132D01*
G01Y1599554D01*
G03X688534Y1599686I-200J0D01*
G02Y1602598I1664J1456D01*
G03X688584Y1602730I-150J132D01*
G01Y1603352D01*
G02X688787Y1603554I203J-1D01*
G37*
G36*
G01X1139101D02*
X1141921D01*
G02X1142124Y1603352I1J-202D01*
G01Y1602730D01*
G03X1142174Y1602598I200J0D01*
G02Y1599686I-1664J-1456D01*
G03X1142124Y1599554I150J-132D01*
G01Y1597612D01*
G03X1142174Y1597480I200J0D01*
G02Y1594568I-1664J-1456D01*
G03X1142124Y1594436I150J-132D01*
G01Y1593814D01*
G02X1141921Y1593612I-203J1D01*
G01X1139101D01*
G02X1138898Y1593814I-1J202D01*
G01Y1594436D01*
G03X1138848Y1594568I-200J0D01*
G02Y1597480I1664J1456D01*
G03X1138898Y1597612I-150J132D01*
G01Y1599554D01*
G03X1138848Y1599686I-200J0D01*
G02Y1602598I1664J1456D01*
G03X1138898Y1602730I-150J132D01*
G01Y1603352D01*
G02X1139101Y1603554I203J-1D01*
G37*
G36*
G01X1173747D02*
X1176567D01*
G02X1176770Y1603352I1J-202D01*
G01Y1602730D01*
G03X1176820Y1602598I200J0D01*
G02Y1599686I-1664J-1456D01*
G03X1176770Y1599554I150J-132D01*
G01Y1597612D01*
G03X1176820Y1597480I200J0D01*
G02Y1594568I-1664J-1456D01*
G03X1176770Y1594436I150J-132D01*
G01Y1593814D01*
G02X1176567Y1593612I-203J1D01*
G01X1173747D01*
G02X1173544Y1593814I-1J202D01*
G01Y1594436D01*
G03X1173494Y1594568I-200J0D01*
G02Y1597480I1664J1456D01*
G03X1173544Y1597612I-150J132D01*
G01Y1599554D01*
G03X1173494Y1599686I-200J0D01*
G02Y1602598I1664J1456D01*
G03X1173544Y1602730I-150J132D01*
G01Y1603352D01*
G02X1173747Y1603554I203J-1D01*
G37*
G36*
G01X1329653D02*
X1332473D01*
G02X1332676Y1603352I1J-202D01*
G01Y1602730D01*
G03X1332726Y1602598I200J0D01*
G02Y1599686I-1664J-1456D01*
G03X1332676Y1599554I150J-132D01*
G01Y1597612D01*
G03X1332726Y1597480I200J0D01*
G02Y1594568I-1664J-1456D01*
G03X1332676Y1594436I150J-132D01*
G01Y1593814D01*
G02X1332473Y1593612I-203J1D01*
G01X1329653D01*
G02X1329450Y1593814I-1J202D01*
G01Y1594436D01*
G03X1329400Y1594568I-200J0D01*
G02Y1597480I1664J1456D01*
G03X1329450Y1597612I-150J132D01*
G01Y1599554D01*
G03X1329400Y1599686I-200J0D01*
G02Y1602598I1664J1456D01*
G03X1329450Y1602730I-150J132D01*
G01Y1603352D01*
G02X1329653Y1603554I203J-1D01*
G37*
G36*
G01X1364299D02*
X1367119D01*
G02X1367322Y1603352I1J-202D01*
G01Y1602730D01*
G03X1367372Y1602598I200J0D01*
G02Y1599686I-1664J-1456D01*
G03X1367322Y1599554I150J-132D01*
G01Y1597612D01*
G03X1367372Y1597480I200J0D01*
G02Y1594568I-1664J-1456D01*
G03X1367322Y1594436I150J-132D01*
G01Y1593814D01*
G02X1367119Y1593612I-203J1D01*
G01X1364299D01*
G02X1364096Y1593814I-1J202D01*
G01Y1594436D01*
G03X1364046Y1594568I-200J0D01*
G02Y1597480I1664J1456D01*
G03X1364096Y1597612I-150J132D01*
G01Y1599554D01*
G03X1364046Y1599686I-200J0D01*
G02Y1602598I1664J1456D01*
G03X1364096Y1602730I-150J132D01*
G01Y1603352D01*
G02X1364299Y1603554I203J-1D01*
G37*
G36*
G01X1676109D02*
X1678929D01*
G02X1679132Y1603352I1J-202D01*
G01Y1602730D01*
G03X1679182Y1602598I200J0D01*
G02Y1599686I-1664J-1456D01*
G03X1679132Y1599554I150J-132D01*
G01Y1597612D01*
G03X1679182Y1597480I200J0D01*
G02Y1594568I-1664J-1456D01*
G03X1679132Y1594436I150J-132D01*
G01Y1593814D01*
G02X1678929Y1593612I-203J1D01*
G01X1676109D01*
G02X1675906Y1593814I-1J202D01*
G01Y1594436D01*
G03X1675856Y1594568I-200J0D01*
G02Y1597480I1664J1456D01*
G03X1675906Y1597612I-150J132D01*
G01Y1599554D01*
G03X1675856Y1599686I-200J0D01*
G02Y1602598I1664J1456D01*
G03X1675906Y1602730I-150J132D01*
G01Y1603352D01*
G02X1676109Y1603554I203J-1D01*
G37*
G36*
G01X1710755D02*
X1713575D01*
G02X1713778Y1603352I1J-202D01*
G01Y1602730D01*
G03X1713828Y1602598I200J0D01*
G02Y1599686I-1664J-1456D01*
G03X1713778Y1599554I150J-132D01*
G01Y1597612D01*
G03X1713828Y1597480I200J0D01*
G02Y1594568I-1664J-1456D01*
G03X1713778Y1594436I150J-132D01*
G01Y1593814D01*
G02X1713575Y1593612I-203J1D01*
G01X1710755D01*
G02X1710552Y1593814I-1J202D01*
G01Y1594436D01*
G03X1710502Y1594568I-200J0D01*
G02Y1597480I1664J1456D01*
G03X1710552Y1597612I-150J132D01*
G01Y1599554D01*
G03X1710502Y1599686I-200J0D01*
G02Y1602598I1664J1456D01*
G03X1710552Y1602730I-150J132D01*
G01Y1603352D01*
G02X1710755Y1603554I203J-1D01*
G37*
G36*
G01X108472Y1614578D02*
X111292D01*
G02X111494Y1614376I0J-202D01*
G01Y1613756D01*
G03X111544Y1613624I200J0D01*
G02Y1610708I-1661J-1458D01*
G03X111494Y1610576I150J-132D01*
G01Y1608638D01*
G03X111544Y1608506I200J0D01*
G02Y1605590I-1661J-1458D01*
G03X111494Y1605458I150J-132D01*
G01Y1604838D01*
G02X111292Y1604636I-202J0D01*
G01X108472D01*
G02X108270Y1604838I0J202D01*
G01Y1605458D01*
G03X108220Y1605590I-200J0D01*
G02Y1608506I1661J1458D01*
G03X108270Y1608638I-150J132D01*
G01Y1610576D01*
G03X108220Y1610708I-200J0D01*
G02Y1613624I1661J1458D01*
G03X108270Y1613756I-150J132D01*
G01Y1614376D01*
G02X108472Y1614578I202J0D01*
G37*
G36*
G01X143118D02*
X145938D01*
G02X146140Y1614376I0J-202D01*
G01Y1613756D01*
G03X146190Y1613624I200J0D01*
G02Y1610708I-1661J-1458D01*
G03X146140Y1610576I150J-132D01*
G01Y1608638D01*
G03X146190Y1608506I200J0D01*
G02Y1605590I-1661J-1458D01*
G03X146140Y1605458I150J-132D01*
G01Y1604838D01*
G02X145938Y1604636I-202J0D01*
G01X143118D01*
G02X142916Y1604838I0J202D01*
G01Y1605458D01*
G03X142866Y1605590I-200J0D01*
G02Y1608506I1661J1458D01*
G03X142916Y1608638I-150J132D01*
G01Y1610576D01*
G03X142866Y1610708I-200J0D01*
G02Y1613624I1661J1458D01*
G03X142916Y1613756I-150J132D01*
G01Y1614376D01*
G02X143118Y1614578I202J0D01*
G37*
G36*
G01X160440D02*
X163260D01*
G02X163462Y1614376I0J-202D01*
G01Y1613756D01*
G03X163512Y1613624I200J0D01*
G02Y1610708I-1661J-1458D01*
G03X163462Y1610576I150J-132D01*
G01Y1608638D01*
G03X163512Y1608506I200J0D01*
G02Y1605590I-1661J-1458D01*
G03X163462Y1605458I150J-132D01*
G01Y1604838D01*
G02X163260Y1604636I-202J0D01*
G01X160440D01*
G02X160238Y1604838I0J202D01*
G01Y1605458D01*
G03X160188Y1605590I-200J0D01*
G02Y1608506I1661J1458D01*
G03X160238Y1608638I-150J132D01*
G01Y1610576D01*
G03X160188Y1610708I-200J0D01*
G02Y1613624I1661J1458D01*
G03X160238Y1613756I-150J132D01*
G01Y1614376D01*
G02X160440Y1614578I202J0D01*
G37*
G36*
G01X281700D02*
X284520D01*
G02X284722Y1614376I0J-202D01*
G01Y1613756D01*
G03X284772Y1613624I200J0D01*
G02Y1610708I-1661J-1458D01*
G03X284722Y1610576I150J-132D01*
G01Y1608638D01*
G03X284772Y1608506I200J0D01*
G02Y1605590I-1661J-1458D01*
G03X284722Y1605458I150J-132D01*
G01Y1604838D01*
G02X284520Y1604636I-202J0D01*
G01X281700D01*
G02X281498Y1604838I0J202D01*
G01Y1605458D01*
G03X281448Y1605590I-200J0D01*
G02Y1608506I1661J1458D01*
G03X281498Y1608638I-150J132D01*
G01Y1610576D01*
G03X281448Y1610708I-200J0D01*
G02Y1613624I1661J1458D01*
G03X281498Y1613756I-150J132D01*
G01Y1614376D01*
G02X281700Y1614578I202J0D01*
G37*
G36*
G01X316346D02*
X319166D01*
G02X319368Y1614376I0J-202D01*
G01Y1613756D01*
G03X319418Y1613624I200J0D01*
G02Y1610708I-1661J-1458D01*
G03X319368Y1610576I150J-132D01*
G01Y1608638D01*
G03X319418Y1608506I200J0D01*
G02Y1605590I-1661J-1458D01*
G03X319368Y1605458I150J-132D01*
G01Y1604838D01*
G02X319166Y1604636I-202J0D01*
G01X316346D01*
G02X316144Y1604838I0J202D01*
G01Y1605458D01*
G03X316094Y1605590I-200J0D01*
G02Y1608506I1661J1458D01*
G03X316144Y1608638I-150J132D01*
G01Y1610576D01*
G03X316094Y1610708I-200J0D01*
G02Y1613624I1661J1458D01*
G03X316144Y1613756I-150J132D01*
G01Y1614376D01*
G02X316346Y1614578I202J0D01*
G37*
G36*
G01X333668D02*
X336488D01*
G02X336690Y1614376I0J-202D01*
G01Y1613756D01*
G03X336740Y1613624I200J0D01*
G02Y1610708I-1661J-1458D01*
G03X336690Y1610576I150J-132D01*
G01Y1608638D01*
G03X336740Y1608506I200J0D01*
G02Y1605590I-1661J-1458D01*
G03X336690Y1605458I150J-132D01*
G01Y1604838D01*
G02X336488Y1604636I-202J0D01*
G01X333668D01*
G02X333466Y1604838I0J202D01*
G01Y1605458D01*
G03X333416Y1605590I-200J0D01*
G02Y1608506I1661J1458D01*
G03X333466Y1608638I-150J132D01*
G01Y1610576D01*
G03X333416Y1610708I-200J0D01*
G02Y1613624I1661J1458D01*
G03X333466Y1613756I-150J132D01*
G01Y1614376D01*
G02X333668Y1614578I202J0D01*
G37*
G36*
G01X645480D02*
X648300D01*
G02X648502Y1614376I0J-202D01*
G01Y1613756D01*
G03X648552Y1613624I200J0D01*
G02Y1610708I-1661J-1458D01*
G03X648502Y1610576I150J-132D01*
G01Y1608638D01*
G03X648552Y1608506I200J0D01*
G02Y1605590I-1661J-1458D01*
G03X648502Y1605458I150J-132D01*
G01Y1604838D01*
G02X648300Y1604636I-202J0D01*
G01X645480D01*
G02X645278Y1604838I0J202D01*
G01Y1605458D01*
G03X645228Y1605590I-200J0D01*
G02Y1608506I1661J1458D01*
G03X645278Y1608638I-150J132D01*
G01Y1610576D01*
G03X645228Y1610708I-200J0D01*
G02Y1613624I1661J1458D01*
G03X645278Y1613756I-150J132D01*
G01Y1614376D01*
G02X645480Y1614578I202J0D01*
G37*
G36*
G01X1130440D02*
X1133260D01*
G02X1133462Y1614376I0J-202D01*
G01Y1613756D01*
G03X1133512Y1613624I200J0D01*
G02Y1610708I-1661J-1458D01*
G03X1133462Y1610576I150J-132D01*
G01Y1608638D01*
G03X1133512Y1608506I200J0D01*
G02Y1605590I-1661J-1458D01*
G03X1133462Y1605458I150J-132D01*
G01Y1604838D01*
G02X1133260Y1604636I-202J0D01*
G01X1130440D01*
G02X1130238Y1604838I0J202D01*
G01Y1605458D01*
G03X1130188Y1605590I-200J0D01*
G02Y1608506I1661J1458D01*
G03X1130238Y1608638I-150J132D01*
G01Y1610576D01*
G03X1130188Y1610708I-200J0D01*
G02Y1613624I1661J1458D01*
G03X1130238Y1613756I-150J132D01*
G01Y1614376D01*
G02X1130440Y1614578I202J0D01*
G37*
G36*
G01X1165086D02*
X1167906D01*
G02X1168108Y1614376I0J-202D01*
G01Y1613756D01*
G03X1168158Y1613624I200J0D01*
G02Y1610708I-1661J-1458D01*
G03X1168108Y1610576I150J-132D01*
G01Y1608638D01*
G03X1168158Y1608506I200J0D01*
G02Y1605590I-1661J-1458D01*
G03X1168108Y1605458I150J-132D01*
G01Y1604838D01*
G02X1167906Y1604636I-202J0D01*
G01X1165086D01*
G02X1164884Y1604838I0J202D01*
G01Y1605458D01*
G03X1164834Y1605590I-200J0D01*
G02Y1608506I1661J1458D01*
G03X1164884Y1608638I-150J132D01*
G01Y1610576D01*
G03X1164834Y1610708I-200J0D01*
G02Y1613624I1661J1458D01*
G03X1164884Y1613756I-150J132D01*
G01Y1614376D01*
G02X1165086Y1614578I202J0D01*
G37*
G36*
G01X1182408D02*
X1185228D01*
G02X1185430Y1614376I0J-202D01*
G01Y1613756D01*
G03X1185480Y1613624I200J0D01*
G02Y1610708I-1661J-1458D01*
G03X1185430Y1610576I150J-132D01*
G01Y1608638D01*
G03X1185480Y1608506I200J0D01*
G02Y1605590I-1661J-1458D01*
G03X1185430Y1605458I150J-132D01*
G01Y1604838D01*
G02X1185228Y1604636I-202J0D01*
G01X1182408D01*
G02X1182206Y1604838I0J202D01*
G01Y1605458D01*
G03X1182156Y1605590I-200J0D01*
G02Y1608506I1661J1458D01*
G03X1182206Y1608638I-150J132D01*
G01Y1610576D01*
G03X1182156Y1610708I-200J0D01*
G02Y1613624I1661J1458D01*
G03X1182206Y1613756I-150J132D01*
G01Y1614376D01*
G02X1182408Y1614578I202J0D01*
G37*
G36*
G01X1320992D02*
X1323812D01*
G02X1324014Y1614376I0J-202D01*
G01Y1613756D01*
G03X1324064Y1613624I200J0D01*
G02Y1610708I-1661J-1458D01*
G03X1324014Y1610576I150J-132D01*
G01Y1608638D01*
G03X1324064Y1608506I200J0D01*
G02Y1605590I-1661J-1458D01*
G03X1324014Y1605458I150J-132D01*
G01Y1604838D01*
G02X1323812Y1604636I-202J0D01*
G01X1320992D01*
G02X1320790Y1604838I0J202D01*
G01Y1605458D01*
G03X1320740Y1605590I-200J0D01*
G02Y1608506I1661J1458D01*
G03X1320790Y1608638I-150J132D01*
G01Y1610576D01*
G03X1320740Y1610708I-200J0D01*
G02Y1613624I1661J1458D01*
G03X1320790Y1613756I-150J132D01*
G01Y1614376D01*
G02X1320992Y1614578I202J0D01*
G37*
G36*
G01X1667448D02*
X1670268D01*
G02X1670470Y1614376I0J-202D01*
G01Y1613756D01*
G03X1670520Y1613624I200J0D01*
G02Y1610708I-1661J-1458D01*
G03X1670470Y1610576I150J-132D01*
G01Y1608638D01*
G03X1670520Y1608506I200J0D01*
G02Y1605590I-1661J-1458D01*
G03X1670470Y1605458I150J-132D01*
G01Y1604838D01*
G02X1670268Y1604636I-202J0D01*
G01X1667448D01*
G02X1667246Y1604838I0J202D01*
G01Y1605458D01*
G03X1667196Y1605590I-200J0D01*
G02Y1608506I1661J1458D01*
G03X1667246Y1608638I-150J132D01*
G01Y1610576D01*
G03X1667196Y1610708I-200J0D01*
G02Y1613624I1661J1458D01*
G03X1667246Y1613756I-150J132D01*
G01Y1614376D01*
G02X1667448Y1614578I202J0D01*
G37*
G36*
G01X125795D02*
X128615D01*
G02X128818Y1614376I1J-202D01*
G01Y1613754D01*
G03X128868Y1613622I200J0D01*
G02Y1610710I-1664J-1456D01*
G03X128818Y1610578I150J-132D01*
G01Y1608636D01*
G03X128868Y1608504I200J0D01*
G02Y1605592I-1664J-1456D01*
G03X128818Y1605460I150J-132D01*
G01Y1604838D01*
G02X128615Y1604636I-203J1D01*
G01X125795D01*
G02X125592Y1604838I-1J202D01*
G01Y1605460D01*
G03X125542Y1605592I-200J0D01*
G02Y1608504I1664J1456D01*
G03X125592Y1608636I-150J132D01*
G01Y1610578D01*
G03X125542Y1610710I-200J0D01*
G02Y1613622I1664J1456D01*
G03X125592Y1613754I-150J132D01*
G01Y1614376D01*
G02X125795Y1614578I203J-1D01*
G37*
G36*
G01X299023D02*
X301843D01*
G02X302046Y1614376I1J-202D01*
G01Y1613754D01*
G03X302096Y1613622I200J0D01*
G02Y1610710I-1664J-1456D01*
G03X302046Y1610578I150J-132D01*
G01Y1608636D01*
G03X302096Y1608504I200J0D01*
G02Y1605592I-1664J-1456D01*
G03X302046Y1605460I150J-132D01*
G01Y1604838D01*
G02X301843Y1604636I-203J1D01*
G01X299023D01*
G02X298820Y1604838I-1J202D01*
G01Y1605460D01*
G03X298770Y1605592I-200J0D01*
G02Y1608504I1664J1456D01*
G03X298820Y1608636I-150J132D01*
G01Y1610578D01*
G03X298770Y1610710I-200J0D01*
G02Y1613622I1664J1456D01*
G03X298820Y1613754I-150J132D01*
G01Y1614376D01*
G02X299023Y1614578I203J-1D01*
G37*
G36*
G01X628157D02*
X630977D01*
G02X631180Y1614376I1J-202D01*
G01Y1613754D01*
G03X631230Y1613622I200J0D01*
G02Y1610710I-1664J-1456D01*
G03X631180Y1610578I150J-132D01*
G01Y1608636D01*
G03X631230Y1608504I200J0D01*
G02Y1605592I-1664J-1456D01*
G03X631180Y1605460I150J-132D01*
G01Y1604838D01*
G02X630977Y1604636I-203J1D01*
G01X628157D01*
G02X627954Y1604838I-1J202D01*
G01Y1605460D01*
G03X627904Y1605592I-200J0D01*
G02Y1608504I1664J1456D01*
G03X627954Y1608636I-150J132D01*
G01Y1610578D01*
G03X627904Y1610710I-200J0D01*
G02Y1613622I1664J1456D01*
G03X627954Y1613754I-150J132D01*
G01Y1614376D01*
G02X628157Y1614578I203J-1D01*
G37*
G36*
G01X662803D02*
X665623D01*
G02X665826Y1614376I1J-202D01*
G01Y1613754D01*
G03X665876Y1613622I200J0D01*
G02Y1610710I-1664J-1456D01*
G03X665826Y1610578I150J-132D01*
G01Y1608636D01*
G03X665876Y1608504I200J0D01*
G02Y1605592I-1664J-1456D01*
G03X665826Y1605460I150J-132D01*
G01Y1604838D01*
G02X665623Y1604636I-203J1D01*
G01X662803D01*
G02X662600Y1604838I-1J202D01*
G01Y1605460D01*
G03X662550Y1605592I-200J0D01*
G02Y1608504I1664J1456D01*
G03X662600Y1608636I-150J132D01*
G01Y1610578D01*
G03X662550Y1610710I-200J0D01*
G02Y1613622I1664J1456D01*
G03X662600Y1613754I-150J132D01*
G01Y1614376D01*
G02X662803Y1614578I203J-1D01*
G37*
G36*
G01X680125D02*
X682945D01*
G02X683148Y1614376I1J-202D01*
G01Y1613754D01*
G03X683198Y1613622I200J0D01*
G02Y1610710I-1664J-1456D01*
G03X683148Y1610578I150J-132D01*
G01Y1608636D01*
G03X683198Y1608504I200J0D01*
G02Y1605592I-1664J-1456D01*
G03X683148Y1605460I150J-132D01*
G01Y1604838D01*
G02X682945Y1604636I-203J1D01*
G01X680125D01*
G02X679922Y1604838I-1J202D01*
G01Y1605460D01*
G03X679872Y1605592I-200J0D01*
G02Y1608504I1664J1456D01*
G03X679922Y1608636I-150J132D01*
G01Y1610578D01*
G03X679872Y1610710I-200J0D01*
G02Y1613622I1664J1456D01*
G03X679922Y1613754I-150J132D01*
G01Y1614376D01*
G02X680125Y1614578I203J-1D01*
G37*
G36*
G01X1147763D02*
X1150583D01*
G02X1150786Y1614376I1J-202D01*
G01Y1613754D01*
G03X1150836Y1613622I200J0D01*
G02Y1610710I-1664J-1456D01*
G03X1150786Y1610578I150J-132D01*
G01Y1608636D01*
G03X1150836Y1608504I200J0D01*
G02Y1605592I-1664J-1456D01*
G03X1150786Y1605460I150J-132D01*
G01Y1604838D01*
G02X1150583Y1604636I-203J1D01*
G01X1147763D01*
G02X1147560Y1604838I-1J202D01*
G01Y1605460D01*
G03X1147510Y1605592I-200J0D01*
G02Y1608504I1664J1456D01*
G03X1147560Y1608636I-150J132D01*
G01Y1610578D01*
G03X1147510Y1610710I-200J0D01*
G02Y1613622I1664J1456D01*
G03X1147560Y1613754I-150J132D01*
G01Y1614376D01*
G02X1147763Y1614578I203J-1D01*
G37*
G36*
G01X1303669D02*
X1306489D01*
G02X1306692Y1614376I1J-202D01*
G01Y1613754D01*
G03X1306742Y1613622I200J0D01*
G02Y1610710I-1664J-1456D01*
G03X1306692Y1610578I150J-132D01*
G01Y1608636D01*
G03X1306742Y1608504I200J0D01*
G02Y1605592I-1664J-1456D01*
G03X1306692Y1605460I150J-132D01*
G01Y1604838D01*
G02X1306489Y1604636I-203J1D01*
G01X1303669D01*
G02X1303466Y1604838I-1J202D01*
G01Y1605460D01*
G03X1303416Y1605592I-200J0D01*
G02Y1608504I1664J1456D01*
G03X1303466Y1608636I-150J132D01*
G01Y1610578D01*
G03X1303416Y1610710I-200J0D01*
G02Y1613622I1664J1456D01*
G03X1303466Y1613754I-150J132D01*
G01Y1614376D01*
G02X1303669Y1614578I203J-1D01*
G37*
G36*
G01X1338315D02*
X1341135D01*
G02X1341338Y1614376I1J-202D01*
G01Y1613754D01*
G03X1341388Y1613622I200J0D01*
G02Y1610710I-1664J-1456D01*
G03X1341338Y1610578I150J-132D01*
G01Y1608636D01*
G03X1341388Y1608504I200J0D01*
G02Y1605592I-1664J-1456D01*
G03X1341338Y1605460I150J-132D01*
G01Y1604838D01*
G02X1341135Y1604636I-203J1D01*
G01X1338315D01*
G02X1338112Y1604838I-1J202D01*
G01Y1605460D01*
G03X1338062Y1605592I-200J0D01*
G02Y1608504I1664J1456D01*
G03X1338112Y1608636I-150J132D01*
G01Y1610578D01*
G03X1338062Y1610710I-200J0D01*
G02Y1613622I1664J1456D01*
G03X1338112Y1613754I-150J132D01*
G01Y1614376D01*
G02X1338315Y1614578I203J-1D01*
G37*
G36*
G01X1355637D02*
X1358457D01*
G02X1358660Y1614376I1J-202D01*
G01Y1613754D01*
G03X1358710Y1613622I200J0D01*
G02Y1610710I-1664J-1456D01*
G03X1358660Y1610578I150J-132D01*
G01Y1608636D01*
G03X1358710Y1608504I200J0D01*
G02Y1605592I-1664J-1456D01*
G03X1358660Y1605460I150J-132D01*
G01Y1604838D01*
G02X1358457Y1604636I-203J1D01*
G01X1355637D01*
G02X1355434Y1604838I-1J202D01*
G01Y1605460D01*
G03X1355384Y1605592I-200J0D01*
G02Y1608504I1664J1456D01*
G03X1355434Y1608636I-150J132D01*
G01Y1610578D01*
G03X1355384Y1610710I-200J0D01*
G02Y1613622I1664J1456D01*
G03X1355434Y1613754I-150J132D01*
G01Y1614376D01*
G02X1355637Y1614578I203J-1D01*
G37*
G36*
G01X1476897D02*
X1479717D01*
G02X1479920Y1614376I1J-202D01*
G01Y1613754D01*
G03X1479970Y1613622I200J0D01*
G02Y1610710I-1664J-1456D01*
G03X1479920Y1610578I150J-132D01*
G01Y1608636D01*
G03X1479970Y1608504I200J0D01*
G02Y1605592I-1664J-1456D01*
G03X1479920Y1605460I150J-132D01*
G01Y1604838D01*
G02X1479717Y1604636I-203J1D01*
G01X1476897D01*
G02X1476694Y1604838I-1J202D01*
G01Y1605460D01*
G03X1476644Y1605592I-200J0D01*
G02Y1608504I1664J1456D01*
G03X1476694Y1608636I-150J132D01*
G01Y1610578D01*
G03X1476644Y1610710I-200J0D01*
G02Y1613622I1664J1456D01*
G03X1476694Y1613754I-150J132D01*
G01Y1614376D01*
G02X1476897Y1614578I203J-1D01*
G37*
G36*
G01X1650125D02*
X1652945D01*
G02X1653148Y1614376I1J-202D01*
G01Y1613754D01*
G03X1653198Y1613622I200J0D01*
G02Y1610710I-1664J-1456D01*
G03X1653148Y1610578I150J-132D01*
G01Y1608636D01*
G03X1653198Y1608504I200J0D01*
G02Y1605592I-1664J-1456D01*
G03X1653148Y1605460I150J-132D01*
G01Y1604838D01*
G02X1652945Y1604636I-203J1D01*
G01X1650125D01*
G02X1649922Y1604838I-1J202D01*
G01Y1605460D01*
G03X1649872Y1605592I-200J0D01*
G02Y1608504I1664J1456D01*
G03X1649922Y1608636I-150J132D01*
G01Y1610578D01*
G03X1649872Y1610710I-200J0D01*
G02Y1613622I1664J1456D01*
G03X1649922Y1613754I-150J132D01*
G01Y1614376D01*
G02X1650125Y1614578I203J-1D01*
G37*
G36*
G01X1684771D02*
X1687591D01*
G02X1687794Y1614376I1J-202D01*
G01Y1613754D01*
G03X1687844Y1613622I200J0D01*
G02Y1610710I-1664J-1456D01*
G03X1687794Y1610578I150J-132D01*
G01Y1608636D01*
G03X1687844Y1608504I200J0D01*
G02Y1605592I-1664J-1456D01*
G03X1687794Y1605460I150J-132D01*
G01Y1604838D01*
G02X1687591Y1604636I-203J1D01*
G01X1684771D01*
G02X1684568Y1604838I-1J202D01*
G01Y1605460D01*
G03X1684518Y1605592I-200J0D01*
G02Y1608504I1664J1456D01*
G03X1684568Y1608636I-150J132D01*
G01Y1610578D01*
G03X1684518Y1610710I-200J0D01*
G02Y1613622I1664J1456D01*
G03X1684568Y1613754I-150J132D01*
G01Y1614376D01*
G02X1684771Y1614578I203J-1D01*
G37*
G36*
G01X1702093D02*
X1704913D01*
G02X1705116Y1614376I1J-202D01*
G01Y1613754D01*
G03X1705166Y1613622I200J0D01*
G02Y1610710I-1664J-1456D01*
G03X1705116Y1610578I150J-132D01*
G01Y1608636D01*
G03X1705166Y1608504I200J0D01*
G02Y1605592I-1664J-1456D01*
G03X1705116Y1605460I150J-132D01*
G01Y1604838D01*
G02X1704913Y1604636I-203J1D01*
G01X1702093D01*
G02X1701890Y1604838I-1J202D01*
G01Y1605460D01*
G03X1701840Y1605592I-200J0D01*
G02Y1608504I1664J1456D01*
G03X1701890Y1608636I-150J132D01*
G01Y1610578D01*
G03X1701840Y1610710I-200J0D01*
G02Y1613622I1664J1456D01*
G03X1701890Y1613754I-150J132D01*
G01Y1614376D01*
G02X1702093Y1614578I203J-1D01*
G37*
G36*
G01X134456Y1618908D02*
X137276D01*
G02X137478Y1618706I0J-202D01*
G01Y1618086D01*
G03X137528Y1617954I200J0D01*
G02Y1615038I-1661J-1458D01*
G03X137478Y1614906I150J-132D01*
G01Y1612968D01*
G03X137528Y1612836I200J0D01*
G02Y1609920I-1661J-1458D01*
G03X137478Y1609788I150J-132D01*
G01Y1609168D01*
G02X137276Y1608966I-202J0D01*
G01X134456D01*
G02X134254Y1609168I0J202D01*
G01Y1609788D01*
G03X134204Y1609920I-200J0D01*
G02Y1612836I1661J1458D01*
G03X134254Y1612968I-150J132D01*
G01Y1614906D01*
G03X134204Y1615038I-200J0D01*
G02Y1617954I1661J1458D01*
G03X134254Y1618086I-150J132D01*
G01Y1618706D01*
G02X134456Y1618908I202J0D01*
G37*
G36*
G01X169102D02*
X171922D01*
G02X172124Y1618706I0J-202D01*
G01Y1618086D01*
G03X172174Y1617954I200J0D01*
G02Y1615038I-1661J-1458D01*
G03X172124Y1614906I150J-132D01*
G01Y1612968D01*
G03X172174Y1612836I200J0D01*
G02Y1609920I-1661J-1458D01*
G03X172124Y1609788I150J-132D01*
G01Y1609168D01*
G02X171922Y1608966I-202J0D01*
G01X169102D01*
G02X168900Y1609168I0J202D01*
G01Y1609788D01*
G03X168850Y1609920I-200J0D01*
G02Y1612836I1661J1458D01*
G03X168900Y1612968I-150J132D01*
G01Y1614906D01*
G03X168850Y1615038I-200J0D01*
G02Y1617954I1661J1458D01*
G03X168900Y1618086I-150J132D01*
G01Y1618706D01*
G02X169102Y1618908I202J0D01*
G37*
G36*
G01X307684D02*
X310504D01*
G02X310706Y1618706I0J-202D01*
G01Y1618086D01*
G03X310756Y1617954I200J0D01*
G02Y1615038I-1661J-1458D01*
G03X310706Y1614906I150J-132D01*
G01Y1612968D01*
G03X310756Y1612836I200J0D01*
G02Y1609920I-1661J-1458D01*
G03X310706Y1609788I150J-132D01*
G01Y1609168D01*
G02X310504Y1608966I-202J0D01*
G01X307684D01*
G02X307482Y1609168I0J202D01*
G01Y1609788D01*
G03X307432Y1609920I-200J0D01*
G02Y1612836I1661J1458D01*
G03X307482Y1612968I-150J132D01*
G01Y1614906D01*
G03X307432Y1615038I-200J0D01*
G02Y1617954I1661J1458D01*
G03X307482Y1618086I-150J132D01*
G01Y1618706D01*
G02X307684Y1618908I202J0D01*
G37*
G36*
G01X342330D02*
X345150D01*
G02X345352Y1618706I0J-202D01*
G01Y1618086D01*
G03X345402Y1617954I200J0D01*
G02Y1615038I-1661J-1458D01*
G03X345352Y1614906I150J-132D01*
G01Y1612968D01*
G03X345402Y1612836I200J0D01*
G02Y1609920I-1661J-1458D01*
G03X345352Y1609788I150J-132D01*
G01Y1609168D01*
G02X345150Y1608966I-202J0D01*
G01X342330D01*
G02X342128Y1609168I0J202D01*
G01Y1609788D01*
G03X342078Y1609920I-200J0D01*
G02Y1612836I1661J1458D01*
G03X342128Y1612968I-150J132D01*
G01Y1614906D01*
G03X342078Y1615038I-200J0D01*
G02Y1617954I1661J1458D01*
G03X342128Y1618086I-150J132D01*
G01Y1618706D01*
G02X342330Y1618908I202J0D01*
G37*
G36*
G01X636818D02*
X639638D01*
G02X639840Y1618706I0J-202D01*
G01Y1618086D01*
G03X639890Y1617954I200J0D01*
G02Y1615038I-1661J-1458D01*
G03X639840Y1614906I150J-132D01*
G01Y1612968D01*
G03X639890Y1612836I200J0D01*
G02Y1609920I-1661J-1458D01*
G03X639840Y1609788I150J-132D01*
G01Y1609168D01*
G02X639638Y1608966I-202J0D01*
G01X636818D01*
G02X636616Y1609168I0J202D01*
G01Y1609788D01*
G03X636566Y1609920I-200J0D01*
G02Y1612836I1661J1458D01*
G03X636616Y1612968I-150J132D01*
G01Y1614906D01*
G03X636566Y1615038I-200J0D01*
G02Y1617954I1661J1458D01*
G03X636616Y1618086I-150J132D01*
G01Y1618706D01*
G02X636818Y1618908I202J0D01*
G37*
G36*
G01X671464D02*
X674284D01*
G02X674486Y1618706I0J-202D01*
G01Y1618086D01*
G03X674536Y1617954I200J0D01*
G02Y1615038I-1661J-1458D01*
G03X674486Y1614906I150J-132D01*
G01Y1612968D01*
G03X674536Y1612836I200J0D01*
G02Y1609920I-1661J-1458D01*
G03X674486Y1609788I150J-132D01*
G01Y1609168D01*
G02X674284Y1608966I-202J0D01*
G01X671464D01*
G02X671262Y1609168I0J202D01*
G01Y1609788D01*
G03X671212Y1609920I-200J0D01*
G02Y1612836I1661J1458D01*
G03X671262Y1612968I-150J132D01*
G01Y1614906D01*
G03X671212Y1615038I-200J0D01*
G02Y1617954I1661J1458D01*
G03X671262Y1618086I-150J132D01*
G01Y1618706D01*
G02X671464Y1618908I202J0D01*
G37*
G36*
G01X1156424D02*
X1159244D01*
G02X1159446Y1618706I0J-202D01*
G01Y1618086D01*
G03X1159496Y1617954I200J0D01*
G02Y1615038I-1661J-1458D01*
G03X1159446Y1614906I150J-132D01*
G01Y1612968D01*
G03X1159496Y1612836I200J0D01*
G02Y1609920I-1661J-1458D01*
G03X1159446Y1609788I150J-132D01*
G01Y1609168D01*
G02X1159244Y1608966I-202J0D01*
G01X1156424D01*
G02X1156222Y1609168I0J202D01*
G01Y1609788D01*
G03X1156172Y1609920I-200J0D01*
G02Y1612836I1661J1458D01*
G03X1156222Y1612968I-150J132D01*
G01Y1614906D01*
G03X1156172Y1615038I-200J0D01*
G02Y1617954I1661J1458D01*
G03X1156222Y1618086I-150J132D01*
G01Y1618706D01*
G02X1156424Y1618908I202J0D01*
G37*
G36*
G01X1191070D02*
X1193890D01*
G02X1194092Y1618706I0J-202D01*
G01Y1618086D01*
G03X1194142Y1617954I200J0D01*
G02Y1615038I-1661J-1458D01*
G03X1194092Y1614906I150J-132D01*
G01Y1612968D01*
G03X1194142Y1612836I200J0D01*
G02Y1609920I-1661J-1458D01*
G03X1194092Y1609788I150J-132D01*
G01Y1609168D01*
G02X1193890Y1608966I-202J0D01*
G01X1191070D01*
G02X1190868Y1609168I0J202D01*
G01Y1609788D01*
G03X1190818Y1609920I-200J0D01*
G02Y1612836I1661J1458D01*
G03X1190868Y1612968I-150J132D01*
G01Y1614906D01*
G03X1190818Y1615038I-200J0D01*
G02Y1617954I1661J1458D01*
G03X1190868Y1618086I-150J132D01*
G01Y1618706D01*
G02X1191070Y1618908I202J0D01*
G37*
G36*
G01X1312330D02*
X1315150D01*
G02X1315352Y1618706I0J-202D01*
G01Y1618086D01*
G03X1315402Y1617954I200J0D01*
G02Y1615038I-1661J-1458D01*
G03X1315352Y1614906I150J-132D01*
G01Y1612968D01*
G03X1315402Y1612836I200J0D01*
G02Y1609920I-1661J-1458D01*
G03X1315352Y1609788I150J-132D01*
G01Y1609168D01*
G02X1315150Y1608966I-202J0D01*
G01X1312330D01*
G02X1312128Y1609168I0J202D01*
G01Y1609788D01*
G03X1312078Y1609920I-200J0D01*
G02Y1612836I1661J1458D01*
G03X1312128Y1612968I-150J132D01*
G01Y1614906D01*
G03X1312078Y1615038I-200J0D01*
G02Y1617954I1661J1458D01*
G03X1312128Y1618086I-150J132D01*
G01Y1618706D01*
G02X1312330Y1618908I202J0D01*
G37*
G36*
G01X1346976D02*
X1349796D01*
G02X1349998Y1618706I0J-202D01*
G01Y1618086D01*
G03X1350048Y1617954I200J0D01*
G02Y1615038I-1661J-1458D01*
G03X1349998Y1614906I150J-132D01*
G01Y1612968D01*
G03X1350048Y1612836I200J0D01*
G02Y1609920I-1661J-1458D01*
G03X1349998Y1609788I150J-132D01*
G01Y1609168D01*
G02X1349796Y1608966I-202J0D01*
G01X1346976D01*
G02X1346774Y1609168I0J202D01*
G01Y1609788D01*
G03X1346724Y1609920I-200J0D01*
G02Y1612836I1661J1458D01*
G03X1346774Y1612968I-150J132D01*
G01Y1614906D01*
G03X1346724Y1615038I-200J0D01*
G02Y1617954I1661J1458D01*
G03X1346774Y1618086I-150J132D01*
G01Y1618706D01*
G02X1346976Y1618908I202J0D01*
G37*
G36*
G01X1658786D02*
X1661606D01*
G02X1661808Y1618706I0J-202D01*
G01Y1618086D01*
G03X1661858Y1617954I200J0D01*
G02Y1615038I-1661J-1458D01*
G03X1661808Y1614906I150J-132D01*
G01Y1612968D01*
G03X1661858Y1612836I200J0D01*
G02Y1609920I-1661J-1458D01*
G03X1661808Y1609788I150J-132D01*
G01Y1609168D01*
G02X1661606Y1608966I-202J0D01*
G01X1658786D01*
G02X1658584Y1609168I0J202D01*
G01Y1609788D01*
G03X1658534Y1609920I-200J0D01*
G02Y1612836I1661J1458D01*
G03X1658584Y1612968I-150J132D01*
G01Y1614906D01*
G03X1658534Y1615038I-200J0D01*
G02Y1617954I1661J1458D01*
G03X1658584Y1618086I-150J132D01*
G01Y1618706D01*
G02X1658786Y1618908I202J0D01*
G37*
G36*
G01X1693432D02*
X1696252D01*
G02X1696454Y1618706I0J-202D01*
G01Y1618086D01*
G03X1696504Y1617954I200J0D01*
G02Y1615038I-1661J-1458D01*
G03X1696454Y1614906I150J-132D01*
G01Y1612968D01*
G03X1696504Y1612836I200J0D01*
G02Y1609920I-1661J-1458D01*
G03X1696454Y1609788I150J-132D01*
G01Y1609168D01*
G02X1696252Y1608966I-202J0D01*
G01X1693432D01*
G02X1693230Y1609168I0J202D01*
G01Y1609788D01*
G03X1693180Y1609920I-200J0D01*
G02Y1612836I1661J1458D01*
G03X1693230Y1612968I-150J132D01*
G01Y1614906D01*
G03X1693180Y1615038I-200J0D01*
G02Y1617954I1661J1458D01*
G03X1693230Y1618086I-150J132D01*
G01Y1618706D01*
G02X1693432Y1618908I202J0D01*
G37*
G36*
G01X117133D02*
X119953D01*
G02X120156Y1618706I1J-202D01*
G01Y1618084D01*
G03X120206Y1617952I200J0D01*
G02Y1615040I-1664J-1456D01*
G03X120156Y1614908I150J-132D01*
G01Y1612966D01*
G03X120206Y1612834I200J0D01*
G02Y1609922I-1664J-1456D01*
G03X120156Y1609790I150J-132D01*
G01Y1609168D01*
G02X119953Y1608966I-203J1D01*
G01X117133D01*
G02X116930Y1609168I-1J202D01*
G01Y1609790D01*
G03X116880Y1609922I-200J0D01*
G02Y1612834I1664J1456D01*
G03X116930Y1612966I-150J132D01*
G01Y1614908D01*
G03X116880Y1615040I-200J0D01*
G02Y1617952I1664J1456D01*
G03X116930Y1618084I-150J132D01*
G01Y1618706D01*
G02X117133Y1618908I203J-1D01*
G37*
G36*
G01X151779D02*
X154599D01*
G02X154802Y1618706I1J-202D01*
G01Y1618084D01*
G03X154852Y1617952I200J0D01*
G02Y1615040I-1664J-1456D01*
G03X154802Y1614908I150J-132D01*
G01Y1612966D01*
G03X154852Y1612834I200J0D01*
G02Y1609922I-1664J-1456D01*
G03X154802Y1609790I150J-132D01*
G01Y1609168D01*
G02X154599Y1608966I-203J1D01*
G01X151779D01*
G02X151576Y1609168I-1J202D01*
G01Y1609790D01*
G03X151526Y1609922I-200J0D01*
G02Y1612834I1664J1456D01*
G03X151576Y1612966I-150J132D01*
G01Y1614908D01*
G03X151526Y1615040I-200J0D01*
G02Y1617952I1664J1456D01*
G03X151576Y1618084I-150J132D01*
G01Y1618706D01*
G02X151779Y1618908I203J-1D01*
G37*
G36*
G01X186425D02*
X189245D01*
G02X189448Y1618706I1J-202D01*
G01Y1618084D01*
G03X189498Y1617952I200J0D01*
G02Y1615040I-1664J-1456D01*
G03X189448Y1614908I150J-132D01*
G01Y1612966D01*
G03X189498Y1612834I200J0D01*
G02Y1609922I-1664J-1456D01*
G03X189448Y1609790I150J-132D01*
G01Y1609168D01*
G02X189245Y1608966I-203J1D01*
G01X186425D01*
G02X186222Y1609168I-1J202D01*
G01Y1609790D01*
G03X186172Y1609922I-200J0D01*
G02Y1612834I1664J1456D01*
G03X186222Y1612966I-150J132D01*
G01Y1614908D01*
G03X186172Y1615040I-200J0D01*
G02Y1617952I1664J1456D01*
G03X186222Y1618084I-150J132D01*
G01Y1618706D01*
G02X186425Y1618908I203J-1D01*
G37*
G36*
G01X290361D02*
X293181D01*
G02X293384Y1618706I1J-202D01*
G01Y1618084D01*
G03X293434Y1617952I200J0D01*
G02Y1615040I-1664J-1456D01*
G03X293384Y1614908I150J-132D01*
G01Y1612966D01*
G03X293434Y1612834I200J0D01*
G02Y1609922I-1664J-1456D01*
G03X293384Y1609790I150J-132D01*
G01Y1609168D01*
G02X293181Y1608966I-203J1D01*
G01X290361D01*
G02X290158Y1609168I-1J202D01*
G01Y1609790D01*
G03X290108Y1609922I-200J0D01*
G02Y1612834I1664J1456D01*
G03X290158Y1612966I-150J132D01*
G01Y1614908D01*
G03X290108Y1615040I-200J0D01*
G02Y1617952I1664J1456D01*
G03X290158Y1618084I-150J132D01*
G01Y1618706D01*
G02X290361Y1618908I203J-1D01*
G37*
G36*
G01X325007D02*
X327827D01*
G02X328030Y1618706I1J-202D01*
G01Y1618084D01*
G03X328080Y1617952I200J0D01*
G02Y1615040I-1664J-1456D01*
G03X328030Y1614908I150J-132D01*
G01Y1612966D01*
G03X328080Y1612834I200J0D01*
G02Y1609922I-1664J-1456D01*
G03X328030Y1609790I150J-132D01*
G01Y1609168D01*
G02X327827Y1608966I-203J1D01*
G01X325007D01*
G02X324804Y1609168I-1J202D01*
G01Y1609790D01*
G03X324754Y1609922I-200J0D01*
G02Y1612834I1664J1456D01*
G03X324804Y1612966I-150J132D01*
G01Y1614908D01*
G03X324754Y1615040I-200J0D01*
G02Y1617952I1664J1456D01*
G03X324804Y1618084I-150J132D01*
G01Y1618706D01*
G02X325007Y1618908I203J-1D01*
G37*
G36*
G01X359653D02*
X362473D01*
G02X362676Y1618706I1J-202D01*
G01Y1618084D01*
G03X362726Y1617952I200J0D01*
G02Y1615040I-1664J-1456D01*
G03X362676Y1614908I150J-132D01*
G01Y1612966D01*
G03X362726Y1612834I200J0D01*
G02Y1609922I-1664J-1456D01*
G03X362676Y1609790I150J-132D01*
G01Y1609168D01*
G02X362473Y1608966I-203J1D01*
G01X359653D01*
G02X359450Y1609168I-1J202D01*
G01Y1609790D01*
G03X359400Y1609922I-200J0D01*
G02Y1612834I1664J1456D01*
G03X359450Y1612966I-150J132D01*
G01Y1614908D01*
G03X359400Y1615040I-200J0D01*
G02Y1617952I1664J1456D01*
G03X359450Y1618084I-150J132D01*
G01Y1618706D01*
G02X359653Y1618908I203J-1D01*
G37*
G36*
G01X515559D02*
X518379D01*
G02X518582Y1618706I1J-202D01*
G01Y1618084D01*
G03X518632Y1617952I200J0D01*
G02Y1615040I-1664J-1456D01*
G03X518582Y1614908I150J-132D01*
G01Y1612966D01*
G03X518632Y1612834I200J0D01*
G02Y1609922I-1664J-1456D01*
G03X518582Y1609790I150J-132D01*
G01Y1609168D01*
G02X518379Y1608966I-203J1D01*
G01X515559D01*
G02X515356Y1609168I-1J202D01*
G01Y1609790D01*
G03X515306Y1609922I-200J0D01*
G02Y1612834I1664J1456D01*
G03X515356Y1612966I-150J132D01*
G01Y1614908D01*
G03X515306Y1615040I-200J0D01*
G02Y1617952I1664J1456D01*
G03X515356Y1618084I-150J132D01*
G01Y1618706D01*
G02X515559Y1618908I203J-1D01*
G37*
G36*
G01X654141D02*
X656961D01*
G02X657164Y1618706I1J-202D01*
G01Y1618084D01*
G03X657214Y1617952I200J0D01*
G02Y1615040I-1664J-1456D01*
G03X657164Y1614908I150J-132D01*
G01Y1612966D01*
G03X657214Y1612834I200J0D01*
G02Y1609922I-1664J-1456D01*
G03X657164Y1609790I150J-132D01*
G01Y1609168D01*
G02X656961Y1608966I-203J1D01*
G01X654141D01*
G02X653938Y1609168I-1J202D01*
G01Y1609790D01*
G03X653888Y1609922I-200J0D01*
G02Y1612834I1664J1456D01*
G03X653938Y1612966I-150J132D01*
G01Y1614908D01*
G03X653888Y1615040I-200J0D01*
G02Y1617952I1664J1456D01*
G03X653938Y1618084I-150J132D01*
G01Y1618706D01*
G02X654141Y1618908I203J-1D01*
G37*
G36*
G01X688787D02*
X691607D01*
G02X691810Y1618706I1J-202D01*
G01Y1618084D01*
G03X691860Y1617952I200J0D01*
G02Y1615040I-1664J-1456D01*
G03X691810Y1614908I150J-132D01*
G01Y1612966D01*
G03X691860Y1612834I200J0D01*
G02Y1609922I-1664J-1456D01*
G03X691810Y1609790I150J-132D01*
G01Y1609168D01*
G02X691607Y1608966I-203J1D01*
G01X688787D01*
G02X688584Y1609168I-1J202D01*
G01Y1609790D01*
G03X688534Y1609922I-200J0D01*
G02Y1612834I1664J1456D01*
G03X688584Y1612966I-150J132D01*
G01Y1614908D01*
G03X688534Y1615040I-200J0D01*
G02Y1617952I1664J1456D01*
G03X688584Y1618084I-150J132D01*
G01Y1618706D01*
G02X688787Y1618908I203J-1D01*
G37*
G36*
G01X1139101D02*
X1141921D01*
G02X1142124Y1618706I1J-202D01*
G01Y1618084D01*
G03X1142174Y1617952I200J0D01*
G02Y1615040I-1664J-1456D01*
G03X1142124Y1614908I150J-132D01*
G01Y1612966D01*
G03X1142174Y1612834I200J0D01*
G02Y1609922I-1664J-1456D01*
G03X1142124Y1609790I150J-132D01*
G01Y1609168D01*
G02X1141921Y1608966I-203J1D01*
G01X1139101D01*
G02X1138898Y1609168I-1J202D01*
G01Y1609790D01*
G03X1138848Y1609922I-200J0D01*
G02Y1612834I1664J1456D01*
G03X1138898Y1612966I-150J132D01*
G01Y1614908D01*
G03X1138848Y1615040I-200J0D01*
G02Y1617952I1664J1456D01*
G03X1138898Y1618084I-150J132D01*
G01Y1618706D01*
G02X1139101Y1618908I203J-1D01*
G37*
G36*
G01X1173747D02*
X1176567D01*
G02X1176770Y1618706I1J-202D01*
G01Y1618084D01*
G03X1176820Y1617952I200J0D01*
G02Y1615040I-1664J-1456D01*
G03X1176770Y1614908I150J-132D01*
G01Y1612966D01*
G03X1176820Y1612834I200J0D01*
G02Y1609922I-1664J-1456D01*
G03X1176770Y1609790I150J-132D01*
G01Y1609168D01*
G02X1176567Y1608966I-203J1D01*
G01X1173747D01*
G02X1173544Y1609168I-1J202D01*
G01Y1609790D01*
G03X1173494Y1609922I-200J0D01*
G02Y1612834I1664J1456D01*
G03X1173544Y1612966I-150J132D01*
G01Y1614908D01*
G03X1173494Y1615040I-200J0D01*
G02Y1617952I1664J1456D01*
G03X1173544Y1618084I-150J132D01*
G01Y1618706D01*
G02X1173747Y1618908I203J-1D01*
G37*
G36*
G01X1329653D02*
X1332473D01*
G02X1332676Y1618706I1J-202D01*
G01Y1618084D01*
G03X1332726Y1617952I200J0D01*
G02Y1615040I-1664J-1456D01*
G03X1332676Y1614908I150J-132D01*
G01Y1612966D01*
G03X1332726Y1612834I200J0D01*
G02Y1609922I-1664J-1456D01*
G03X1332676Y1609790I150J-132D01*
G01Y1609168D01*
G02X1332473Y1608966I-203J1D01*
G01X1329653D01*
G02X1329450Y1609168I-1J202D01*
G01Y1609790D01*
G03X1329400Y1609922I-200J0D01*
G02Y1612834I1664J1456D01*
G03X1329450Y1612966I-150J132D01*
G01Y1614908D01*
G03X1329400Y1615040I-200J0D01*
G02Y1617952I1664J1456D01*
G03X1329450Y1618084I-150J132D01*
G01Y1618706D01*
G02X1329653Y1618908I203J-1D01*
G37*
G36*
G01X1364299D02*
X1367119D01*
G02X1367322Y1618706I1J-202D01*
G01Y1618084D01*
G03X1367372Y1617952I200J0D01*
G02Y1615040I-1664J-1456D01*
G03X1367322Y1614908I150J-132D01*
G01Y1612966D01*
G03X1367372Y1612834I200J0D01*
G02Y1609922I-1664J-1456D01*
G03X1367322Y1609790I150J-132D01*
G01Y1609168D01*
G02X1367119Y1608966I-203J1D01*
G01X1364299D01*
G02X1364096Y1609168I-1J202D01*
G01Y1609790D01*
G03X1364046Y1609922I-200J0D01*
G02Y1612834I1664J1456D01*
G03X1364096Y1612966I-150J132D01*
G01Y1614908D01*
G03X1364046Y1615040I-200J0D01*
G02Y1617952I1664J1456D01*
G03X1364096Y1618084I-150J132D01*
G01Y1618706D01*
G02X1364299Y1618908I203J-1D01*
G37*
G36*
G01X1676109D02*
X1678929D01*
G02X1679132Y1618706I1J-202D01*
G01Y1618084D01*
G03X1679182Y1617952I200J0D01*
G02Y1615040I-1664J-1456D01*
G03X1679132Y1614908I150J-132D01*
G01Y1612966D01*
G03X1679182Y1612834I200J0D01*
G02Y1609922I-1664J-1456D01*
G03X1679132Y1609790I150J-132D01*
G01Y1609168D01*
G02X1678929Y1608966I-203J1D01*
G01X1676109D01*
G02X1675906Y1609168I-1J202D01*
G01Y1609790D01*
G03X1675856Y1609922I-200J0D01*
G02Y1612834I1664J1456D01*
G03X1675906Y1612966I-150J132D01*
G01Y1614908D01*
G03X1675856Y1615040I-200J0D01*
G02Y1617952I1664J1456D01*
G03X1675906Y1618084I-150J132D01*
G01Y1618706D01*
G02X1676109Y1618908I203J-1D01*
G37*
G36*
G01X1710755D02*
X1713575D01*
G02X1713778Y1618706I1J-202D01*
G01Y1618084D01*
G03X1713828Y1617952I200J0D01*
G02Y1615040I-1664J-1456D01*
G03X1713778Y1614908I150J-132D01*
G01Y1612966D01*
G03X1713828Y1612834I200J0D01*
G02Y1609922I-1664J-1456D01*
G03X1713778Y1609790I150J-132D01*
G01Y1609168D01*
G02X1713575Y1608966I-203J1D01*
G01X1710755D01*
G02X1710552Y1609168I-1J202D01*
G01Y1609790D01*
G03X1710502Y1609922I-200J0D01*
G02Y1612834I1664J1456D01*
G03X1710552Y1612966I-150J132D01*
G01Y1614908D01*
G03X1710502Y1615040I-200J0D01*
G02Y1617952I1664J1456D01*
G03X1710552Y1618084I-150J132D01*
G01Y1618706D01*
G02X1710755Y1618908I203J-1D01*
G37*
G36*
G01X1522570Y1409998D02*
X1525970D01*
G02Y1406992I0J-1503D01*
G01X1522570D01*
G02Y1409998I0J1503D01*
G37*
G36*
G01X1559290Y1349690D02*
X1562690D01*
G02Y1346684I0J-1503D01*
G01X1559290D01*
G02Y1349690I0J1503D01*
G37*
G36*
G01X1522570Y1385800D02*
X1525970D01*
G02Y1382794I0J-1503D01*
G01X1522570D01*
G02Y1385800I0J1503D01*
G37*
G36*
G01Y1373888D02*
X1525970D01*
G02Y1370882I0J-1503D01*
G01X1522570D01*
G02Y1373888I0J1503D01*
G37*
G36*
G01Y1398086D02*
X1525970D01*
G02Y1395080I0J-1503D01*
G01X1522570D01*
G02Y1398086I0J1503D01*
G37*
G36*
G01X1510330Y1373888D02*
X1513730D01*
G02Y1370882I0J-1503D01*
G01X1510330D01*
G02Y1373888I0J1503D01*
G37*
G36*
G01X1547050Y1361602D02*
X1550450D01*
G02Y1358596I0J-1503D01*
G01X1547050D01*
G02Y1361602I0J1503D01*
G37*
G36*
G01X1534810D02*
X1538210D01*
G02Y1358596I0J-1503D01*
G01X1534810D01*
G02Y1361602I0J1503D01*
G37*
G36*
G01X1547050Y1349690D02*
X1550450D01*
G02Y1346684I0J-1503D01*
G01X1547050D01*
G02Y1349690I0J1503D01*
G37*
G36*
G01X1534810D02*
X1538210D01*
G02Y1346684I0J-1503D01*
G01X1534810D01*
G02Y1349690I0J1503D01*
G37*
G36*
G01X241623Y1373888D02*
X245023D01*
G02Y1370882I0J-1503D01*
G01X241623D01*
G02Y1373888I0J1503D01*
G37*
G36*
G01Y1361602D02*
X245023D01*
G02Y1358596I0J-1503D01*
G01X241623D01*
G02Y1361602I0J1503D01*
G37*
G36*
G01X1485850Y1409998D02*
X1489250D01*
G02Y1406992I0J-1503D01*
G01X1485850D01*
G02Y1409998I0J1503D01*
G37*
G36*
G01X1510330Y1349690D02*
X1513730D01*
G02Y1346684I0J-1503D01*
G01X1510330D01*
G02Y1349690I0J1503D01*
G37*
G36*
G01X364023Y1398086D02*
X367423D01*
G02Y1395080I0J-1503D01*
G01X364023D01*
G02Y1398086I0J1503D01*
G37*
G36*
G01X1485850Y1385800D02*
X1489250D01*
G02Y1382794I0J-1503D01*
G01X1485850D01*
G02Y1385800I0J1503D01*
G37*
G36*
G01X1473610D02*
X1477010D01*
G02Y1382794I0J-1503D01*
G01X1473610D01*
G02Y1385800I0J1503D01*
G37*
G36*
G01Y1361602D02*
X1477010D01*
G02Y1358596I0J-1503D01*
G01X1473610D01*
G02Y1361602I0J1503D01*
G37*
G36*
G01Y1349690D02*
X1477010D01*
G02Y1346684I0J-1503D01*
G01X1473610D01*
G02Y1349690I0J1503D01*
G37*
G36*
G01X1461370Y1385800D02*
X1464770D01*
G02Y1382794I0J-1503D01*
G01X1461370D01*
G02Y1385800I0J1503D01*
G37*
G36*
G01Y1373888D02*
X1464770D01*
G02Y1370882I0J-1503D01*
G01X1461370D01*
G02Y1373888I0J1503D01*
G37*
G36*
G01Y1361602D02*
X1464770D01*
G02Y1358596I0J-1503D01*
G01X1461370D01*
G02Y1361602I0J1503D01*
G37*
G36*
G01Y1349690D02*
X1464770D01*
G02Y1346684I0J-1503D01*
G01X1461370D01*
G02Y1349690I0J1503D01*
G37*
G36*
G01X1485850Y1373888D02*
X1489250D01*
G02Y1370882I0J-1503D01*
G01X1485850D01*
G02Y1373888I0J1503D01*
G37*
G36*
G01X1498090Y1361602D02*
X1501490D01*
G02Y1358596I0J-1503D01*
G01X1498090D01*
G02Y1361602I0J1503D01*
G37*
G36*
G01X1485850D02*
X1489250D01*
G02Y1358596I0J-1503D01*
G01X1485850D01*
G02Y1361602I0J1503D01*
G37*
G36*
G01X253863Y1409998D02*
X257263D01*
G02Y1406992I0J-1503D01*
G01X253863D01*
G02Y1409998I0J1503D01*
G37*
G36*
G01X266103Y1373888D02*
X269503D01*
G02Y1370882I0J-1503D01*
G01X266103D01*
G02Y1373888I0J1503D01*
G37*
G36*
G01X290583Y1361602D02*
X293983D01*
G02Y1358596I0J-1503D01*
G01X290583D01*
G02Y1361602I0J1503D01*
G37*
G36*
G01X327303Y1349690D02*
X330703D01*
G02Y1346684I0J-1503D01*
G01X327303D01*
G02Y1349690I0J1503D01*
G37*
G36*
G01X290583Y1385800D02*
X293983D01*
G02Y1382794I0J-1503D01*
G01X290583D01*
G02Y1385800I0J1503D01*
G37*
G36*
G01Y1409998D02*
X293983D01*
G02Y1406992I0J-1503D01*
G01X290583D01*
G02Y1409998I0J1503D01*
G37*
G36*
G01X253863Y1398086D02*
X257263D01*
G02Y1395080I0J-1503D01*
G01X253863D01*
G02Y1398086I0J1503D01*
G37*
G36*
G01X364023Y1361602D02*
X367423D01*
G02Y1358596I0J-1503D01*
G01X364023D01*
G02Y1361602I0J1503D01*
G37*
G36*
G01X339543Y1349690D02*
X342943D01*
G02Y1346684I0J-1503D01*
G01X339543D01*
G02Y1349690I0J1503D01*
G37*
G36*
G01X241623D02*
X245023D01*
G02Y1346684I0J-1503D01*
G01X241623D01*
G02Y1349690I0J1503D01*
G37*
G36*
G01X339543Y1361602D02*
X342943D01*
G02Y1358596I0J-1503D01*
G01X339543D01*
G02Y1361602I0J1503D01*
G37*
G36*
G01X302823Y1409998D02*
X306223D01*
G02Y1406992I0J-1503D01*
G01X302823D01*
G02Y1409998I0J1503D01*
G37*
G36*
G01X364023Y1385800D02*
X367423D01*
G02Y1382794I0J-1503D01*
G01X364023D01*
G02Y1385800I0J1503D01*
G37*
G36*
G01X290583Y1398086D02*
X293983D01*
G02Y1395080I0J-1503D01*
G01X290583D01*
G02Y1398086I0J1503D01*
G37*
G36*
G01X112832D02*
X116232D01*
G02Y1395080I0J-1503D01*
G01X112832D01*
G02Y1398086I0J1503D01*
G37*
G36*
G01X364023Y1373888D02*
X367423D01*
G02Y1370882I0J-1503D01*
G01X364023D01*
G02Y1373888I0J1503D01*
G37*
G36*
G01X302823Y1361602D02*
X306223D01*
G02Y1358596I0J-1503D01*
G01X302823D01*
G02Y1361602I0J1503D01*
G37*
G36*
G01X1534810Y1409998D02*
X1538210D01*
G02Y1406992I0J-1503D01*
G01X1534810D01*
G02Y1409998I0J1503D01*
G37*
G36*
G01X1510330Y1385800D02*
X1513730D01*
G02Y1382794I0J-1503D01*
G01X1510330D01*
G02Y1385800I0J1503D01*
G37*
G36*
G01X1534810Y1398086D02*
X1538210D01*
G02Y1395080I0J-1503D01*
G01X1534810D01*
G02Y1398086I0J1503D01*
G37*
G36*
G01X302823Y1349690D02*
X306223D01*
G02Y1346684I0J-1503D01*
G01X302823D01*
G02Y1349690I0J1503D01*
G37*
G36*
G01X88352Y1373888D02*
X91752D01*
G02Y1370882I0J-1503D01*
G01X88352D01*
G02Y1373888I0J1503D01*
G37*
G36*
G01X339543Y1385800D02*
X342943D01*
G02Y1382794I0J-1503D01*
G01X339543D01*
G02Y1385800I0J1503D01*
G37*
G36*
G01X327303Y1373888D02*
X330703D01*
G02Y1370882I0J-1503D01*
G01X327303D01*
G02Y1373888I0J1503D01*
G37*
G36*
G01Y1409998D02*
X330703D01*
G02Y1406992I0J-1503D01*
G01X327303D01*
G02Y1409998I0J1503D01*
G37*
G36*
G01X278343Y1398086D02*
X281743D01*
G02Y1395080I0J-1503D01*
G01X278343D01*
G02Y1398086I0J1503D01*
G37*
G36*
G01X351783Y1349690D02*
X355183D01*
G02Y1346684I0J-1503D01*
G01X351783D01*
G02Y1349690I0J1503D01*
G37*
G36*
G01X186272Y1385800D02*
X189672D01*
G02Y1382794I0J-1503D01*
G01X186272D01*
G02Y1385800I0J1503D01*
G37*
G36*
G01Y1373888D02*
X189672D01*
G02Y1370882I0J-1503D01*
G01X186272D01*
G02Y1373888I0J1503D01*
G37*
G36*
G01X315063Y1361602D02*
X318463D01*
G02Y1358596I0J-1503D01*
G01X315063D01*
G02Y1361602I0J1503D01*
G37*
G36*
G01X327303D02*
X330703D01*
G02Y1358596I0J-1503D01*
G01X327303D01*
G02Y1361602I0J1503D01*
G37*
G36*
G01X315063Y1349690D02*
X318463D01*
G02Y1346684I0J-1503D01*
G01X315063D01*
G02Y1349690I0J1503D01*
G37*
G36*
G01X174032Y1398086D02*
X177432D01*
G02Y1395080I0J-1503D01*
G01X174032D01*
G02Y1398086I0J1503D01*
G37*
G36*
G01X266103Y1349690D02*
X269503D01*
G02Y1346684I0J-1503D01*
G01X266103D01*
G02Y1349690I0J1503D01*
G37*
G36*
G01X1054713Y1361602D02*
X1058113D01*
G02Y1358596I0J-1503D01*
G01X1054713D01*
G02Y1361602I0J1503D01*
G37*
G36*
G01Y1349690D02*
X1058113D01*
G02Y1346684I0J-1503D01*
G01X1054713D01*
G02Y1349690I0J1503D01*
G37*
G36*
G01Y1385800D02*
X1058113D01*
G02Y1382794I0J-1503D01*
G01X1054713D01*
G02Y1385800I0J1503D01*
G37*
G36*
G01Y1373888D02*
X1058113D01*
G02Y1370882I0J-1503D01*
G01X1054713D01*
G02Y1373888I0J1503D01*
G37*
G36*
G01X1177113Y1409998D02*
X1180513D01*
G02Y1406992I0J-1503D01*
G01X1177113D01*
G02Y1409998I0J1503D01*
G37*
G36*
G01Y1398086D02*
X1180513D01*
G02Y1395080I0J-1503D01*
G01X1177113D01*
G02Y1398086I0J1503D01*
G37*
G36*
G01Y1373888D02*
X1180513D01*
G02Y1370882I0J-1503D01*
G01X1177113D01*
G02Y1373888I0J1503D01*
G37*
G36*
G01Y1385800D02*
X1180513D01*
G02Y1382794I0J-1503D01*
G01X1177113D01*
G02Y1385800I0J1503D01*
G37*
G36*
G01Y1361602D02*
X1180513D01*
G02Y1358596I0J-1503D01*
G01X1177113D01*
G02Y1361602I0J1503D01*
G37*
G36*
G01Y1349690D02*
X1180513D01*
G02Y1346684I0J-1503D01*
G01X1177113D01*
G02Y1349690I0J1503D01*
G37*
G36*
G01X1164873Y1409998D02*
X1168273D01*
G02Y1406992I0J-1503D01*
G01X1164873D01*
G02Y1409998I0J1503D01*
G37*
G36*
G01Y1398086D02*
X1168273D01*
G02Y1395080I0J-1503D01*
G01X1164873D01*
G02Y1398086I0J1503D01*
G37*
G36*
G01Y1385800D02*
X1168273D01*
G02Y1382794I0J-1503D01*
G01X1164873D01*
G02Y1385800I0J1503D01*
G37*
G36*
G01Y1373888D02*
X1168273D01*
G02Y1370882I0J-1503D01*
G01X1164873D01*
G02Y1373888I0J1503D01*
G37*
G36*
G01Y1361602D02*
X1168273D01*
G02Y1358596I0J-1503D01*
G01X1164873D01*
G02Y1361602I0J1503D01*
G37*
G36*
G01Y1349690D02*
X1168273D01*
G02Y1346684I0J-1503D01*
G01X1164873D01*
G02Y1349690I0J1503D01*
G37*
G36*
G01X1152633Y1409998D02*
X1156033D01*
G02Y1406992I0J-1503D01*
G01X1152633D01*
G02Y1409998I0J1503D01*
G37*
G36*
G01Y1398086D02*
X1156033D01*
G02Y1395080I0J-1503D01*
G01X1152633D01*
G02Y1398086I0J1503D01*
G37*
G36*
G01Y1373888D02*
X1156033D01*
G02Y1370882I0J-1503D01*
G01X1152633D01*
G02Y1373888I0J1503D01*
G37*
G36*
G01Y1385800D02*
X1156033D01*
G02Y1382794I0J-1503D01*
G01X1152633D01*
G02Y1385800I0J1503D01*
G37*
G36*
G01Y1361602D02*
X1156033D01*
G02Y1358596I0J-1503D01*
G01X1152633D01*
G02Y1361602I0J1503D01*
G37*
G36*
G01Y1349690D02*
X1156033D01*
G02Y1346684I0J-1503D01*
G01X1152633D01*
G02Y1349690I0J1503D01*
G37*
G36*
G01X1128153Y1409998D02*
X1131553D01*
G02Y1406992I0J-1503D01*
G01X1128153D01*
G02Y1409998I0J1503D01*
G37*
G36*
G01X1140393D02*
X1143793D01*
G02Y1406992I0J-1503D01*
G01X1140393D01*
G02Y1409998I0J1503D01*
G37*
G36*
G01X1128153Y1398086D02*
X1131553D01*
G02Y1395080I0J-1503D01*
G01X1128153D01*
G02Y1398086I0J1503D01*
G37*
G36*
G01X1140393D02*
X1143793D01*
G02Y1395080I0J-1503D01*
G01X1140393D01*
G02Y1398086I0J1503D01*
G37*
G36*
G01X1128153Y1373888D02*
X1131553D01*
G02Y1370882I0J-1503D01*
G01X1128153D01*
G02Y1373888I0J1503D01*
G37*
G36*
G01Y1385800D02*
X1131553D01*
G02Y1382794I0J-1503D01*
G01X1128153D01*
G02Y1385800I0J1503D01*
G37*
G36*
G01X1140393D02*
X1143793D01*
G02Y1382794I0J-1503D01*
G01X1140393D01*
G02Y1385800I0J1503D01*
G37*
G36*
G01Y1373888D02*
X1143793D01*
G02Y1370882I0J-1503D01*
G01X1140393D01*
G02Y1373888I0J1503D01*
G37*
G36*
G01X1128153Y1361602D02*
X1131553D01*
G02Y1358596I0J-1503D01*
G01X1128153D01*
G02Y1361602I0J1503D01*
G37*
G36*
G01X1140393D02*
X1143793D01*
G02Y1358596I0J-1503D01*
G01X1140393D01*
G02Y1361602I0J1503D01*
G37*
G36*
G01X1128153Y1349690D02*
X1131553D01*
G02Y1346684I0J-1503D01*
G01X1128153D01*
G02Y1349690I0J1503D01*
G37*
G36*
G01X1140393D02*
X1143793D01*
G02Y1346684I0J-1503D01*
G01X1140393D01*
G02Y1349690I0J1503D01*
G37*
G36*
G01X1115913Y1409998D02*
X1119313D01*
G02Y1406992I0J-1503D01*
G01X1115913D01*
G02Y1409998I0J1503D01*
G37*
G36*
G01Y1398086D02*
X1119313D01*
G02Y1395080I0J-1503D01*
G01X1115913D01*
G02Y1398086I0J1503D01*
G37*
G36*
G01Y1373888D02*
X1119313D01*
G02Y1370882I0J-1503D01*
G01X1115913D01*
G02Y1373888I0J1503D01*
G37*
G36*
G01Y1385800D02*
X1119313D01*
G02Y1382794I0J-1503D01*
G01X1115913D01*
G02Y1385800I0J1503D01*
G37*
G36*
G01Y1361602D02*
X1119313D01*
G02Y1358596I0J-1503D01*
G01X1115913D01*
G02Y1361602I0J1503D01*
G37*
G36*
G01Y1349690D02*
X1119313D01*
G02Y1346684I0J-1503D01*
G01X1115913D01*
G02Y1349690I0J1503D01*
G37*
G36*
G01X1103673Y1409998D02*
X1107073D01*
G02Y1406992I0J-1503D01*
G01X1103673D01*
G02Y1409998I0J1503D01*
G37*
G36*
G01Y1398086D02*
X1107073D01*
G02Y1395080I0J-1503D01*
G01X1103673D01*
G02Y1398086I0J1503D01*
G37*
G36*
G01Y1385800D02*
X1107073D01*
G02Y1382794I0J-1503D01*
G01X1103673D01*
G02Y1385800I0J1503D01*
G37*
G36*
G01Y1373888D02*
X1107073D01*
G02Y1370882I0J-1503D01*
G01X1103673D01*
G02Y1373888I0J1503D01*
G37*
G36*
G01Y1361602D02*
X1107073D01*
G02Y1358596I0J-1503D01*
G01X1103673D01*
G02Y1361602I0J1503D01*
G37*
G36*
G01Y1349690D02*
X1107073D01*
G02Y1346684I0J-1503D01*
G01X1103673D01*
G02Y1349690I0J1503D01*
G37*
G36*
G01X1079193Y1409998D02*
X1082593D01*
G02Y1406992I0J-1503D01*
G01X1079193D01*
G02Y1409998I0J1503D01*
G37*
G36*
G01X1091433D02*
X1094833D01*
G02Y1406992I0J-1503D01*
G01X1091433D01*
G02Y1409998I0J1503D01*
G37*
G36*
G01X1079193Y1398086D02*
X1082593D01*
G02Y1395080I0J-1503D01*
G01X1079193D01*
G02Y1398086I0J1503D01*
G37*
G36*
G01X1091433D02*
X1094833D01*
G02Y1395080I0J-1503D01*
G01X1091433D01*
G02Y1398086I0J1503D01*
G37*
G36*
G01X1079193Y1385800D02*
X1082593D01*
G02Y1382794I0J-1503D01*
G01X1079193D01*
G02Y1385800I0J1503D01*
G37*
G36*
G01Y1373888D02*
X1082593D01*
G02Y1370882I0J-1503D01*
G01X1079193D01*
G02Y1373888I0J1503D01*
G37*
G36*
G01X1091433Y1385800D02*
X1094833D01*
G02Y1382794I0J-1503D01*
G01X1091433D01*
G02Y1385800I0J1503D01*
G37*
G36*
G01Y1373888D02*
X1094833D01*
G02Y1370882I0J-1503D01*
G01X1091433D01*
G02Y1373888I0J1503D01*
G37*
G36*
G01X1079193Y1361602D02*
X1082593D01*
G02Y1358596I0J-1503D01*
G01X1079193D01*
G02Y1361602I0J1503D01*
G37*
G36*
G01X1091433D02*
X1094833D01*
G02Y1358596I0J-1503D01*
G01X1091433D01*
G02Y1361602I0J1503D01*
G37*
G36*
G01X1079193Y1349690D02*
X1082593D01*
G02Y1346684I0J-1503D01*
G01X1079193D01*
G02Y1349690I0J1503D01*
G37*
G36*
G01X1091433D02*
X1094833D01*
G02Y1346684I0J-1503D01*
G01X1091433D01*
G02Y1349690I0J1503D01*
G37*
G36*
G01X1066953Y1409998D02*
X1070353D01*
G02Y1406992I0J-1503D01*
G01X1066953D01*
G02Y1409998I0J1503D01*
G37*
G36*
G01Y1398086D02*
X1070353D01*
G02Y1395080I0J-1503D01*
G01X1066953D01*
G02Y1398086I0J1503D01*
G37*
G36*
G01X290583Y1349690D02*
X293983D01*
G02Y1346684I0J-1503D01*
G01X290583D01*
G02Y1349690I0J1503D01*
G37*
G36*
G01X241623Y1385800D02*
X245023D01*
G02Y1382794I0J-1503D01*
G01X241623D01*
G02Y1385800I0J1503D01*
G37*
G36*
G01X253863Y1361602D02*
X257263D01*
G02Y1358596I0J-1503D01*
G01X253863D01*
G02Y1361602I0J1503D01*
G37*
G36*
G01Y1349690D02*
X257263D01*
G02Y1346684I0J-1503D01*
G01X253863D01*
G02Y1349690I0J1503D01*
G37*
G36*
G01X1547050Y1409998D02*
X1550450D01*
G02Y1406992I0J-1503D01*
G01X1547050D01*
G02Y1409998I0J1503D01*
G37*
G36*
G01X1559290Y1385800D02*
X1562690D01*
G02Y1382794I0J-1503D01*
G01X1559290D01*
G02Y1385800I0J1503D01*
G37*
G36*
G01X1230326Y1349690D02*
X1233726D01*
G02Y1346684I0J-1503D01*
G01X1230326D01*
G02Y1349690I0J1503D01*
G37*
G36*
G01Y1361602D02*
X1233726D01*
G02Y1358596I0J-1503D01*
G01X1230326D01*
G02Y1361602I0J1503D01*
G37*
G36*
G01Y1373888D02*
X1233726D01*
G02Y1370882I0J-1503D01*
G01X1230326D01*
G02Y1373888I0J1503D01*
G37*
G36*
G01Y1385800D02*
X1233726D01*
G02Y1382794I0J-1503D01*
G01X1230326D01*
G02Y1385800I0J1503D01*
G37*
G36*
G01X1242566Y1349690D02*
X1245966D01*
G02Y1346684I0J-1503D01*
G01X1242566D01*
G02Y1349690I0J1503D01*
G37*
G36*
G01Y1361602D02*
X1245966D01*
G02Y1358596I0J-1503D01*
G01X1242566D01*
G02Y1361602I0J1503D01*
G37*
G36*
G01Y1385800D02*
X1245966D01*
G02Y1382794I0J-1503D01*
G01X1242566D01*
G02Y1385800I0J1503D01*
G37*
G36*
G01Y1373888D02*
X1245966D01*
G02Y1370882I0J-1503D01*
G01X1242566D01*
G02Y1373888I0J1503D01*
G37*
G36*
G01Y1398086D02*
X1245966D01*
G02Y1395080I0J-1503D01*
G01X1242566D01*
G02Y1398086I0J1503D01*
G37*
G36*
G01Y1409998D02*
X1245966D01*
G02Y1406992I0J-1503D01*
G01X1242566D01*
G02Y1409998I0J1503D01*
G37*
G36*
G01X1267046Y1349690D02*
X1270446D01*
G02Y1346684I0J-1503D01*
G01X1267046D01*
G02Y1349690I0J1503D01*
G37*
G36*
G01X1254806D02*
X1258206D01*
G02Y1346684I0J-1503D01*
G01X1254806D01*
G02Y1349690I0J1503D01*
G37*
G36*
G01X1267046Y1361602D02*
X1270446D01*
G02Y1358596I0J-1503D01*
G01X1267046D01*
G02Y1361602I0J1503D01*
G37*
G36*
G01X1254806D02*
X1258206D01*
G02Y1358596I0J-1503D01*
G01X1254806D01*
G02Y1361602I0J1503D01*
G37*
G36*
G01X1267046Y1385800D02*
X1270446D01*
G02Y1382794I0J-1503D01*
G01X1267046D01*
G02Y1385800I0J1503D01*
G37*
G36*
G01Y1373888D02*
X1270446D01*
G02Y1370882I0J-1503D01*
G01X1267046D01*
G02Y1373888I0J1503D01*
G37*
G36*
G01X1254806D02*
X1258206D01*
G02Y1370882I0J-1503D01*
G01X1254806D01*
G02Y1373888I0J1503D01*
G37*
G36*
G01Y1385800D02*
X1258206D01*
G02Y1382794I0J-1503D01*
G01X1254806D01*
G02Y1385800I0J1503D01*
G37*
G36*
G01X1267046Y1398086D02*
X1270446D01*
G02Y1395080I0J-1503D01*
G01X1267046D01*
G02Y1398086I0J1503D01*
G37*
G36*
G01X1254806D02*
X1258206D01*
G02Y1395080I0J-1503D01*
G01X1254806D01*
G02Y1398086I0J1503D01*
G37*
G36*
G01X1267046Y1409998D02*
X1270446D01*
G02Y1406992I0J-1503D01*
G01X1267046D01*
G02Y1409998I0J1503D01*
G37*
G36*
G01X1254806D02*
X1258206D01*
G02Y1406992I0J-1503D01*
G01X1254806D01*
G02Y1409998I0J1503D01*
G37*
G36*
G01X1279286Y1349690D02*
X1282686D01*
G02Y1346684I0J-1503D01*
G01X1279286D01*
G02Y1349690I0J1503D01*
G37*
G36*
G01Y1361602D02*
X1282686D01*
G02Y1358596I0J-1503D01*
G01X1279286D01*
G02Y1361602I0J1503D01*
G37*
G36*
G01X1510330D02*
X1513730D01*
G02Y1358596I0J-1503D01*
G01X1510330D01*
G02Y1361602I0J1503D01*
G37*
G36*
G01X1279286Y1373888D02*
X1282686D01*
G02Y1370882I0J-1503D01*
G01X1279286D01*
G02Y1373888I0J1503D01*
G37*
G36*
G01Y1385800D02*
X1282686D01*
G02Y1382794I0J-1503D01*
G01X1279286D01*
G02Y1385800I0J1503D01*
G37*
G36*
G01X1648118Y1409998D02*
X1651518D01*
G02Y1406992I0J-1503D01*
G01X1648118D01*
G02Y1409998I0J1503D01*
G37*
G36*
G01X1279286Y1398086D02*
X1282686D01*
G02Y1395080I0J-1503D01*
G01X1279286D01*
G02Y1398086I0J1503D01*
G37*
G36*
G01Y1409998D02*
X1282686D01*
G02Y1406992I0J-1503D01*
G01X1279286D01*
G02Y1409998I0J1503D01*
G37*
G36*
G01X1291526Y1349690D02*
X1294926D01*
G02Y1346684I0J-1503D01*
G01X1291526D01*
G02Y1349690I0J1503D01*
G37*
G36*
G01X1559290Y1398086D02*
X1562690D01*
G02Y1395080I0J-1503D01*
G01X1559290D01*
G02Y1398086I0J1503D01*
G37*
G36*
G01X161792Y1409998D02*
X165192D01*
G02Y1406992I0J-1503D01*
G01X161792D01*
G02Y1409998I0J1503D01*
G37*
G36*
G01X186272Y1349690D02*
X189672D01*
G02Y1346684I0J-1503D01*
G01X186272D01*
G02Y1349690I0J1503D01*
G37*
G36*
G01X315063Y1409998D02*
X318463D01*
G02Y1406992I0J-1503D01*
G01X315063D01*
G02Y1409998I0J1503D01*
G37*
G36*
G01X1534810Y1373888D02*
X1538210D01*
G02Y1370882I0J-1503D01*
G01X1534810D01*
G02Y1373888I0J1503D01*
G37*
G36*
G01X1559290Y1409998D02*
X1562690D01*
G02Y1406992I0J-1503D01*
G01X1559290D01*
G02Y1409998I0J1503D01*
G37*
G36*
G01X351783Y1361602D02*
X355183D01*
G02Y1358596I0J-1503D01*
G01X351783D01*
G02Y1361602I0J1503D01*
G37*
G36*
G01X198512Y1385800D02*
X201912D01*
G02Y1382794I0J-1503D01*
G01X198512D01*
G02Y1385800I0J1503D01*
G37*
G36*
G01X1291526Y1361602D02*
X1294926D01*
G02Y1358596I0J-1503D01*
G01X1291526D01*
G02Y1361602I0J1503D01*
G37*
G36*
G01X1635878Y1349690D02*
X1639278D01*
G02Y1346684I0J-1503D01*
G01X1635878D01*
G02Y1349690I0J1503D01*
G37*
G36*
G01Y1361602D02*
X1639278D01*
G02Y1358596I0J-1503D01*
G01X1635878D01*
G02Y1361602I0J1503D01*
G37*
G36*
G01X1291526Y1385800D02*
X1294926D01*
G02Y1382794I0J-1503D01*
G01X1291526D01*
G02Y1385800I0J1503D01*
G37*
G36*
G01Y1373888D02*
X1294926D01*
G02Y1370882I0J-1503D01*
G01X1291526D01*
G02Y1373888I0J1503D01*
G37*
G36*
G01X1635878Y1385800D02*
X1639278D01*
G02Y1382794I0J-1503D01*
G01X1635878D01*
G02Y1385800I0J1503D01*
G37*
G36*
G01Y1373888D02*
X1639278D01*
G02Y1370882I0J-1503D01*
G01X1635878D01*
G02Y1373888I0J1503D01*
G37*
G36*
G01Y1398086D02*
X1639278D01*
G02Y1395080I0J-1503D01*
G01X1635878D01*
G02Y1398086I0J1503D01*
G37*
G36*
G01X1623638Y1349690D02*
X1627038D01*
G02Y1346684I0J-1503D01*
G01X1623638D01*
G02Y1349690I0J1503D01*
G37*
G36*
G01X1611398D02*
X1614798D01*
G02Y1346684I0J-1503D01*
G01X1611398D01*
G02Y1349690I0J1503D01*
G37*
G36*
G01X1623638Y1361602D02*
X1627038D01*
G02Y1358596I0J-1503D01*
G01X1623638D01*
G02Y1361602I0J1503D01*
G37*
G36*
G01X1291526Y1398086D02*
X1294926D01*
G02Y1395080I0J-1503D01*
G01X1291526D01*
G02Y1398086I0J1503D01*
G37*
G36*
G01Y1409998D02*
X1294926D01*
G02Y1406992I0J-1503D01*
G01X1291526D01*
G02Y1409998I0J1503D01*
G37*
G36*
G01X1316006Y1349690D02*
X1319406D01*
G02Y1346684I0J-1503D01*
G01X1316006D01*
G02Y1349690I0J1503D01*
G37*
G36*
G01X1303766D02*
X1307166D01*
G02Y1346684I0J-1503D01*
G01X1303766D01*
G02Y1349690I0J1503D01*
G37*
G36*
G01X1316006Y1361602D02*
X1319406D01*
G02Y1358596I0J-1503D01*
G01X1316006D01*
G02Y1361602I0J1503D01*
G37*
G36*
G01X1303766D02*
X1307166D01*
G02Y1358596I0J-1503D01*
G01X1303766D01*
G02Y1361602I0J1503D01*
G37*
G36*
G01X1316006Y1385800D02*
X1319406D01*
G02Y1382794I0J-1503D01*
G01X1316006D01*
G02Y1385800I0J1503D01*
G37*
G36*
G01X1611398Y1373888D02*
X1614798D01*
G02Y1370882I0J-1503D01*
G01X1611398D01*
G02Y1373888I0J1503D01*
G37*
G36*
G01Y1385800D02*
X1614798D01*
G02Y1382794I0J-1503D01*
G01X1611398D01*
G02Y1385800I0J1503D01*
G37*
G36*
G01X1623638Y1398086D02*
X1627038D01*
G02Y1395080I0J-1503D01*
G01X1623638D01*
G02Y1398086I0J1503D01*
G37*
G36*
G01X1316006Y1373888D02*
X1319406D01*
G02Y1370882I0J-1503D01*
G01X1316006D01*
G02Y1373888I0J1503D01*
G37*
G36*
G01X1303766D02*
X1307166D01*
G02Y1370882I0J-1503D01*
G01X1303766D01*
G02Y1373888I0J1503D01*
G37*
G36*
G01Y1385800D02*
X1307166D01*
G02Y1382794I0J-1503D01*
G01X1303766D01*
G02Y1385800I0J1503D01*
G37*
G36*
G01X1316006Y1398086D02*
X1319406D01*
G02Y1395080I0J-1503D01*
G01X1316006D01*
G02Y1398086I0J1503D01*
G37*
G36*
G01X1303766D02*
X1307166D01*
G02Y1395080I0J-1503D01*
G01X1303766D01*
G02Y1398086I0J1503D01*
G37*
G36*
G01X1316006Y1409998D02*
X1319406D01*
G02Y1406992I0J-1503D01*
G01X1316006D01*
G02Y1409998I0J1503D01*
G37*
G36*
G01X1303766D02*
X1307166D01*
G02Y1406992I0J-1503D01*
G01X1303766D01*
G02Y1409998I0J1503D01*
G37*
G36*
G01X1623638D02*
X1627038D01*
G02Y1406992I0J-1503D01*
G01X1623638D01*
G02Y1409998I0J1503D01*
G37*
G36*
G01X1328246Y1349690D02*
X1331646D01*
G02Y1346684I0J-1503D01*
G01X1328246D01*
G02Y1349690I0J1503D01*
G37*
G36*
G01Y1361602D02*
X1331646D01*
G02Y1358596I0J-1503D01*
G01X1328246D01*
G02Y1361602I0J1503D01*
G37*
G36*
G01X1648118Y1398086D02*
X1651518D01*
G02Y1395080I0J-1503D01*
G01X1648118D01*
G02Y1398086I0J1503D01*
G37*
G36*
G01Y1373888D02*
X1651518D01*
G02Y1370882I0J-1503D01*
G01X1648118D01*
G02Y1373888I0J1503D01*
G37*
G36*
G01Y1385800D02*
X1651518D01*
G02Y1382794I0J-1503D01*
G01X1648118D01*
G02Y1385800I0J1503D01*
G37*
G36*
G01X1328246Y1373888D02*
X1331646D01*
G02Y1370882I0J-1503D01*
G01X1328246D01*
G02Y1373888I0J1503D01*
G37*
G36*
G01X1648118Y1361602D02*
X1651518D01*
G02Y1358596I0J-1503D01*
G01X1648118D01*
G02Y1361602I0J1503D01*
G37*
G36*
G01Y1349690D02*
X1651518D01*
G02Y1346684I0J-1503D01*
G01X1648118D01*
G02Y1349690I0J1503D01*
G37*
G36*
G01X1635878Y1409998D02*
X1639278D01*
G02Y1406992I0J-1503D01*
G01X1635878D01*
G02Y1409998I0J1503D01*
G37*
G36*
G01X1660358D02*
X1663758D01*
G02Y1406992I0J-1503D01*
G01X1660358D01*
G02Y1409998I0J1503D01*
G37*
G36*
G01X1672598D02*
X1675998D01*
G02Y1406992I0J-1503D01*
G01X1672598D01*
G02Y1409998I0J1503D01*
G37*
G36*
G01X1660358Y1398086D02*
X1663758D01*
G02Y1395080I0J-1503D01*
G01X1660358D01*
G02Y1398086I0J1503D01*
G37*
G36*
G01X1672598D02*
X1675998D01*
G02Y1395080I0J-1503D01*
G01X1672598D01*
G02Y1398086I0J1503D01*
G37*
G36*
G01X1660358Y1373888D02*
X1663758D01*
G02Y1370882I0J-1503D01*
G01X1660358D01*
G02Y1373888I0J1503D01*
G37*
G36*
G01Y1385800D02*
X1663758D01*
G02Y1382794I0J-1503D01*
G01X1660358D01*
G02Y1385800I0J1503D01*
G37*
G36*
G01X1672598Y1373888D02*
X1675998D01*
G02Y1370882I0J-1503D01*
G01X1672598D01*
G02Y1373888I0J1503D01*
G37*
G36*
G01X1328246Y1385800D02*
X1331646D01*
G02Y1382794I0J-1503D01*
G01X1328246D01*
G02Y1385800I0J1503D01*
G37*
G36*
G01X1672598D02*
X1675998D01*
G02Y1382794I0J-1503D01*
G01X1672598D01*
G02Y1385800I0J1503D01*
G37*
G36*
G01X174032Y1409998D02*
X177432D01*
G02Y1406992I0J-1503D01*
G01X174032D01*
G02Y1409998I0J1503D01*
G37*
G36*
G01X266103Y1385800D02*
X269503D01*
G02Y1382794I0J-1503D01*
G01X266103D01*
G02Y1385800I0J1503D01*
G37*
G36*
G01X315063D02*
X318463D01*
G02Y1382794I0J-1503D01*
G01X315063D01*
G02Y1385800I0J1503D01*
G37*
G36*
G01X278343Y1409998D02*
X281743D01*
G02Y1406992I0J-1503D01*
G01X278343D01*
G02Y1409998I0J1503D01*
G37*
G36*
G01X1328246Y1398086D02*
X1331646D01*
G02Y1395080I0J-1503D01*
G01X1328246D01*
G02Y1398086I0J1503D01*
G37*
G36*
G01X364023Y1409998D02*
X367423D01*
G02Y1406992I0J-1503D01*
G01X364023D01*
G02Y1409998I0J1503D01*
G37*
G36*
G01X266103D02*
X269503D01*
G02Y1406992I0J-1503D01*
G01X266103D01*
G02Y1409998I0J1503D01*
G37*
G36*
G01X1733798Y1385800D02*
X1737198D01*
G02Y1382794I0J-1503D01*
G01X1733798D01*
G02Y1385800I0J1503D01*
G37*
G36*
G01Y1373888D02*
X1737198D01*
G02Y1370882I0J-1503D01*
G01X1733798D01*
G02Y1373888I0J1503D01*
G37*
G36*
G01Y1398086D02*
X1737198D01*
G02Y1395080I0J-1503D01*
G01X1733798D01*
G02Y1398086I0J1503D01*
G37*
G36*
G01X1721558Y1373888D02*
X1724958D01*
G02Y1370882I0J-1503D01*
G01X1721558D01*
G02Y1373888I0J1503D01*
G37*
G36*
G01X290583D02*
X293983D01*
G02Y1370882I0J-1503D01*
G01X290583D01*
G02Y1373888I0J1503D01*
G37*
G36*
G01X1328246Y1409998D02*
X1331646D01*
G02Y1406992I0J-1503D01*
G01X1328246D01*
G02Y1409998I0J1503D01*
G37*
G36*
G01X1340486Y1349690D02*
X1343886D01*
G02Y1346684I0J-1503D01*
G01X1340486D01*
G02Y1349690I0J1503D01*
G37*
G36*
G01X1583770Y1373888D02*
X1587170D01*
G02Y1370882I0J-1503D01*
G01X1583770D01*
G02Y1373888I0J1503D01*
G37*
G36*
G01X1485850Y1349690D02*
X1489250D01*
G02Y1346684I0J-1503D01*
G01X1485850D01*
G02Y1349690I0J1503D01*
G37*
G36*
G01X1340486Y1361602D02*
X1343886D01*
G02Y1358596I0J-1503D01*
G01X1340486D01*
G02Y1361602I0J1503D01*
G37*
G36*
G01X1733798Y1409998D02*
X1737198D01*
G02Y1406992I0J-1503D01*
G01X1733798D01*
G02Y1409998I0J1503D01*
G37*
G36*
G01X278343Y1373888D02*
X281743D01*
G02Y1370882I0J-1503D01*
G01X278343D01*
G02Y1373888I0J1503D01*
G37*
G36*
G01X266103Y1398086D02*
X269503D01*
G02Y1395080I0J-1503D01*
G01X266103D01*
G02Y1398086I0J1503D01*
G37*
G36*
G01X1733798Y1349690D02*
X1737198D01*
G02Y1346684I0J-1503D01*
G01X1733798D01*
G02Y1349690I0J1503D01*
G37*
G36*
G01X137312Y1385800D02*
X140712D01*
G02Y1382794I0J-1503D01*
G01X137312D01*
G02Y1385800I0J1503D01*
G37*
G36*
G01X1721558Y1398086D02*
X1724958D01*
G02Y1395080I0J-1503D01*
G01X1721558D01*
G02Y1398086I0J1503D01*
G37*
G36*
G01X1340486Y1385800D02*
X1343886D01*
G02Y1382794I0J-1503D01*
G01X1340486D01*
G02Y1385800I0J1503D01*
G37*
G36*
G01Y1373888D02*
X1343886D01*
G02Y1370882I0J-1503D01*
G01X1340486D01*
G02Y1373888I0J1503D01*
G37*
G36*
G01X1721558Y1385800D02*
X1724958D01*
G02Y1382794I0J-1503D01*
G01X1721558D01*
G02Y1385800I0J1503D01*
G37*
G36*
G01X339543Y1398086D02*
X342943D01*
G02Y1395080I0J-1503D01*
G01X339543D01*
G02Y1398086I0J1503D01*
G37*
G36*
G01X327303Y1385800D02*
X330703D01*
G02Y1382794I0J-1503D01*
G01X327303D01*
G02Y1385800I0J1503D01*
G37*
G36*
G01X315063Y1373888D02*
X318463D01*
G02Y1370882I0J-1503D01*
G01X315063D01*
G02Y1373888I0J1503D01*
G37*
G36*
G01X339543D02*
X342943D01*
G02Y1370882I0J-1503D01*
G01X339543D01*
G02Y1373888I0J1503D01*
G37*
G36*
G01X351783Y1385800D02*
X355183D01*
G02Y1382794I0J-1503D01*
G01X351783D01*
G02Y1385800I0J1503D01*
G37*
G36*
G01Y1373888D02*
X355183D01*
G02Y1370882I0J-1503D01*
G01X351783D01*
G02Y1373888I0J1503D01*
G37*
G36*
G01Y1398086D02*
X355183D01*
G02Y1395080I0J-1503D01*
G01X351783D01*
G02Y1398086I0J1503D01*
G37*
G36*
G01Y1409998D02*
X355183D01*
G02Y1406992I0J-1503D01*
G01X351783D01*
G02Y1409998I0J1503D01*
G37*
G36*
G01X315063Y1398086D02*
X318463D01*
G02Y1395080I0J-1503D01*
G01X315063D01*
G02Y1398086I0J1503D01*
G37*
G36*
G01X278343Y1361602D02*
X281743D01*
G02Y1358596I0J-1503D01*
G01X278343D01*
G02Y1361602I0J1503D01*
G37*
G36*
G01X1498090Y1349690D02*
X1501490D01*
G02Y1346684I0J-1503D01*
G01X1498090D01*
G02Y1349690I0J1503D01*
G37*
G36*
G01X266103Y1361602D02*
X269503D01*
G02Y1358596I0J-1503D01*
G01X266103D01*
G02Y1361602I0J1503D01*
G37*
G36*
G01X35825Y1466648D02*
X39225D01*
G02Y1463044I0J-1802D01*
G01X35825D01*
G02Y1466648I0J1802D01*
G37*
G36*
G01X942699Y344560D02*
X939299D01*
G02Y348166I0J1803D01*
G01X942699D01*
G02Y344560I0J-1803D01*
G37*
G36*
G01X942730Y322242D02*
X939330D01*
G02Y325846I0J1802D01*
G01X942730D01*
G02Y322242I0J-1802D01*
G37*
G36*
G01X927963Y342238D02*
X924563D01*
G02Y345844I0J1803D01*
G01X927963D01*
G02Y342238I0J-1803D01*
G37*
G36*
G01X919353Y342348D02*
X915953D01*
G02Y345952I0J1802D01*
G01X919353D01*
G02Y342348I0J-1802D01*
G37*
G36*
G01X302823Y1398086D02*
X306223D01*
G02Y1395080I0J-1503D01*
G01X302823D01*
G02Y1398086I0J1503D01*
G37*
G36*
G01X389015Y794228D02*
X392415D01*
G02Y791222I0J-1503D01*
G01X389015D01*
G02Y794228I0J1503D01*
G37*
G36*
G01X302823Y1373888D02*
X306223D01*
G02Y1370882I0J-1503D01*
G01X302823D01*
G02Y1373888I0J1503D01*
G37*
G36*
G01X1534810Y1385800D02*
X1538210D01*
G02Y1382794I0J-1503D01*
G01X1534810D01*
G02Y1385800I0J1503D01*
G37*
G36*
G01X327303Y1398086D02*
X330703D01*
G02Y1395080I0J-1503D01*
G01X327303D01*
G02Y1398086I0J1503D01*
G37*
G36*
G01X339543Y1409998D02*
X342943D01*
G02Y1406992I0J-1503D01*
G01X339543D01*
G02Y1409998I0J1503D01*
G37*
G36*
G01X302823Y1385800D02*
X306223D01*
G02Y1382794I0J-1503D01*
G01X302823D01*
G02Y1385800I0J1503D01*
G37*
G36*
G01X278343D02*
X281743D01*
G02Y1382794I0J-1503D01*
G01X278343D01*
G02Y1385800I0J1503D01*
G37*
G36*
G01X1340486Y1398086D02*
X1343886D01*
G02Y1395080I0J-1503D01*
G01X1340486D01*
G02Y1398086I0J1503D01*
G37*
G36*
G01Y1409998D02*
X1343886D01*
G02Y1406992I0J-1503D01*
G01X1340486D01*
G02Y1409998I0J1503D01*
G37*
G36*
G01X1583770Y1385800D02*
X1587170D01*
G02Y1382794I0J-1503D01*
G01X1583770D01*
G02Y1385800I0J1503D01*
G37*
G36*
G01X1571530Y1349690D02*
X1574930D01*
G02Y1346684I0J-1503D01*
G01X1571530D01*
G02Y1349690I0J1503D01*
G37*
G36*
G01Y1373888D02*
X1574930D01*
G02Y1370882I0J-1503D01*
G01X1571530D01*
G02Y1373888I0J1503D01*
G37*
G36*
G01Y1385800D02*
X1574930D01*
G02Y1382794I0J-1503D01*
G01X1571530D01*
G02Y1385800I0J1503D01*
G37*
G36*
G01X1473610Y1398086D02*
X1477010D01*
G02Y1395080I0J-1503D01*
G01X1473610D01*
G02Y1398086I0J1503D01*
G37*
G36*
G01Y1409998D02*
X1477010D01*
G02Y1406992I0J-1503D01*
G01X1473610D01*
G02Y1409998I0J1503D01*
G37*
G36*
G01X1583770Y1398086D02*
X1587170D01*
G02Y1395080I0J-1503D01*
G01X1583770D01*
G02Y1398086I0J1503D01*
G37*
G36*
G01Y1409998D02*
X1587170D01*
G02Y1406992I0J-1503D01*
G01X1583770D01*
G02Y1409998I0J1503D01*
G37*
G36*
G01X1485850Y1398086D02*
X1489250D01*
G02Y1395080I0J-1503D01*
G01X1485850D01*
G02Y1398086I0J1503D01*
G37*
G36*
G01X1498090Y1373888D02*
X1501490D01*
G02Y1370882I0J-1503D01*
G01X1498090D01*
G02Y1373888I0J1503D01*
G37*
G36*
G01X1522570Y1361602D02*
X1525970D01*
G02Y1358596I0J-1503D01*
G01X1522570D01*
G02Y1361602I0J1503D01*
G37*
G36*
G01X1498090Y1409998D02*
X1501490D01*
G02Y1406992I0J-1503D01*
G01X1498090D01*
G02Y1409998I0J1503D01*
G37*
G36*
G01X1352726Y1349690D02*
X1356126D01*
G02Y1346684I0J-1503D01*
G01X1352726D01*
G02Y1349690I0J1503D01*
G37*
G36*
G01X1510330Y1398086D02*
X1513730D01*
G02Y1395080I0J-1503D01*
G01X1510330D01*
G02Y1398086I0J1503D01*
G37*
G36*
G01X1611398Y1361602D02*
X1614798D01*
G02Y1358596I0J-1503D01*
G01X1611398D01*
G02Y1361602I0J1503D01*
G37*
G36*
G01X1623638Y1373888D02*
X1627038D01*
G02Y1370882I0J-1503D01*
G01X1623638D01*
G02Y1373888I0J1503D01*
G37*
G36*
G01X1547050D02*
X1550450D01*
G02Y1370882I0J-1503D01*
G01X1547050D01*
G02Y1373888I0J1503D01*
G37*
G36*
G01X1352726Y1361602D02*
X1356126D01*
G02Y1358596I0J-1503D01*
G01X1352726D01*
G02Y1361602I0J1503D01*
G37*
G36*
G01Y1385800D02*
X1356126D01*
G02Y1382794I0J-1503D01*
G01X1352726D01*
G02Y1385800I0J1503D01*
G37*
G36*
G01Y1373888D02*
X1356126D01*
G02Y1370882I0J-1503D01*
G01X1352726D01*
G02Y1373888I0J1503D01*
G37*
G36*
G01X1684838Y1409998D02*
X1688238D01*
G02Y1406992I0J-1503D01*
G01X1684838D01*
G02Y1409998I0J1503D01*
G37*
G36*
G01X1709318Y1373888D02*
X1712718D01*
G02Y1370882I0J-1503D01*
G01X1709318D01*
G02Y1373888I0J1503D01*
G37*
G36*
G01Y1385800D02*
X1712718D01*
G02Y1382794I0J-1503D01*
G01X1709318D01*
G02Y1385800I0J1503D01*
G37*
G36*
G01X1733798Y1361602D02*
X1737198D01*
G02Y1358596I0J-1503D01*
G01X1733798D01*
G02Y1361602I0J1503D01*
G37*
G36*
G01X1697078Y1373888D02*
X1700478D01*
G02Y1370882I0J-1503D01*
G01X1697078D01*
G02Y1373888I0J1503D01*
G37*
G36*
G01X1709318Y1409998D02*
X1712718D01*
G02Y1406992I0J-1503D01*
G01X1709318D01*
G02Y1409998I0J1503D01*
G37*
G36*
G01X1697078Y1398086D02*
X1700478D01*
G02Y1395080I0J-1503D01*
G01X1697078D01*
G02Y1398086I0J1503D01*
G37*
G36*
G01X1709318D02*
X1712718D01*
G02Y1395080I0J-1503D01*
G01X1709318D01*
G02Y1398086I0J1503D01*
G37*
G36*
G01X1721558Y1349690D02*
X1724958D01*
G02Y1346684I0J-1503D01*
G01X1721558D01*
G02Y1349690I0J1503D01*
G37*
G36*
G01Y1361602D02*
X1724958D01*
G02Y1358596I0J-1503D01*
G01X1721558D01*
G02Y1361602I0J1503D01*
G37*
G36*
G01Y1409998D02*
X1724958D01*
G02Y1406992I0J-1503D01*
G01X1721558D01*
G02Y1409998I0J1503D01*
G37*
G36*
G01X1352726Y1398086D02*
X1356126D01*
G02Y1395080I0J-1503D01*
G01X1352726D01*
G02Y1398086I0J1503D01*
G37*
G36*
G01X174032Y1361602D02*
X177432D01*
G02Y1358596I0J-1503D01*
G01X174032D01*
G02Y1361602I0J1503D01*
G37*
G36*
G01X198512Y1349690D02*
X201912D01*
G02Y1346684I0J-1503D01*
G01X198512D01*
G02Y1349690I0J1503D01*
G37*
G36*
G01Y1398086D02*
X201912D01*
G02Y1395080I0J-1503D01*
G01X198512D01*
G02Y1398086I0J1503D01*
G37*
G36*
G01X186272D02*
X189672D01*
G02Y1395080I0J-1503D01*
G01X186272D01*
G02Y1398086I0J1503D01*
G37*
G36*
G01X161792Y1349690D02*
X165192D01*
G02Y1346684I0J-1503D01*
G01X161792D01*
G02Y1349690I0J1503D01*
G37*
G36*
G01X186272Y1361602D02*
X189672D01*
G02Y1358596I0J-1503D01*
G01X186272D01*
G02Y1361602I0J1503D01*
G37*
G36*
G01X100592Y1349690D02*
X103992D01*
G02Y1346684I0J-1503D01*
G01X100592D01*
G02Y1349690I0J1503D01*
G37*
G36*
G01X112832D02*
X116232D01*
G02Y1346684I0J-1503D01*
G01X112832D01*
G02Y1349690I0J1503D01*
G37*
G36*
G01X149552Y1398086D02*
X152952D01*
G02Y1395080I0J-1503D01*
G01X149552D01*
G02Y1398086I0J1503D01*
G37*
G36*
G01X161792D02*
X165192D01*
G02Y1395080I0J-1503D01*
G01X161792D01*
G02Y1398086I0J1503D01*
G37*
G36*
G01Y1373888D02*
X165192D01*
G02Y1370882I0J-1503D01*
G01X161792D01*
G02Y1373888I0J1503D01*
G37*
G36*
G01Y1385800D02*
X165192D01*
G02Y1382794I0J-1503D01*
G01X161792D01*
G02Y1385800I0J1503D01*
G37*
G36*
G01X198512Y1361602D02*
X201912D01*
G02Y1358596I0J-1503D01*
G01X198512D01*
G02Y1361602I0J1503D01*
G37*
G36*
G01X137312D02*
X140712D01*
G02Y1358596I0J-1503D01*
G01X137312D01*
G02Y1361602I0J1503D01*
G37*
G36*
G01X161792D02*
X165192D01*
G02Y1358596I0J-1503D01*
G01X161792D01*
G02Y1361602I0J1503D01*
G37*
G36*
G01X149552Y1349690D02*
X152952D01*
G02Y1346684I0J-1503D01*
G01X149552D01*
G02Y1349690I0J1503D01*
G37*
G36*
G01X137312D02*
X140712D01*
G02Y1346684I0J-1503D01*
G01X137312D01*
G02Y1349690I0J1503D01*
G37*
G36*
G01X76112Y1361602D02*
X79512D01*
G02Y1358596I0J-1503D01*
G01X76112D01*
G02Y1361602I0J1503D01*
G37*
G36*
G01X174032Y1385800D02*
X177432D01*
G02Y1382794I0J-1503D01*
G01X174032D01*
G02Y1385800I0J1503D01*
G37*
G36*
G01X125072Y1409998D02*
X128472D01*
G02Y1406992I0J-1503D01*
G01X125072D01*
G02Y1409998I0J1503D01*
G37*
G36*
G01Y1398086D02*
X128472D01*
G02Y1395080I0J-1503D01*
G01X125072D01*
G02Y1398086I0J1503D01*
G37*
G36*
G01Y1373888D02*
X128472D01*
G02Y1370882I0J-1503D01*
G01X125072D01*
G02Y1373888I0J1503D01*
G37*
G36*
G01Y1385800D02*
X128472D01*
G02Y1382794I0J-1503D01*
G01X125072D01*
G02Y1385800I0J1503D01*
G37*
G36*
G01X1571530Y1361602D02*
X1574930D01*
G02Y1358596I0J-1503D01*
G01X1571530D01*
G02Y1361602I0J1503D01*
G37*
G36*
G01X100592Y1385800D02*
X103992D01*
G02Y1382794I0J-1503D01*
G01X100592D01*
G02Y1385800I0J1503D01*
G37*
G36*
G01X76112Y1373888D02*
X79512D01*
G02Y1370882I0J-1503D01*
G01X76112D01*
G02Y1373888I0J1503D01*
G37*
G36*
G01X88352Y1409998D02*
X91752D01*
G02Y1406992I0J-1503D01*
G01X88352D01*
G02Y1409998I0J1503D01*
G37*
G36*
G01X149552D02*
X152952D01*
G02Y1406992I0J-1503D01*
G01X149552D01*
G02Y1409998I0J1503D01*
G37*
G36*
G01X137312Y1373888D02*
X140712D01*
G02Y1370882I0J-1503D01*
G01X137312D01*
G02Y1373888I0J1503D01*
G37*
G36*
G01X253863Y1385800D02*
X257263D01*
G02Y1382794I0J-1503D01*
G01X253863D01*
G02Y1385800I0J1503D01*
G37*
G36*
G01X186272Y1409998D02*
X189672D01*
G02Y1406992I0J-1503D01*
G01X186272D01*
G02Y1409998I0J1503D01*
G37*
G36*
G01X125072Y1361602D02*
X128472D01*
G02Y1358596I0J-1503D01*
G01X125072D01*
G02Y1361602I0J1503D01*
G37*
G36*
G01Y1349690D02*
X128472D01*
G02Y1346684I0J-1503D01*
G01X125072D01*
G02Y1349690I0J1503D01*
G37*
G36*
G01X149552Y1373888D02*
X152952D01*
G02Y1370882I0J-1503D01*
G01X149552D01*
G02Y1373888I0J1503D01*
G37*
G36*
G01X174032Y1349690D02*
X177432D01*
G02Y1346684I0J-1503D01*
G01X174032D01*
G02Y1349690I0J1503D01*
G37*
G36*
G01Y1373888D02*
X177432D01*
G02Y1370882I0J-1503D01*
G01X174032D01*
G02Y1373888I0J1503D01*
G37*
G36*
G01X76112Y1385800D02*
X79512D01*
G02Y1382794I0J-1503D01*
G01X76112D01*
G02Y1385800I0J1503D01*
G37*
G36*
G01X1583770Y1349690D02*
X1587170D01*
G02Y1346684I0J-1503D01*
G01X1583770D01*
G02Y1349690I0J1503D01*
G37*
G36*
G01X1697078Y1385800D02*
X1700478D01*
G02Y1382794I0J-1503D01*
G01X1697078D01*
G02Y1385800I0J1503D01*
G37*
G36*
G01X88352Y1361602D02*
X91752D01*
G02Y1358596I0J-1503D01*
G01X88352D01*
G02Y1361602I0J1503D01*
G37*
G36*
G01Y1349690D02*
X91752D01*
G02Y1346684I0J-1503D01*
G01X88352D01*
G02Y1349690I0J1503D01*
G37*
G36*
G01X1697078Y1409998D02*
X1700478D01*
G02Y1406992I0J-1503D01*
G01X1697078D01*
G02Y1409998I0J1503D01*
G37*
G36*
G01X112832Y1373888D02*
X116232D01*
G02Y1370882I0J-1503D01*
G01X112832D01*
G02Y1373888I0J1503D01*
G37*
G36*
G01Y1409998D02*
X116232D01*
G02Y1406992I0J-1503D01*
G01X112832D01*
G02Y1409998I0J1503D01*
G37*
G36*
G01X100592D02*
X103992D01*
G02Y1406992I0J-1503D01*
G01X100592D01*
G02Y1409998I0J1503D01*
G37*
G36*
G01X724208Y1385800D02*
X727608D01*
G02Y1382794I0J-1503D01*
G01X724208D01*
G02Y1385800I0J1503D01*
G37*
G36*
G01X88352D02*
X91752D01*
G02Y1382794I0J-1503D01*
G01X88352D01*
G02Y1385800I0J1503D01*
G37*
G36*
G01X760928Y1361602D02*
X764328D01*
G02Y1358596I0J-1503D01*
G01X760928D01*
G02Y1361602I0J1503D01*
G37*
G36*
G01X100592Y1373888D02*
X103992D01*
G02Y1370882I0J-1503D01*
G01X100592D01*
G02Y1373888I0J1503D01*
G37*
G36*
G01X137312Y1398086D02*
X140712D01*
G02Y1395080I0J-1503D01*
G01X137312D01*
G02Y1398086I0J1503D01*
G37*
G36*
G01Y1409998D02*
X140712D01*
G02Y1406992I0J-1503D01*
G01X137312D01*
G02Y1409998I0J1503D01*
G37*
G36*
G01X112832Y1385800D02*
X116232D01*
G02Y1382794I0J-1503D01*
G01X112832D01*
G02Y1385800I0J1503D01*
G37*
G36*
G01X663008Y1361602D02*
X666408D01*
G02Y1358596I0J-1503D01*
G01X663008D01*
G02Y1361602I0J1503D01*
G37*
G36*
G01X100592Y1398086D02*
X103992D01*
G02Y1395080I0J-1503D01*
G01X100592D01*
G02Y1398086I0J1503D01*
G37*
G36*
G01X748688Y1385800D02*
X752088D01*
G02Y1382794I0J-1503D01*
G01X748688D01*
G02Y1385800I0J1503D01*
G37*
G36*
G01X1352726Y1409998D02*
X1356126D01*
G02Y1406992I0J-1503D01*
G01X1352726D01*
G02Y1409998I0J1503D01*
G37*
G36*
G01X100592Y1361602D02*
X103992D01*
G02Y1358596I0J-1503D01*
G01X100592D01*
G02Y1361602I0J1503D01*
G37*
G36*
G01X112832D02*
X116232D01*
G02Y1358596I0J-1503D01*
G01X112832D01*
G02Y1361602I0J1503D01*
G37*
G36*
G01X88352Y1398086D02*
X91752D01*
G02Y1395080I0J-1503D01*
G01X88352D01*
G02Y1398086I0J1503D01*
G37*
G36*
G01X1660358Y1361602D02*
X1663758D01*
G02Y1358596I0J-1503D01*
G01X1660358D01*
G02Y1361602I0J1503D01*
G37*
G36*
G01X1066953Y1349690D02*
X1070353D01*
G02Y1346684I0J-1503D01*
G01X1066953D01*
G02Y1349690I0J1503D01*
G37*
G36*
G01X663008D02*
X666408D01*
G02Y1346684I0J-1503D01*
G01X663008D01*
G02Y1349690I0J1503D01*
G37*
G36*
G01X1583770Y1361602D02*
X1587170D01*
G02Y1358596I0J-1503D01*
G01X1583770D01*
G02Y1361602I0J1503D01*
G37*
G36*
G01X1571530Y1398086D02*
X1574930D01*
G02Y1395080I0J-1503D01*
G01X1571530D01*
G02Y1398086I0J1503D01*
G37*
G36*
G01X1559290Y1361602D02*
X1562690D01*
G02Y1358596I0J-1503D01*
G01X1559290D01*
G02Y1361602I0J1503D01*
G37*
G36*
G01Y1373888D02*
X1562690D01*
G02Y1370882I0J-1503D01*
G01X1559290D01*
G02Y1373888I0J1503D01*
G37*
G36*
G01X1623638Y1385800D02*
X1627038D01*
G02Y1382794I0J-1503D01*
G01X1623638D01*
G02Y1385800I0J1503D01*
G37*
G36*
G01X76112Y1349690D02*
X79512D01*
G02Y1346684I0J-1503D01*
G01X76112D01*
G02Y1349690I0J1503D01*
G37*
G36*
G01X1066953Y1361602D02*
X1070353D01*
G02Y1358596I0J-1503D01*
G01X1066953D01*
G02Y1361602I0J1503D01*
G37*
G36*
G01X1547050Y1385800D02*
X1550450D01*
G02Y1382794I0J-1503D01*
G01X1547050D01*
G02Y1385800I0J1503D01*
G37*
G36*
G01X1672598Y1349690D02*
X1675998D01*
G02Y1346684I0J-1503D01*
G01X1672598D01*
G02Y1349690I0J1503D01*
G37*
G36*
G01X1660358D02*
X1663758D01*
G02Y1346684I0J-1503D01*
G01X1660358D01*
G02Y1349690I0J1503D01*
G37*
G36*
G01X1672598Y1361602D02*
X1675998D01*
G02Y1358596I0J-1503D01*
G01X1672598D01*
G02Y1361602I0J1503D01*
G37*
G36*
G01X1709318Y1349690D02*
X1712718D01*
G02Y1346684I0J-1503D01*
G01X1709318D01*
G02Y1349690I0J1503D01*
G37*
G36*
G01X1697078D02*
X1700478D01*
G02Y1346684I0J-1503D01*
G01X1697078D01*
G02Y1349690I0J1503D01*
G37*
G36*
G01X1684838Y1385800D02*
X1688238D01*
G02Y1382794I0J-1503D01*
G01X1684838D01*
G02Y1385800I0J1503D01*
G37*
G36*
G01X1709318Y1361602D02*
X1712718D01*
G02Y1358596I0J-1503D01*
G01X1709318D01*
G02Y1361602I0J1503D01*
G37*
G36*
G01X1697078D02*
X1700478D01*
G02Y1358596I0J-1503D01*
G01X1697078D01*
G02Y1361602I0J1503D01*
G37*
G36*
G01X1684838D02*
X1688238D01*
G02Y1358596I0J-1503D01*
G01X1684838D01*
G02Y1361602I0J1503D01*
G37*
G36*
G01Y1373888D02*
X1688238D01*
G02Y1370882I0J-1503D01*
G01X1684838D01*
G02Y1373888I0J1503D01*
G37*
G36*
G01Y1398086D02*
X1688238D01*
G02Y1395080I0J-1503D01*
G01X1684838D01*
G02Y1398086I0J1503D01*
G37*
G36*
G01X1066953Y1373888D02*
X1070353D01*
G02Y1370882I0J-1503D01*
G01X1066953D01*
G02Y1373888I0J1503D01*
G37*
G36*
G01Y1385800D02*
X1070353D01*
G02Y1382794I0J-1503D01*
G01X1066953D01*
G02Y1385800I0J1503D01*
G37*
G36*
G01X1547050Y1398086D02*
X1550450D01*
G02Y1395080I0J-1503D01*
G01X1547050D01*
G02Y1398086I0J1503D01*
G37*
G36*
G01X549168Y783102D02*
G02Y780098I0J-1502D01*
G01X545813D01*
X545808D01*
G02X545944Y783092I-38J1502D01*
G01X545956Y783090D01*
X548978D01*
X548990Y783092D01*
G02X549168Y783102I173J-1492D01*
G37*
G36*
G01X278343Y1349690D02*
X281743D01*
G02Y1346684I0J-1503D01*
G01X278343D01*
G02Y1349690I0J1503D01*
G37*
G36*
G01X945982Y888540D02*
X949382D01*
G02Y884936I0J-1802D01*
G01X945982D01*
G02Y888540I0J1802D01*
G37*
G36*
G01X1684838Y1349690D02*
X1688238D01*
G02Y1346684I0J-1503D01*
G01X1684838D01*
G02Y1349690I0J1503D01*
G37*
G36*
G01X1571530Y1409998D02*
X1574930D01*
G02Y1406992I0J-1503D01*
G01X1571530D01*
G02Y1409998I0J1503D01*
G37*
G36*
G01X1473610Y1373888D02*
X1477010D01*
G02Y1370882I0J-1503D01*
G01X1473610D01*
G02Y1373888I0J1503D01*
G37*
G36*
G01X1498090Y1398086D02*
X1501490D01*
G02Y1395080I0J-1503D01*
G01X1498090D01*
G02Y1398086I0J1503D01*
G37*
G36*
G01Y1385800D02*
X1501490D01*
G02Y1382794I0J-1503D01*
G01X1498090D01*
G02Y1385800I0J1503D01*
G37*
G36*
G01X1510330Y1409998D02*
X1513730D01*
G02Y1406992I0J-1503D01*
G01X1510330D01*
G02Y1409998I0J1503D01*
G37*
G36*
G01X1522570Y1349690D02*
X1525970D01*
G02Y1346684I0J-1503D01*
G01X1522570D01*
G02Y1349690I0J1503D01*
G37*
G36*
G01X146948Y1135604D02*
X143208D01*
G02Y1138210I0J1303D01*
G01X146948D01*
G02Y1135604I0J-1303D01*
G37*
G36*
G01X165649Y1131864D02*
X161909D01*
G02Y1134470I0J1303D01*
G01X165649D01*
G02Y1131864I0J-1303D01*
G37*
G36*
G01X154429D02*
X150689D01*
G02Y1134470I0J1303D01*
G01X154429D01*
G02Y1131864I0J-1303D01*
G37*
G36*
G01X173129Y1135604D02*
X169389D01*
G02Y1138210I0J1303D01*
G01X173129D01*
G02Y1135604I0J-1303D01*
G37*
G36*
G01X440402Y1361602D02*
X443802D01*
G02Y1358596I0J-1503D01*
G01X440402D01*
G02Y1361602I0J1503D01*
G37*
G36*
G01Y1349690D02*
X443802D01*
G02Y1346684I0J-1503D01*
G01X440402D01*
G02Y1349690I0J1503D01*
G37*
G36*
G01X452642Y1361602D02*
X456042D01*
G02Y1358596I0J-1503D01*
G01X452642D01*
G02Y1361602I0J1503D01*
G37*
G36*
G01Y1349690D02*
X456042D01*
G02Y1346684I0J-1503D01*
G01X452642D01*
G02Y1349690I0J1503D01*
G37*
G36*
G01X501602Y1385800D02*
X505002D01*
G02Y1382794I0J-1503D01*
G01X501602D01*
G02Y1385800I0J1503D01*
G37*
G36*
G01X513842D02*
X517242D01*
G02Y1382794I0J-1503D01*
G01X513842D01*
G02Y1385800I0J1503D01*
G37*
G36*
G01Y1373888D02*
X517242D01*
G02Y1370882I0J-1503D01*
G01X513842D01*
G02Y1373888I0J1503D01*
G37*
G36*
G01X501602D02*
X505002D01*
G02Y1370882I0J-1503D01*
G01X501602D01*
G02Y1373888I0J1503D01*
G37*
G36*
G01X464882Y1349690D02*
X468282D01*
G02Y1346684I0J-1503D01*
G01X464882D01*
G02Y1349690I0J1503D01*
G37*
G36*
G01X477122D02*
X480522D01*
G02Y1346684I0J-1503D01*
G01X477122D01*
G02Y1349690I0J1503D01*
G37*
G36*
G01X526082Y1385800D02*
X529482D01*
G02Y1382794I0J-1503D01*
G01X526082D01*
G02Y1385800I0J1503D01*
G37*
G36*
G01X538322D02*
X541722D01*
G02Y1382794I0J-1503D01*
G01X538322D01*
G02Y1385800I0J1503D01*
G37*
G36*
G01X526082Y1373888D02*
X529482D01*
G02Y1370882I0J-1503D01*
G01X526082D01*
G02Y1373888I0J1503D01*
G37*
G36*
G01X538322D02*
X541722D01*
G02Y1370882I0J-1503D01*
G01X538322D01*
G02Y1373888I0J1503D01*
G37*
G36*
G01X464882Y1361602D02*
X468282D01*
G02Y1358596I0J-1503D01*
G01X464882D01*
G02Y1361602I0J1503D01*
G37*
G36*
G01X477122D02*
X480522D01*
G02Y1358596I0J-1503D01*
G01X477122D01*
G02Y1361602I0J1503D01*
G37*
G36*
G01X489362Y1349690D02*
X492762D01*
G02Y1346684I0J-1503D01*
G01X489362D01*
G02Y1349690I0J1503D01*
G37*
G36*
G01X440402Y1373888D02*
X443802D01*
G02Y1370882I0J-1503D01*
G01X440402D01*
G02Y1373888I0J1503D01*
G37*
G36*
G01X550562Y1385800D02*
X553962D01*
G02Y1382794I0J-1503D01*
G01X550562D01*
G02Y1385800I0J1503D01*
G37*
G36*
G01Y1373888D02*
X553962D01*
G02Y1370882I0J-1503D01*
G01X550562D01*
G02Y1373888I0J1503D01*
G37*
G36*
G01X489362Y1361602D02*
X492762D01*
G02Y1358596I0J-1503D01*
G01X489362D01*
G02Y1361602I0J1503D01*
G37*
G36*
G01X440402Y1385800D02*
X443802D01*
G02Y1382794I0J-1503D01*
G01X440402D01*
G02Y1385800I0J1503D01*
G37*
G36*
G01X452642Y1373888D02*
X456042D01*
G02Y1370882I0J-1503D01*
G01X452642D01*
G02Y1373888I0J1503D01*
G37*
G36*
G01X562802Y1385800D02*
X566202D01*
G02Y1382794I0J-1503D01*
G01X562802D01*
G02Y1385800I0J1503D01*
G37*
G36*
G01X452642Y1409998D02*
X456042D01*
G02Y1406992I0J-1503D01*
G01X452642D01*
G02Y1409998I0J1503D01*
G37*
G36*
G01Y1398086D02*
X456042D01*
G02Y1395080I0J-1503D01*
G01X452642D01*
G02Y1398086I0J1503D01*
G37*
G36*
G01X562802Y1373888D02*
X566202D01*
G02Y1370882I0J-1503D01*
G01X562802D01*
G02Y1373888I0J1503D01*
G37*
G36*
G01X452642Y1385800D02*
X456042D01*
G02Y1382794I0J-1503D01*
G01X452642D01*
G02Y1385800I0J1503D01*
G37*
G36*
G01X464882Y1409998D02*
X468282D01*
G02Y1406992I0J-1503D01*
G01X464882D01*
G02Y1409998I0J1503D01*
G37*
G36*
G01Y1398086D02*
X468282D01*
G02Y1395080I0J-1503D01*
G01X464882D01*
G02Y1398086I0J1503D01*
G37*
G36*
G01Y1385800D02*
X468282D01*
G02Y1382794I0J-1503D01*
G01X464882D01*
G02Y1385800I0J1503D01*
G37*
G36*
G01X477122D02*
X480522D01*
G02Y1382794I0J-1503D01*
G01X477122D01*
G02Y1385800I0J1503D01*
G37*
G36*
G01Y1373888D02*
X480522D01*
G02Y1370882I0J-1503D01*
G01X477122D01*
G02Y1373888I0J1503D01*
G37*
G36*
G01X464882D02*
X468282D01*
G02Y1370882I0J-1503D01*
G01X464882D01*
G02Y1373888I0J1503D01*
G37*
G36*
G01X489362D02*
X492762D01*
G02Y1370882I0J-1503D01*
G01X489362D01*
G02Y1373888I0J1503D01*
G37*
G36*
G01Y1409998D02*
X492762D01*
G02Y1406992I0J-1503D01*
G01X489362D01*
G02Y1409998I0J1503D01*
G37*
G36*
G01Y1398086D02*
X492762D01*
G02Y1395080I0J-1503D01*
G01X489362D01*
G02Y1398086I0J1503D01*
G37*
G36*
G01X477122Y1409998D02*
X480522D01*
G02Y1406992I0J-1503D01*
G01X477122D01*
G02Y1409998I0J1503D01*
G37*
G36*
G01Y1398086D02*
X480522D01*
G02Y1395080I0J-1503D01*
G01X477122D01*
G02Y1398086I0J1503D01*
G37*
G36*
G01X489362Y1385800D02*
X492762D01*
G02Y1382794I0J-1503D01*
G01X489362D01*
G02Y1385800I0J1503D01*
G37*
G36*
G01X501602Y1361602D02*
X505002D01*
G02Y1358596I0J-1503D01*
G01X501602D01*
G02Y1361602I0J1503D01*
G37*
G36*
G01X513842D02*
X517242D01*
G02Y1358596I0J-1503D01*
G01X513842D01*
G02Y1361602I0J1503D01*
G37*
G36*
G01X501602Y1349690D02*
X505002D01*
G02Y1346684I0J-1503D01*
G01X501602D01*
G02Y1349690I0J1503D01*
G37*
G36*
G01X513842D02*
X517242D01*
G02Y1346684I0J-1503D01*
G01X513842D01*
G02Y1349690I0J1503D01*
G37*
G36*
G01X501602Y1398086D02*
X505002D01*
G02Y1395080I0J-1503D01*
G01X501602D01*
G02Y1398086I0J1503D01*
G37*
G36*
G01Y1409998D02*
X505002D01*
G02Y1406992I0J-1503D01*
G01X501602D01*
G02Y1409998I0J1503D01*
G37*
G36*
G01X526082Y1361602D02*
X529482D01*
G02Y1358596I0J-1503D01*
G01X526082D01*
G02Y1361602I0J1503D01*
G37*
G36*
G01Y1349690D02*
X529482D01*
G02Y1346684I0J-1503D01*
G01X526082D01*
G02Y1349690I0J1503D01*
G37*
G36*
G01X513842Y1398086D02*
X517242D01*
G02Y1395080I0J-1503D01*
G01X513842D01*
G02Y1398086I0J1503D01*
G37*
G36*
G01X526082Y1409998D02*
X529482D01*
G02Y1406992I0J-1503D01*
G01X526082D01*
G02Y1409998I0J1503D01*
G37*
G36*
G01X513842D02*
X517242D01*
G02Y1406992I0J-1503D01*
G01X513842D01*
G02Y1409998I0J1503D01*
G37*
G36*
G01X526082Y1398086D02*
X529482D01*
G02Y1395080I0J-1503D01*
G01X526082D01*
G02Y1398086I0J1503D01*
G37*
G36*
G01X538322Y1361602D02*
X541722D01*
G02Y1358596I0J-1503D01*
G01X538322D01*
G02Y1361602I0J1503D01*
G37*
G36*
G01X550562D02*
X553962D01*
G02Y1358596I0J-1503D01*
G01X550562D01*
G02Y1361602I0J1503D01*
G37*
G36*
G01X538322Y1349690D02*
X541722D01*
G02Y1346684I0J-1503D01*
G01X538322D01*
G02Y1349690I0J1503D01*
G37*
G36*
G01X550562D02*
X553962D01*
G02Y1346684I0J-1503D01*
G01X550562D01*
G02Y1349690I0J1503D01*
G37*
G36*
G01X538322Y1398086D02*
X541722D01*
G02Y1395080I0J-1503D01*
G01X538322D01*
G02Y1398086I0J1503D01*
G37*
G36*
G01Y1409998D02*
X541722D01*
G02Y1406992I0J-1503D01*
G01X538322D01*
G02Y1409998I0J1503D01*
G37*
G36*
G01X562802Y1361602D02*
X566202D01*
G02Y1358596I0J-1503D01*
G01X562802D01*
G02Y1361602I0J1503D01*
G37*
G36*
G01Y1349690D02*
X566202D01*
G02Y1346684I0J-1503D01*
G01X562802D01*
G02Y1349690I0J1503D01*
G37*
G36*
G01X550562Y1398086D02*
X553962D01*
G02Y1395080I0J-1503D01*
G01X550562D01*
G02Y1398086I0J1503D01*
G37*
G36*
G01X562802D02*
X566202D01*
G02Y1395080I0J-1503D01*
G01X562802D01*
G02Y1398086I0J1503D01*
G37*
G36*
G01X550562Y1409998D02*
X553962D01*
G02Y1406992I0J-1503D01*
G01X550562D01*
G02Y1409998I0J1503D01*
G37*
G36*
G01X562802D02*
X566202D01*
G02Y1406992I0J-1503D01*
G01X562802D01*
G02Y1409998I0J1503D01*
G37*
G36*
G01X650768Y1361602D02*
X654168D01*
G02Y1358596I0J-1503D01*
G01X650768D01*
G02Y1361602I0J1503D01*
G37*
G36*
G01Y1349690D02*
X654168D01*
G02Y1346684I0J-1503D01*
G01X650768D01*
G02Y1349690I0J1503D01*
G37*
G36*
G01X626288Y1409998D02*
X629688D01*
G02Y1406992I0J-1503D01*
G01X626288D01*
G02Y1409998I0J1503D01*
G37*
G36*
G01X638528Y1385800D02*
X641928D01*
G02Y1382794I0J-1503D01*
G01X638528D01*
G02Y1385800I0J1503D01*
G37*
G36*
G01Y1373888D02*
X641928D01*
G02Y1370882I0J-1503D01*
G01X638528D01*
G02Y1373888I0J1503D01*
G37*
G36*
G01X626288Y1398086D02*
X629688D01*
G02Y1395080I0J-1503D01*
G01X626288D01*
G02Y1398086I0J1503D01*
G37*
G36*
G01X675248Y1361602D02*
X678648D01*
G02Y1358596I0J-1503D01*
G01X675248D01*
G02Y1361602I0J1503D01*
G37*
G36*
G01X650768Y1385800D02*
X654168D01*
G02Y1382794I0J-1503D01*
G01X650768D01*
G02Y1385800I0J1503D01*
G37*
G36*
G01X675248Y1349690D02*
X678648D01*
G02Y1346684I0J-1503D01*
G01X675248D01*
G02Y1349690I0J1503D01*
G37*
G36*
G01X650768Y1373888D02*
X654168D01*
G02Y1370882I0J-1503D01*
G01X650768D01*
G02Y1373888I0J1503D01*
G37*
G36*
G01X638528Y1409998D02*
X641928D01*
G02Y1406992I0J-1503D01*
G01X638528D01*
G02Y1409998I0J1503D01*
G37*
G36*
G01Y1398086D02*
X641928D01*
G02Y1395080I0J-1503D01*
G01X638528D01*
G02Y1398086I0J1503D01*
G37*
G36*
G01X687488Y1361602D02*
X690888D01*
G02Y1358596I0J-1503D01*
G01X687488D01*
G02Y1361602I0J1503D01*
G37*
G36*
G01Y1349690D02*
X690888D01*
G02Y1346684I0J-1503D01*
G01X687488D01*
G02Y1349690I0J1503D01*
G37*
G36*
G01X663008Y1385800D02*
X666408D01*
G02Y1382794I0J-1503D01*
G01X663008D01*
G02Y1385800I0J1503D01*
G37*
G36*
G01X650768Y1409998D02*
X654168D01*
G02Y1406992I0J-1503D01*
G01X650768D01*
G02Y1409998I0J1503D01*
G37*
G36*
G01X663008Y1373888D02*
X666408D01*
G02Y1370882I0J-1503D01*
G01X663008D01*
G02Y1373888I0J1503D01*
G37*
G36*
G01X650768Y1398086D02*
X654168D01*
G02Y1395080I0J-1503D01*
G01X650768D01*
G02Y1398086I0J1503D01*
G37*
G36*
G01X699728Y1361602D02*
X703128D01*
G02Y1358596I0J-1503D01*
G01X699728D01*
G02Y1361602I0J1503D01*
G37*
G36*
G01X687488Y1385800D02*
X690888D01*
G02Y1382794I0J-1503D01*
G01X687488D01*
G02Y1385800I0J1503D01*
G37*
G36*
G01X699728Y1349690D02*
X703128D01*
G02Y1346684I0J-1503D01*
G01X699728D01*
G02Y1349690I0J1503D01*
G37*
G36*
G01X687488Y1373888D02*
X690888D01*
G02Y1370882I0J-1503D01*
G01X687488D01*
G02Y1373888I0J1503D01*
G37*
G36*
G01X675248Y1385800D02*
X678648D01*
G02Y1382794I0J-1503D01*
G01X675248D01*
G02Y1385800I0J1503D01*
G37*
G36*
G01Y1373888D02*
X678648D01*
G02Y1370882I0J-1503D01*
G01X675248D01*
G02Y1373888I0J1503D01*
G37*
G36*
G01X711968Y1349690D02*
X715368D01*
G02Y1346684I0J-1503D01*
G01X711968D01*
G02Y1349690I0J1503D01*
G37*
G36*
G01Y1361602D02*
X715368D01*
G02Y1358596I0J-1503D01*
G01X711968D01*
G02Y1361602I0J1503D01*
G37*
G36*
G01X663008Y1409998D02*
X666408D01*
G02Y1406992I0J-1503D01*
G01X663008D01*
G02Y1409998I0J1503D01*
G37*
G36*
G01X699728Y1385800D02*
X703128D01*
G02Y1382794I0J-1503D01*
G01X699728D01*
G02Y1385800I0J1503D01*
G37*
G36*
G01Y1373888D02*
X703128D01*
G02Y1370882I0J-1503D01*
G01X699728D01*
G02Y1373888I0J1503D01*
G37*
G36*
G01X663008Y1398086D02*
X666408D01*
G02Y1395080I0J-1503D01*
G01X663008D01*
G02Y1398086I0J1503D01*
G37*
G36*
G01X724208Y1397992D02*
X727608D01*
G02Y1394986I0J-1503D01*
G01X724208D01*
G02Y1397992I0J1503D01*
G37*
G36*
G01Y1349690D02*
X727608D01*
G02Y1346684I0J-1503D01*
G01X724208D01*
G02Y1349690I0J1503D01*
G37*
G36*
G01X675248Y1409998D02*
X678648D01*
G02Y1406992I0J-1503D01*
G01X675248D01*
G02Y1409998I0J1503D01*
G37*
G36*
G01Y1398086D02*
X678648D01*
G02Y1395080I0J-1503D01*
G01X675248D01*
G02Y1398086I0J1503D01*
G37*
G36*
G01X724208Y1361602D02*
X727608D01*
G02Y1358596I0J-1503D01*
G01X724208D01*
G02Y1361602I0J1503D01*
G37*
G36*
G01Y1409904D02*
X727608D01*
G02Y1406898I0J-1503D01*
G01X724208D01*
G02Y1409904I0J1503D01*
G37*
G36*
G01X736448Y1349690D02*
X739848D01*
G02Y1346684I0J-1503D01*
G01X736448D01*
G02Y1349690I0J1503D01*
G37*
G36*
G01X711968Y1373888D02*
X715368D01*
G02Y1370882I0J-1503D01*
G01X711968D01*
G02Y1373888I0J1503D01*
G37*
G36*
G01X736448Y1361602D02*
X739848D01*
G02Y1358596I0J-1503D01*
G01X736448D01*
G02Y1361602I0J1503D01*
G37*
G36*
G01X711968Y1385800D02*
X715368D01*
G02Y1382794I0J-1503D01*
G01X711968D01*
G02Y1385800I0J1503D01*
G37*
G36*
G01X687488Y1409998D02*
X690888D01*
G02Y1406992I0J-1503D01*
G01X687488D01*
G02Y1409998I0J1503D01*
G37*
G36*
G01Y1398086D02*
X690888D01*
G02Y1395080I0J-1503D01*
G01X687488D01*
G02Y1398086I0J1503D01*
G37*
G36*
G01X736448Y1373888D02*
X739848D01*
G02Y1370882I0J-1503D01*
G01X736448D01*
G02Y1373888I0J1503D01*
G37*
G36*
G01X748688Y1349690D02*
X752088D01*
G02Y1346684I0J-1503D01*
G01X748688D01*
G02Y1349690I0J1503D01*
G37*
G36*
G01X724208Y1373888D02*
X727608D01*
G02Y1370882I0J-1503D01*
G01X724208D01*
G02Y1373888I0J1503D01*
G37*
G36*
G01X736448Y1385800D02*
X739848D01*
G02Y1382794I0J-1503D01*
G01X736448D01*
G02Y1385800I0J1503D01*
G37*
G36*
G01X748688Y1361602D02*
X752088D01*
G02Y1358596I0J-1503D01*
G01X748688D01*
G02Y1361602I0J1503D01*
G37*
G36*
G01X736448Y1409904D02*
X739848D01*
G02Y1406898I0J-1503D01*
G01X736448D01*
G02Y1409904I0J1503D01*
G37*
G36*
G01Y1397992D02*
X739848D01*
G02Y1394986I0J-1503D01*
G01X736448D01*
G02Y1397992I0J1503D01*
G37*
G36*
G01X699728Y1409998D02*
X703128D01*
G02Y1406992I0J-1503D01*
G01X699728D01*
G02Y1409998I0J1503D01*
G37*
G36*
G01Y1398086D02*
X703128D01*
G02Y1395080I0J-1503D01*
G01X699728D01*
G02Y1398086I0J1503D01*
G37*
G36*
G01X748688Y1373888D02*
X752088D01*
G02Y1370882I0J-1503D01*
G01X748688D01*
G02Y1373888I0J1503D01*
G37*
G36*
G01X773168Y1349690D02*
X776568D01*
G02Y1346684I0J-1503D01*
G01X773168D01*
G02Y1349690I0J1503D01*
G37*
G36*
G01X760928D02*
X764328D01*
G02Y1346684I0J-1503D01*
G01X760928D01*
G02Y1349690I0J1503D01*
G37*
G36*
G01X711968Y1409998D02*
X715368D01*
G02Y1406992I0J-1503D01*
G01X711968D01*
G02Y1409998I0J1503D01*
G37*
G36*
G01Y1398086D02*
X715368D01*
G02Y1395080I0J-1503D01*
G01X711968D01*
G02Y1398086I0J1503D01*
G37*
G36*
G01X773168Y1361602D02*
X776568D01*
G02Y1358596I0J-1503D01*
G01X773168D01*
G02Y1361602I0J1503D01*
G37*
G36*
G01X760928Y1373888D02*
X764328D01*
G02Y1370882I0J-1503D01*
G01X760928D01*
G02Y1373888I0J1503D01*
G37*
G36*
G01Y1385800D02*
X764328D01*
G02Y1382794I0J-1503D01*
G01X760928D01*
G02Y1385800I0J1503D01*
G37*
G36*
G01X149552D02*
X152952D01*
G02Y1382794I0J-1503D01*
G01X149552D01*
G02Y1385800I0J1503D01*
G37*
G36*
G01Y1361602D02*
X152952D01*
G02Y1358596I0J-1503D01*
G01X149552D01*
G02Y1361602I0J1503D01*
G37*
G36*
G01X253863Y1373888D02*
X257263D01*
G02Y1370882I0J-1503D01*
G01X253863D01*
G02Y1373888I0J1503D01*
G37*
G36*
G01X198512D02*
X201912D01*
G02Y1370882I0J-1503D01*
G01X198512D01*
G02Y1373888I0J1503D01*
G37*
G36*
G01Y1409998D02*
X201912D01*
G02Y1406992I0J-1503D01*
G01X198512D01*
G02Y1409998I0J1503D01*
G37*
G36*
G01X364023Y1349690D02*
X367423D01*
G02Y1346684I0J-1503D01*
G01X364023D01*
G02Y1349690I0J1503D01*
G37*
G54D76*
X978614Y1210568D03*
Y1214838D03*
X914637Y1210568D03*
Y1214838D03*
X70947Y1201565D03*
Y1205835D03*
X1822594Y1211054D03*
Y1215324D03*
G54D82*
X320866Y1221062D03*
X313385Y1209842D03*
X320866Y1213582D03*
X324606Y1221062D03*
X313385Y1217322D03*
Y1247243D03*
X320866D03*
X317125Y1250984D03*
X313385Y1243503D03*
X324606Y1247243D03*
X317125Y1254724D03*
X320866Y1198621D03*
X313385Y1202362D03*
X324606Y1198621D03*
X317125Y1202362D03*
X320866Y1206102D03*
X324606D03*
X317125Y1217322D03*
Y1209842D03*
X324606Y1213582D03*
X294685Y1250984D03*
X298425Y1247243D03*
X309645Y1250984D03*
X298425Y1243503D03*
X305905D03*
Y1247243D03*
X302165Y1250984D03*
X294685Y1254724D03*
X309645D03*
X302165D03*
X290944Y1247243D03*
Y1243503D03*
X219881Y1232283D03*
Y1236023D03*
X223622Y1224803D03*
X227362Y1232283D03*
X223622Y1228543D03*
X227362Y1236023D03*
X204921Y1232283D03*
X201181Y1224803D03*
X212401Y1232283D03*
X208661Y1228543D03*
X212401Y1236023D03*
X216141Y1224803D03*
X208661D03*
X201181Y1228543D03*
X216141D03*
X204921Y1236023D03*
X197440D03*
X186220Y1224803D03*
X193700Y1228543D03*
X197440Y1232283D03*
X189960Y1236023D03*
X186220Y1228543D03*
X193700Y1224803D03*
X189960Y1232283D03*
X178740Y1228543D03*
X171259Y1224803D03*
X182480Y1236023D03*
Y1232283D03*
X174999D03*
X171259Y1228543D03*
X178740Y1224803D03*
X174999Y1236023D03*
X1085432Y1224803D03*
Y1228543D03*
X1089172Y1232283D03*
Y1236023D03*
X1092913Y1224803D03*
Y1228543D03*
X1100393Y1224803D03*
Y1228543D03*
X1104133Y1236023D03*
Y1232283D03*
X1107873Y1228543D03*
Y1224803D03*
X1096653Y1232283D03*
Y1236023D03*
X1115354Y1224803D03*
Y1228543D03*
X1119094Y1236023D03*
Y1232283D03*
X1122834Y1228543D03*
Y1224803D03*
X1126574Y1232283D03*
Y1236023D03*
X1111613Y1232283D03*
Y1236023D03*
X1130314Y1224803D03*
Y1228543D03*
X1141535Y1236023D03*
Y1232283D03*
X1134054Y1236023D03*
Y1232283D03*
X1137795Y1228543D03*
Y1224803D03*
X1205117Y1243503D03*
Y1247243D03*
X1220078Y1243503D03*
Y1247243D03*
X1223818Y1250984D03*
Y1254724D03*
X1216338D03*
Y1250984D03*
X1212598Y1247243D03*
Y1243503D03*
X1208858Y1250984D03*
Y1254724D03*
X1238779Y1247243D03*
X1235039D03*
X1231298Y1250984D03*
Y1254724D03*
X1227558Y1247243D03*
Y1243503D03*
X1238779Y1198621D03*
X1235039D03*
X1231298Y1202362D03*
X1227558D03*
X1235039Y1206102D03*
X1238779D03*
Y1213582D03*
X1235039D03*
X1238779Y1221062D03*
X1235039D03*
X1231298Y1217322D03*
X1227558D03*
Y1209842D03*
X1231298D03*
X1542519Y1224803D03*
Y1228543D03*
X1546259Y1232283D03*
Y1236023D03*
Y1250984D03*
Y1254724D03*
X1542519Y1247243D03*
Y1243503D03*
X1550000Y1224803D03*
Y1228543D03*
Y1243503D03*
Y1247243D03*
X1557480Y1224803D03*
Y1228543D03*
X1561220Y1236023D03*
Y1232283D03*
X1564960Y1228543D03*
Y1224803D03*
X1553740Y1232283D03*
Y1236023D03*
X1557480Y1243503D03*
Y1247243D03*
X1561220Y1254724D03*
Y1250984D03*
X1564960Y1247243D03*
Y1243503D03*
X1553740Y1250984D03*
Y1254724D03*
X1568700Y1232283D03*
Y1236023D03*
Y1250984D03*
Y1254724D03*
X1632283Y1224803D03*
Y1228543D03*
Y1247243D03*
Y1243503D03*
X1636023Y1236023D03*
Y1232283D03*
X1639763Y1224803D03*
Y1228543D03*
X1643504Y1236023D03*
Y1232283D03*
X1647244Y1228543D03*
Y1224803D03*
X1636023Y1254724D03*
Y1250984D03*
X1639763Y1243503D03*
Y1247243D03*
X1643504Y1250984D03*
Y1254724D03*
X1647244Y1247243D03*
Y1243503D03*
X1654724Y1224803D03*
Y1228543D03*
X1658464Y1232283D03*
Y1236023D03*
X1650984D03*
Y1232283D03*
X1654724Y1247243D03*
X1658464Y1254724D03*
Y1250984D03*
X1654724Y1243503D03*
X1650984Y1254724D03*
Y1250984D03*
X639567Y1236023D03*
Y1232283D03*
X632086Y1236023D03*
Y1232283D03*
X635827Y1228543D03*
Y1224803D03*
X628346Y1228543D03*
Y1224803D03*
X639567Y1254724D03*
Y1250984D03*
X628346Y1243503D03*
Y1247243D03*
X632086Y1254724D03*
Y1250984D03*
X635827Y1247243D03*
Y1243503D03*
X654527Y1236023D03*
Y1232283D03*
X650787Y1224803D03*
Y1228543D03*
X647047Y1232283D03*
Y1236023D03*
X643307Y1228543D03*
Y1224803D03*
X654527Y1254724D03*
Y1250984D03*
X650787Y1243503D03*
Y1247243D03*
X647047Y1250984D03*
Y1254724D03*
X643307Y1247243D03*
Y1243503D03*
X718110Y1228543D03*
Y1224803D03*
Y1243503D03*
Y1247243D03*
X733071Y1224803D03*
Y1228543D03*
X736811Y1232283D03*
Y1236023D03*
X729331Y1232283D03*
Y1236023D03*
X725590Y1228543D03*
Y1224803D03*
X721850Y1232283D03*
Y1236023D03*
X733071Y1243503D03*
Y1247243D03*
X736811Y1250984D03*
Y1254724D03*
X729331D03*
Y1250984D03*
X725590Y1247243D03*
Y1243503D03*
X721850Y1250984D03*
Y1254724D03*
X744291Y1236023D03*
Y1232283D03*
X740551Y1228543D03*
Y1224803D03*
Y1243503D03*
X744291Y1250984D03*
Y1254724D03*
X740551Y1247243D03*
G54D80*
X970071Y1409152D03*
Y1365652D03*
G54D73*
X743337Y374862D03*
G54D66*
X1819042Y-27188D03*
Y-37188D03*
Y-47188D03*
X1753686Y-85978D03*
Y-75978D03*
Y-65978D03*
X1564906Y-27086D03*
Y-47086D03*
Y-37086D03*
X1574906Y-66006D03*
Y-86006D03*
Y-76006D03*
X1534542Y-27058D03*
Y-37058D03*
Y-47058D03*
X1499186Y-65978D03*
Y-75978D03*
Y-85978D03*
X1280406Y-26956D03*
Y-46956D03*
Y-36956D03*
X1320406Y-86006D03*
Y-66006D03*
Y-76006D03*
X1248042Y-26928D03*
X1242686Y-65978D03*
Y-75978D03*
Y-85978D03*
X993906Y-26826D03*
Y-46826D03*
Y-36826D03*
X1063906Y-66006D03*
Y-86006D03*
Y-76006D03*
X964542Y-26798D03*
Y-36798D03*
X939542D03*
Y-26798D03*
X989386Y-65978D03*
Y-75978D03*
X964386D03*
Y-65978D03*
X710406Y-26826D03*
Y-36826D03*
X735406D03*
Y-26826D03*
X830406Y-66006D03*
Y-76006D03*
X855406D03*
Y-66006D03*
X1248042Y-36928D03*
Y-46928D03*
X1018906Y-36826D03*
Y-46826D03*
X1217686Y-65978D03*
Y-75978D03*
X1305406Y-36956D03*
Y-46956D03*
Y-26956D03*
X1018906Y-26826D03*
X1217686Y-85978D03*
X1223042Y-26928D03*
Y-36928D03*
X1088906Y-76006D03*
Y-86006D03*
X1345406D03*
Y-76006D03*
Y-66006D03*
X1088906D03*
X1223042Y-46928D03*
X1474186Y-65978D03*
Y-75978D03*
Y-85978D03*
X1509542Y-27058D03*
Y-37058D03*
Y-47058D03*
X1794042Y-27188D03*
Y-37188D03*
Y-47188D03*
X1728686Y-65978D03*
Y-75978D03*
Y-85978D03*
X1589906Y-37086D03*
Y-47086D03*
Y-27086D03*
X1599906Y-76006D03*
Y-86006D03*
Y-66006D03*
G54D79*
X909360Y230906D03*
Y274606D03*
G54D74*
X1729390Y144095D03*
X1627028D03*
X1169941D03*
X1067579D03*
X965217D03*
X815217D03*
G54D72*
X640522Y630650D03*
X1657510Y374862D03*
X1554695Y630650D03*
X1200423Y374862D03*
X1097608Y630650D03*
X286250Y374862D03*
X183435Y630650D03*
G54D78*
X51043Y144095D03*
X57933Y66811D03*
X153405Y144095D03*
X160295Y66811D03*
X255767Y144095D03*
X262657Y66811D03*
X358129Y144095D03*
X365019Y66811D03*
X508130Y144095D03*
X515020Y66811D03*
X610492Y144095D03*
X617382Y66811D03*
X712854Y144095D03*
X719744Y66811D03*
X822106D03*
X972106D03*
X1074468D03*
X1176830D03*
X1272302Y144095D03*
X1279192Y66811D03*
X1422303Y144095D03*
X1429193Y66811D03*
X1524665Y144095D03*
X1531555Y66811D03*
X1633917D03*
X1736279D03*
G54D71*
X736447Y630650D03*
X1650620D03*
X1561585Y374862D03*
X1193533Y630650D03*
X1104498Y374862D03*
X279360Y630650D03*
X190325Y374862D03*
G54D70*
X1817323Y56693D03*
G54D69*
X924650Y1326119D03*
X370202Y1313064D03*
X559070Y686509D03*
X561570Y694509D03*
X559070Y702509D03*
X561570Y710509D03*
X559070Y718509D03*
X460950Y326485D03*
X463950Y334359D03*
X460950Y342233D03*
X463950Y350107D03*
X937000Y313983D03*
X66856Y105949D03*
X169218D03*
X271580D03*
X373942D03*
X893284Y235040D03*
X899352Y310261D03*
X1079748Y321042D03*
X1209184Y461917D03*
X1302896Y342096D03*
X1438116Y105949D03*
X1540478D03*
X1642840D03*
X1745202D03*
X1089096Y543562D03*
X1754906Y822634D03*
X917882Y326517D03*
X212980Y485254D03*
X205680Y478168D03*
X138290Y485260D03*
X148692Y478199D03*
X788482Y476118D03*
X778080Y483179D03*
X721092Y483210D03*
X713792Y476124D03*
X1245568Y476118D03*
X1235166Y483179D03*
X1178178Y483210D03*
X1170878Y476124D03*
X1584240Y485254D03*
X1576940Y478168D03*
X1519952Y478199D03*
X1509550Y485260D03*
X35688Y127128D03*
X28388Y120042D03*
Y134215D03*
X35688Y112955D03*
X130750Y120042D03*
Y134215D03*
X148692Y421047D03*
X138290Y413987D03*
X140690Y399813D03*
X148692Y406874D03*
Y392701D03*
X138050Y127128D03*
Y112955D03*
X138290Y471087D03*
Y442333D03*
Y428160D03*
X148692Y435221D03*
X205680Y399782D03*
X212980Y406868D03*
Y392695D03*
Y471081D03*
Y435215D03*
X205680Y442302D03*
Y428128D03*
Y413955D03*
X212980Y421041D03*
X233112Y134215D03*
Y120042D03*
X240412Y127128D03*
Y112955D03*
X342774Y127128D03*
X335474Y134215D03*
Y120042D03*
X342774Y112955D03*
X533092Y127096D03*
Y112923D03*
X543494Y134209D03*
Y120035D03*
X635454Y127096D03*
Y112923D03*
X645856Y134209D03*
Y120035D03*
X748218Y134209D03*
X737816Y127096D03*
X748218Y120035D03*
X737816Y112923D03*
X721092Y469037D03*
X778080Y469006D03*
X840178Y127096D03*
Y112923D03*
X850580Y134209D03*
Y120035D03*
X990178Y127096D03*
Y112923D03*
X1000580Y134209D03*
Y120035D03*
X1092540Y127096D03*
Y112923D03*
X1102942Y134209D03*
Y120035D03*
X1178178Y469037D03*
X1205304Y134209D03*
X1194902Y127096D03*
X1205304Y120035D03*
X1194902Y112923D03*
X1235166Y469006D03*
X1297264Y127096D03*
Y112923D03*
X1307666Y134209D03*
Y120035D03*
X1399648Y120042D03*
Y134215D03*
X1406948Y127128D03*
Y112955D03*
X1509310D03*
X1509550Y428160D03*
Y413987D03*
X1511950Y399813D03*
X1502010Y134215D03*
X1509310Y127128D03*
X1502010Y120042D03*
X1519952Y421047D03*
Y406874D03*
Y392701D03*
X1509550Y471087D03*
Y442333D03*
X1519952Y435221D03*
X1576940Y442302D03*
Y428128D03*
Y413955D03*
Y399782D03*
X1584240Y421041D03*
Y406868D03*
Y392695D03*
X1604372Y134215D03*
X1611672Y127128D03*
X1604372Y120042D03*
X1611672Y112955D03*
X1584240Y471081D03*
Y435215D03*
X1706734Y134215D03*
Y120042D03*
X1714034Y127128D03*
Y112955D03*
X148692Y536506D03*
Y522333D03*
X138290Y515221D03*
X148692Y492373D03*
X138290Y529394D03*
X205680Y492341D03*
Y536475D03*
X212980Y529388D03*
Y515215D03*
X205680Y522302D03*
X713792Y612817D03*
Y598644D03*
Y584471D03*
Y570297D03*
Y534431D03*
Y520258D03*
Y490297D03*
X721092Y591557D03*
Y577384D03*
Y563210D03*
Y527344D03*
Y513171D03*
Y605730D03*
X778080Y563179D03*
Y527313D03*
Y513139D03*
Y591525D03*
Y605699D03*
Y577352D03*
X788482Y570291D03*
Y534425D03*
Y520252D03*
Y490291D03*
Y612811D03*
Y598638D03*
Y584465D03*
X1170878Y612817D03*
Y598644D03*
Y584471D03*
Y570297D03*
Y534431D03*
Y520258D03*
Y490297D03*
X1178178Y563210D03*
Y527344D03*
Y513171D03*
Y605730D03*
Y591557D03*
Y577384D03*
X1235166Y527313D03*
Y513139D03*
Y605699D03*
Y591525D03*
Y577352D03*
Y563179D03*
X1245568Y570291D03*
Y534425D03*
Y520252D03*
Y490291D03*
Y612811D03*
Y598638D03*
Y584465D03*
X1509550Y529394D03*
Y515221D03*
X1519952Y536506D03*
Y522333D03*
Y492373D03*
X1576940Y536475D03*
Y522302D03*
Y492341D03*
X1584240Y529388D03*
Y515215D03*
X7982Y1527335D03*
G54D67*
X1592187Y-71006D03*
Y-81006D03*
X1582187Y-32086D03*
Y-42086D03*
X1736405Y-80978D03*
Y-70978D03*
X1801761Y-42188D03*
Y-32188D03*
X1517261Y-42058D03*
Y-32058D03*
X1481905Y-80978D03*
Y-70978D03*
X1230761Y-41928D03*
X1081187Y-71006D03*
X1337687D03*
Y-81006D03*
X1081187D03*
X1230761Y-31928D03*
X1225405Y-80978D03*
X1011187Y-31826D03*
X1297687Y-31956D03*
Y-41956D03*
X1225405Y-70978D03*
X1011187Y-41826D03*
X213969Y1460153D03*
Y1449153D03*
X227249Y1460153D03*
Y1449153D03*
G54D81*
X1817323Y1567323D03*
G54D68*
X1009333Y1344993D03*
X1015659Y681354D03*
X933725Y587636D03*
X933741Y596387D03*
X486837Y703006D03*
X394883Y340077D03*
X217907Y1428752D03*
X415203Y1497818D03*
X397267Y1516347D03*
X295011Y461917D03*
X523943Y105949D03*
X626305D03*
X728667D03*
X752097Y461917D03*
X831029Y105949D03*
X981029D03*
X1083391D03*
X1080351Y329955D03*
X1185753Y105949D03*
X1288115D03*
X1366535Y353200D03*
Y337452D03*
X1363535Y345326D03*
Y329578D03*
X1666271Y461919D03*
X174923Y543562D03*
X632009D03*
X1546183Y543564D03*
X385091Y1299153D03*
X454385Y1303545D03*
X940997Y333613D03*
X256705Y476124D03*
X264005Y483210D03*
X605779Y478199D03*
X595377Y485260D03*
X331395Y476118D03*
X320993Y483179D03*
X670067Y485254D03*
X662767Y478168D03*
X1127153Y485254D03*
X1119853Y478168D03*
X1062865Y478199D03*
X1052463Y485260D03*
X1702655Y476118D03*
X1692253Y483179D03*
X1635265Y483210D03*
X1627965Y476124D03*
X76005Y127096D03*
Y112923D03*
X86407Y120035D03*
Y134209D03*
X178367Y127096D03*
Y112923D03*
X188769Y134209D03*
Y120035D03*
X264005Y469037D03*
X291131Y134209D03*
Y120035D03*
X280729Y127096D03*
Y112923D03*
X320993Y469005D03*
X393493Y134209D03*
X383091Y127096D03*
X393493Y120035D03*
X383091Y112923D03*
X485475Y134215D03*
Y120042D03*
X492775Y127128D03*
Y112955D03*
X587837Y134215D03*
Y120042D03*
X597777Y399813D03*
X595137Y127128D03*
Y112955D03*
X595377Y471087D03*
Y442333D03*
Y428160D03*
Y413987D03*
X605779Y435221D03*
Y421047D03*
Y406874D03*
Y392701D03*
X670067Y435215D03*
X662767Y442302D03*
Y428128D03*
Y413955D03*
X670067Y421041D03*
X662767Y399782D03*
X670067Y406868D03*
Y392695D03*
Y471081D03*
X690199Y120042D03*
X697499Y127128D03*
X690199Y134215D03*
X697499Y112955D03*
X799861D03*
Y127128D03*
X792561Y120042D03*
Y134215D03*
X949861Y112955D03*
X942561Y120042D03*
Y134215D03*
X949861Y127128D03*
X1044923Y134215D03*
X1052223Y127128D03*
X1044923Y120042D03*
X1052223Y112955D03*
X1052463Y471087D03*
Y442333D03*
Y428160D03*
Y413987D03*
X1054863Y399813D03*
X1062865Y435221D03*
Y421047D03*
Y406874D03*
Y392701D03*
X1119853Y399782D03*
Y442302D03*
Y428128D03*
Y413955D03*
X1154585Y112955D03*
X1127153Y471081D03*
Y435215D03*
Y421041D03*
Y406868D03*
Y392695D03*
X1154585Y127128D03*
X1147285Y134215D03*
Y120042D03*
X1249647Y134215D03*
Y120042D03*
X1256947Y127128D03*
Y112955D03*
X1447265Y127096D03*
Y112923D03*
X1457667Y134209D03*
Y120035D03*
X1560029Y134209D03*
X1549627Y127096D03*
X1560029Y120035D03*
X1549627Y112923D03*
X1651989Y127096D03*
Y112923D03*
X1635265Y469037D03*
X1662391Y134209D03*
Y120035D03*
X1692253Y469006D03*
X1754351Y127096D03*
Y112923D03*
X1764753Y134209D03*
Y120035D03*
X264005Y513171D03*
X256705Y520258D03*
Y490297D03*
Y612817D03*
X264005Y591557D03*
Y605730D03*
X256705Y598644D03*
X264005Y577384D03*
X256705Y584471D03*
Y570297D03*
X264005Y563210D03*
X256705Y534431D03*
X264005Y527344D03*
X320993Y513139D03*
Y591525D03*
Y605699D03*
Y577352D03*
Y563179D03*
Y527313D03*
X331395Y490291D03*
Y612811D03*
Y598638D03*
Y584465D03*
Y570291D03*
Y534425D03*
Y520252D03*
X595377Y529394D03*
Y515221D03*
X605779Y536506D03*
Y522333D03*
Y492373D03*
X670067Y529388D03*
X662767Y536475D03*
Y522302D03*
X670067Y515215D03*
X662767Y492341D03*
X1052463Y529394D03*
Y515221D03*
X1062865Y536506D03*
Y522333D03*
Y492373D03*
X1119853Y536475D03*
Y522302D03*
Y492341D03*
X1127153Y529388D03*
Y515215D03*
X1627965Y584471D03*
Y570297D03*
Y534431D03*
Y520258D03*
Y490297D03*
Y612817D03*
Y598644D03*
X1635265Y527344D03*
Y513171D03*
Y605730D03*
Y591557D03*
Y577384D03*
Y563210D03*
X1692253Y605699D03*
Y591525D03*
Y577352D03*
Y563179D03*
Y527313D03*
Y513139D03*
X1702655Y534425D03*
Y520252D03*
Y490291D03*
Y612811D03*
Y598638D03*
Y584465D03*
Y570291D03*
G54D77*
X770472Y1490945D03*
X820079Y388583D03*
X1020866D03*
X1070472Y1490945D03*
G54D65*
X19685Y-83298D03*
X1821260D03*
X26789Y1373669D03*
X1796847Y1517889D03*
X1809883Y120792D03*
X184851Y334492D03*
X19685Y1801195D03*
X1821260D03*
G54D75*
X1030905Y1066535D03*
Y1263386D03*
X810038Y1066535D03*
Y1263386D03*
X573818Y1066535D03*
Y1263386D03*
X352952Y1066535D03*
Y1263386D03*
X116731Y1066535D03*
Y1263386D03*
X1724212Y1066535D03*
Y1263386D03*
X1487991Y1066535D03*
Y1263386D03*
X1267125Y1066535D03*
Y1263386D03*
%LPC*%
G75*
G36*
G01X179540Y1228543D02*
G02I-800J0D01*
G37*
G36*
G01X172059Y1224803D02*
G02I-800J0D01*
G37*
G36*
G01X175799Y1232283D02*
G02I-800J0D01*
G37*
G36*
G01X172059Y1228543D02*
G02I-800J0D01*
G37*
G36*
G01X179540Y1224803D02*
G02I-800J0D01*
G37*
G36*
G01X175799Y1236023D02*
G02I-800J0D01*
G37*
G36*
G01X183280D02*
G02I-800J0D01*
G37*
G36*
G01X198240D02*
G02I-800J0D01*
G37*
G36*
G01X187020Y1224803D02*
G02I-800J0D01*
G37*
G36*
G01X183280Y1232283D02*
G02I-800J0D01*
G37*
G36*
G01X194500Y1228543D02*
G02I-800J0D01*
G37*
G36*
G01X198240Y1232283D02*
G02I-800J0D01*
G37*
G36*
G01X190760Y1236023D02*
G02I-800J0D01*
G37*
G36*
G01X187020Y1228543D02*
G02I-800J0D01*
G37*
G36*
G01X194500Y1224803D02*
G02I-800J0D01*
G37*
G36*
G01X190760Y1232283D02*
G02I-800J0D01*
G37*
G36*
G01X205721D02*
G02I-800J0D01*
G37*
G36*
G01X201981Y1224803D02*
G02I-800J0D01*
G37*
G36*
G01X213201Y1232283D02*
G02I-800J0D01*
G37*
G36*
G01X209461Y1228543D02*
G02I-800J0D01*
G37*
G36*
G01X213201Y1236023D02*
G02I-800J0D01*
G37*
G36*
G01X209461Y1224803D02*
G02I-800J0D01*
G37*
G36*
G01X201981Y1228543D02*
G02I-800J0D01*
G37*
G36*
G01X205721Y1236023D02*
G02I-800J0D01*
G37*
G36*
G01X220681Y1232283D02*
G02I-800J0D01*
G37*
G36*
G01Y1236023D02*
G02I-800J0D01*
G37*
G36*
G01X216941Y1224803D02*
G02I-800J0D01*
G37*
G36*
G01X224422D02*
G02I-800J0D01*
G37*
G36*
G01X228162Y1232283D02*
G02I-800J0D01*
G37*
G36*
G01X224422Y1228543D02*
G02I-800J0D01*
G37*
G36*
G01X216941D02*
G02I-800J0D01*
G37*
G36*
G01X228162Y1236023D02*
G02I-800J0D01*
G37*
G36*
G01X295485Y1250984D02*
G02I-800J0D01*
G37*
G36*
G01X291744Y1247243D02*
G02I-800J0D01*
G37*
G36*
G01Y1243503D02*
G02I-800J0D01*
G37*
G36*
G01X295485Y1254724D02*
G02I-800J0D01*
G37*
G36*
G01X299225Y1247243D02*
G02I-800J0D01*
G37*
G36*
G01X310445Y1250984D02*
G02I-800J0D01*
G37*
G36*
G01X299225Y1243503D02*
G02I-800J0D01*
G37*
G36*
G01X306705D02*
G02I-800J0D01*
G37*
G36*
G01Y1247243D02*
G02I-800J0D01*
G37*
G36*
G01X302965Y1250984D02*
G02I-800J0D01*
G37*
G36*
G01X310445Y1254724D02*
G02I-800J0D01*
G37*
G36*
G01X302965D02*
G02I-800J0D01*
G37*
G36*
G01X321666Y1198621D02*
G02I-800J0D01*
G37*
G36*
G01X314185Y1202362D02*
G02I-800J0D01*
G37*
G36*
G01X325406Y1198621D02*
G02I-800J0D01*
G37*
G36*
G01X317925Y1202362D02*
G02I-800J0D01*
G37*
G36*
G01Y1217322D02*
G02I-800J0D01*
G37*
G36*
G01Y1209842D02*
G02I-800J0D01*
G37*
G36*
G01X325406Y1213582D02*
G02I-800J0D01*
G37*
G36*
G01X321666Y1221062D02*
G02I-800J0D01*
G37*
G36*
G01X314185Y1209842D02*
G02I-800J0D01*
G37*
G36*
G01X321666Y1206102D02*
G02I-800J0D01*
G37*
G36*
G01Y1213582D02*
G02I-800J0D01*
G37*
G36*
G01X325406Y1221062D02*
G02I-800J0D01*
G37*
G36*
G01Y1206102D02*
G02I-800J0D01*
G37*
G36*
G01X314185Y1217322D02*
G02I-800J0D01*
G37*
G36*
G01Y1247243D02*
G02I-800J0D01*
G37*
G36*
G01X321666D02*
G02I-800J0D01*
G37*
G36*
G01X317925Y1250984D02*
G02I-800J0D01*
G37*
G36*
G01X314185Y1243503D02*
G02I-800J0D01*
G37*
G36*
G01X325406Y1247243D02*
G02I-800J0D01*
G37*
G36*
G01X317925Y1254724D02*
G02I-800J0D01*
G37*
G36*
G01X629146Y1224803D02*
G02I-800J0D01*
G37*
G36*
G01Y1228543D02*
G02I-800J0D01*
G37*
G36*
G01X636627D02*
G02I-800J0D01*
G37*
G36*
G01X632886Y1232283D02*
G02I-800J0D01*
G37*
G36*
G01Y1236023D02*
G02I-800J0D01*
G37*
G36*
G01X636627Y1224803D02*
G02I-800J0D01*
G37*
G36*
G01Y1243503D02*
G02I-800J0D01*
G37*
G36*
G01X632886Y1250984D02*
G02I-800J0D01*
G37*
G36*
G01X636627Y1247243D02*
G02I-800J0D01*
G37*
G36*
G01X629146Y1243503D02*
G02I-800J0D01*
G37*
G36*
G01Y1247243D02*
G02I-800J0D01*
G37*
G36*
G01X632886Y1254724D02*
G02I-800J0D01*
G37*
G36*
G01X640367Y1236023D02*
G02I-800J0D01*
G37*
G36*
G01X647847D02*
G02I-800J0D01*
G37*
G36*
G01X640367Y1232283D02*
G02I-800J0D01*
G37*
G36*
G01X644107Y1224803D02*
G02I-800J0D01*
G37*
G36*
G01X647847Y1232283D02*
G02I-800J0D01*
G37*
G36*
G01X644107Y1228543D02*
G02I-800J0D01*
G37*
G36*
G01X651587D02*
G02I-800J0D01*
G37*
G36*
G01Y1224803D02*
G02I-800J0D01*
G37*
G36*
G01X640367Y1250984D02*
G02I-800J0D01*
G37*
G36*
G01X651587Y1247243D02*
G02I-800J0D01*
G37*
G36*
G01Y1243503D02*
G02I-800J0D01*
G37*
G36*
G01X647847Y1250984D02*
G02I-800J0D01*
G37*
G36*
G01X644107Y1247243D02*
G02I-800J0D01*
G37*
G36*
G01Y1243503D02*
G02I-800J0D01*
G37*
G36*
G01X640367Y1254724D02*
G02I-800J0D01*
G37*
G36*
G01X647847D02*
G02I-800J0D01*
G37*
G36*
G01X655327Y1236023D02*
G02I-800J0D01*
G37*
G36*
G01Y1232283D02*
G02I-800J0D01*
G37*
G36*
G01Y1250984D02*
G02I-800J0D01*
G37*
G36*
G01Y1254724D02*
G02I-800J0D01*
G37*
G36*
G01X718910Y1228543D02*
G02I-800J0D01*
G37*
G36*
G01Y1224803D02*
G02I-800J0D01*
G37*
G36*
G01Y1243503D02*
G02I-800J0D01*
G37*
G36*
G01Y1247243D02*
G02I-800J0D01*
G37*
G36*
G01X726390Y1228543D02*
G02I-800J0D01*
G37*
G36*
G01X733871D02*
G02I-800J0D01*
G37*
G36*
G01X722650Y1236023D02*
G02I-800J0D01*
G37*
G36*
G01X733871Y1224803D02*
G02I-800J0D01*
G37*
G36*
G01X722650Y1232283D02*
G02I-800J0D01*
G37*
G36*
G01X726390Y1224803D02*
G02I-800J0D01*
G37*
G36*
G01X730131Y1236023D02*
G02I-800J0D01*
G37*
G36*
G01Y1232283D02*
G02I-800J0D01*
G37*
G36*
G01Y1250984D02*
G02I-800J0D01*
G37*
G36*
G01X733871Y1247243D02*
G02I-800J0D01*
G37*
G36*
G01X722650Y1250984D02*
G02I-800J0D01*
G37*
G36*
G01X726390Y1243503D02*
G02I-800J0D01*
G37*
G36*
G01X733871D02*
G02I-800J0D01*
G37*
G36*
G01X726390Y1247243D02*
G02I-800J0D01*
G37*
G36*
G01X722650Y1254724D02*
G02I-800J0D01*
G37*
G36*
G01X730131D02*
G02I-800J0D01*
G37*
G36*
G01X745091Y1236023D02*
G02I-800J0D01*
G37*
G36*
G01X737611Y1232283D02*
G02I-800J0D01*
G37*
G36*
G01X745091D02*
G02I-800J0D01*
G37*
G36*
G01X737611Y1236023D02*
G02I-800J0D01*
G37*
G36*
G01X741351Y1224803D02*
G02I-800J0D01*
G37*
G36*
G01Y1228543D02*
G02I-800J0D01*
G37*
G36*
G01Y1243503D02*
G02I-800J0D01*
G37*
G36*
G01Y1247243D02*
G02I-800J0D01*
G37*
G36*
G01X745091Y1250984D02*
G02I-800J0D01*
G37*
G36*
G01X737611D02*
G02I-800J0D01*
G37*
G36*
G01X745091Y1254724D02*
G02I-800J0D01*
G37*
G36*
G01X737611D02*
G02I-800J0D01*
G37*
G36*
G01X940026Y1577634D02*
G03X940910Y1577268I884J885D01*
G01X956342D01*
G02X956484Y1577209I0J-200D01*
G01X959830Y1573863D01*
G02X959889Y1573721I-141J-142D01*
G01Y1543680D01*
G03X960255Y1542796I1251J0D01*
G01X964295Y1538756D01*
G03X965179Y1538390I884J885D01*
G01X1019906D01*
G02X1020048Y1538331I0J-200D01*
G01X1031515Y1526864D01*
G02X1031574Y1526722I-141J-142D01*
G01Y1492904D01*
G02X1031515Y1492762I-200J0D01*
G01X1031368Y1492615D01*
G02X1031226Y1492556I-142J141D01*
G01X947183D01*
G02X947041Y1492615I0J200D01*
G01X944876Y1494780D01*
G03X943992Y1495146I-884J-885D01*
G01X933579D01*
G03X932695Y1494780I0J-1251D01*
G01X917141Y1479226D01*
G03X916775Y1478342I885J-884D01*
G01Y1465020D01*
G02X916716Y1464878I-200J0D01*
G01X914188Y1462350D01*
G03X913822Y1461466I885J-884D01*
G01Y1460928D01*
G02X913763Y1460786I-200J0D01*
G01X913527Y1460550D01*
G03X913161Y1459666I885J-884D01*
G01Y1446448D01*
G02X913102Y1446306I-200J0D01*
G01X912955Y1446159D01*
G02X912813Y1446100I-142J141D01*
G01X900559D01*
G02X900417Y1446159I0J200D01*
G01X900270Y1446306D01*
G02X900211Y1446448I141J142D01*
G01Y1459640D01*
G03X899845Y1460524I-1251J0D01*
G01X899532Y1460837D01*
G02X899473Y1460979I141J142D01*
G01Y1462024D01*
G03X899107Y1462908I-1251J0D01*
G01X894403Y1467612D01*
G02X894344Y1467754I141J142D01*
G01Y1473096D01*
G03X893978Y1473980I-1251J0D01*
G01X888953Y1479005D01*
G03X888069Y1479371I-884J-885D01*
G01X880504D01*
G03X879620Y1479005I0J-1251D01*
G01X872265Y1471650D01*
G03X871899Y1470766I885J-884D01*
G01Y1460991D01*
G02X871840Y1460849I-200J0D01*
G01X871502Y1460511D01*
G03X871136Y1459627I885J-884D01*
G01Y1446423D01*
G02X871077Y1446281I-200J0D01*
G01X870968Y1446172D01*
G02X870826Y1446113I-142J141D01*
G01X858702D01*
G02X858560Y1446172I0J200D01*
G01X858139Y1446593D01*
G02X858080Y1446735I141J142D01*
G01Y1459524D01*
G03X857714Y1460408I-1251J0D01*
G01X853660Y1464462D01*
G03X852776Y1464828I-884J-885D01*
G01X828441D01*
G03X827557Y1464462I0J-1251D01*
G01X827039Y1463944D01*
G03X826673Y1463060I885J-884D01*
G01Y1461847D01*
G02X826614Y1461705I-200J0D01*
G01X826571Y1461662D01*
G02X826429Y1461603I-142J141D01*
G01X825036D01*
G03X824152Y1461237I0J-1251D01*
G01X821533Y1458618D01*
G02X821391Y1458559I-142J141D01*
G01X820451D01*
G03X819567Y1458193I0J-1251D01*
G01X819360Y1457986D01*
G03X818994Y1457102I885J-884D01*
G01Y1446462D01*
G02X818935Y1446320I-200J0D01*
G01X818826Y1446211D01*
G02X818684Y1446152I-142J141D01*
G01X806393D01*
G02X806251Y1446211I0J200D01*
G01X806063Y1446399D01*
G02X806004Y1446541I141J142D01*
G01Y1459828D01*
G02X806063Y1459970I200J0D01*
G01X806195Y1460102D01*
G03X806561Y1460986I-885J884D01*
G01Y1474310D01*
G02X806615Y1474447I200J0D01*
G03X806950Y1475299I-916J852D01*
G01Y1523715D01*
G02X807009Y1523857I200J0D01*
G01X816830Y1533678D01*
G03X817196Y1534562I-885J884D01*
G01Y1620853D01*
G02X817255Y1620995I200J0D01*
G01X822528Y1626268D01*
G02X822670Y1626327I142J-141D01*
G01X927565D01*
G02X927707Y1626268I0J-200D01*
G01X932114Y1621861D01*
G02X932173Y1621719I-141J-142D01*
G01Y1586005D01*
G03X932539Y1585121I1251J0D01*
G01X940026Y1577634D01*
G37*
G36*
G01X953110Y1480583D02*
G03X953130Y1480563I894J874D01*
G02X953192Y1480419I-138J-145D01*
G01Y1451442D01*
G02X953133Y1451300I-200J0D01*
G01X952668Y1450835D01*
G02X952526Y1450776I-142J141D01*
G01X930592D01*
G02X930450Y1450835I0J200D01*
G01X929621Y1451664D01*
G02X929562Y1451806I141J142D01*
G01Y1480891D01*
G02X929621Y1481033I200J0D01*
G01X930418Y1481830D01*
G02X930560Y1481889I142J-141D01*
G01X951737D01*
G02X951894Y1481812I-1J-200D01*
G03X951995Y1481698I984J770D01*
G01X953110Y1480583D01*
G37*
G36*
G01X955751Y1485453D02*
X957168Y1486870D01*
G02X957310Y1486929I142J-141D01*
G01X1045732D01*
G02X1045874Y1486870I0J-200D01*
G01X1046659Y1486085D01*
G02X1046718Y1485943I-141J-142D01*
G01Y1452303D01*
G02X1046659Y1452161I-200J0D01*
G01X1045333Y1450835D01*
G02X1045191Y1450776I-142J141D01*
G01X956304D01*
G02X956162Y1450835I0J200D01*
G01X955751Y1451246D01*
G02X955692Y1451388I141J142D01*
G01Y1485311D01*
G02X955751Y1485453I200J0D01*
G37*
G36*
G01X1089972Y1232283D02*
G02I-800J0D01*
G37*
G36*
G01Y1236023D02*
G02I-800J0D01*
G37*
G36*
G01X1086232Y1224803D02*
G02I-800J0D01*
G37*
G36*
G01Y1228543D02*
G02I-800J0D01*
G37*
G36*
G01X1101193D02*
G02I-800J0D01*
G37*
G36*
G01X1104933Y1236023D02*
G02I-800J0D01*
G37*
G36*
G01X1093713Y1224803D02*
G02I-800J0D01*
G37*
G36*
G01X1104933Y1232283D02*
G02I-800J0D01*
G37*
G36*
G01X1108673Y1224803D02*
G02I-800J0D01*
G37*
G36*
G01X1097453Y1236023D02*
G02I-800J0D01*
G37*
G36*
G01X1101193Y1224803D02*
G02I-800J0D01*
G37*
G36*
G01X1108673Y1228543D02*
G02I-800J0D01*
G37*
G36*
G01X1097453Y1232283D02*
G02I-800J0D01*
G37*
G36*
G01X1093713Y1228543D02*
G02I-800J0D01*
G37*
G36*
G01X1123634Y1224803D02*
G02I-800J0D01*
G37*
G36*
G01X1119894Y1232283D02*
G02I-800J0D01*
G37*
G36*
G01X1116154Y1228543D02*
G02I-800J0D01*
G37*
G36*
G01X1112413Y1232283D02*
G02I-800J0D01*
G37*
G36*
G01X1119894Y1236023D02*
G02I-800J0D01*
G37*
G36*
G01X1116154Y1224803D02*
G02I-800J0D01*
G37*
G36*
G01X1112413Y1236023D02*
G02I-800J0D01*
G37*
G36*
G01X1123634Y1228543D02*
G02I-800J0D01*
G37*
G36*
G01X1134854Y1236023D02*
G02I-800J0D01*
G37*
G36*
G01X1138595Y1228543D02*
G02I-800J0D01*
G37*
G36*
G01X1134854Y1232283D02*
G02I-800J0D01*
G37*
G36*
G01X1127374D02*
G02I-800J0D01*
G37*
G36*
G01Y1236023D02*
G02I-800J0D01*
G37*
G36*
G01X1138595Y1224803D02*
G02I-800J0D01*
G37*
G36*
G01X1131114Y1228543D02*
G02I-800J0D01*
G37*
G36*
G01Y1224803D02*
G02I-800J0D01*
G37*
G36*
G01X1142335Y1236023D02*
G02I-800J0D01*
G37*
G36*
G01Y1232283D02*
G02I-800J0D01*
G37*
G36*
G01X1205917Y1243503D02*
G02I-800J0D01*
G37*
G36*
G01Y1247243D02*
G02I-800J0D01*
G37*
G36*
G01X1213398Y1243503D02*
G02I-800J0D01*
G37*
G36*
G01X1220878Y1247243D02*
G02I-800J0D01*
G37*
G36*
G01Y1243503D02*
G02I-800J0D01*
G37*
G36*
G01X1213398Y1247243D02*
G02I-800J0D01*
G37*
G36*
G01X1209658Y1250984D02*
G02I-800J0D01*
G37*
G36*
G01X1217138D02*
G02I-800J0D01*
G37*
G36*
G01X1209658Y1254724D02*
G02I-800J0D01*
G37*
G36*
G01X1217138D02*
G02I-800J0D01*
G37*
G36*
G01X1232098Y1202362D02*
G02I-800J0D01*
G37*
G36*
G01X1235839Y1198621D02*
G02I-800J0D01*
G37*
G36*
G01X1228358Y1202362D02*
G02I-800J0D01*
G37*
G36*
G01X1235839Y1213582D02*
G02I-800J0D01*
G37*
G36*
G01X1232098Y1209842D02*
G02I-800J0D01*
G37*
G36*
G01X1228358D02*
G02I-800J0D01*
G37*
G36*
G01X1235839Y1221062D02*
G02I-800J0D01*
G37*
G36*
G01X1232098Y1217322D02*
G02I-800J0D01*
G37*
G36*
G01X1235839Y1206102D02*
G02I-800J0D01*
G37*
G36*
G01X1228358Y1217322D02*
G02I-800J0D01*
G37*
G36*
G01Y1247243D02*
G02I-800J0D01*
G37*
G36*
G01X1224618Y1250984D02*
G02I-800J0D01*
G37*
G36*
G01X1228358Y1243503D02*
G02I-800J0D01*
G37*
G36*
G01X1232098Y1250984D02*
G02I-800J0D01*
G37*
G36*
G01X1235839Y1247243D02*
G02I-800J0D01*
G37*
G36*
G01X1232098Y1254724D02*
G02I-800J0D01*
G37*
G36*
G01X1224618D02*
G02I-800J0D01*
G37*
G36*
G01X1239579Y1198621D02*
G02I-800J0D01*
G37*
G36*
G01Y1221062D02*
G02I-800J0D01*
G37*
G36*
G01Y1206102D02*
G02I-800J0D01*
G37*
G36*
G01Y1213582D02*
G02I-800J0D01*
G37*
G36*
G01Y1247243D02*
G02I-800J0D01*
G37*
G36*
G01X1547059Y1232283D02*
G02I-800J0D01*
G37*
G36*
G01X1543319Y1228543D02*
G02I-800J0D01*
G37*
G36*
G01X1547059Y1236023D02*
G02I-800J0D01*
G37*
G36*
G01X1543319Y1224803D02*
G02I-800J0D01*
G37*
G36*
G01X1547059Y1250984D02*
G02I-800J0D01*
G37*
G36*
G01X1543319Y1243503D02*
G02I-800J0D01*
G37*
G36*
G01Y1247243D02*
G02I-800J0D01*
G37*
G36*
G01X1547059Y1254724D02*
G02I-800J0D01*
G37*
G36*
G01X1554540Y1232283D02*
G02I-800J0D01*
G37*
G36*
G01X1550800Y1228543D02*
G02I-800J0D01*
G37*
G36*
G01X1554540Y1236023D02*
G02I-800J0D01*
G37*
G36*
G01X1550800Y1224803D02*
G02I-800J0D01*
G37*
G36*
G01X1558280Y1228543D02*
G02I-800J0D01*
G37*
G36*
G01X1562020Y1236023D02*
G02I-800J0D01*
G37*
G36*
G01Y1232283D02*
G02I-800J0D01*
G37*
G36*
G01X1558280Y1224803D02*
G02I-800J0D01*
G37*
G36*
G01X1562020Y1250984D02*
G02I-800J0D01*
G37*
G36*
G01X1550800Y1243503D02*
G02I-800J0D01*
G37*
G36*
G01X1558280Y1247243D02*
G02I-800J0D01*
G37*
G36*
G01X1550800D02*
G02I-800J0D01*
G37*
G36*
G01X1558280Y1243503D02*
G02I-800J0D01*
G37*
G36*
G01X1554540Y1250984D02*
G02I-800J0D01*
G37*
G36*
G01X1562020Y1254724D02*
G02I-800J0D01*
G37*
G36*
G01X1554540D02*
G02I-800J0D01*
G37*
G36*
G01X1569500Y1236023D02*
G02I-800J0D01*
G37*
G36*
G01X1565760Y1224803D02*
G02I-800J0D01*
G37*
G36*
G01Y1228543D02*
G02I-800J0D01*
G37*
G36*
G01X1569500Y1232283D02*
G02I-800J0D01*
G37*
G36*
G01X1565760Y1243503D02*
G02I-800J0D01*
G37*
G36*
G01Y1247243D02*
G02I-800J0D01*
G37*
G36*
G01X1569500Y1250984D02*
G02I-800J0D01*
G37*
G36*
G01Y1254724D02*
G02I-800J0D01*
G37*
G36*
G01X1633083Y1228543D02*
G02I-800J0D01*
G37*
G36*
G01X1640563Y1224803D02*
G02I-800J0D01*
G37*
G36*
G01X1636823Y1236023D02*
G02I-800J0D01*
G37*
G36*
G01X1644304Y1232283D02*
G02I-800J0D01*
G37*
G36*
G01X1633083Y1224803D02*
G02I-800J0D01*
G37*
G36*
G01X1644304Y1236023D02*
G02I-800J0D01*
G37*
G36*
G01X1636823Y1232283D02*
G02I-800J0D01*
G37*
G36*
G01X1640563Y1228543D02*
G02I-800J0D01*
G37*
G36*
G01X1633083Y1243503D02*
G02I-800J0D01*
G37*
G36*
G01X1640563D02*
G02I-800J0D01*
G37*
G36*
G01X1636823Y1250984D02*
G02I-800J0D01*
G37*
G36*
G01X1633083Y1247243D02*
G02I-800J0D01*
G37*
G36*
G01X1644304Y1250984D02*
G02I-800J0D01*
G37*
G36*
G01X1640563Y1247243D02*
G02I-800J0D01*
G37*
G36*
G01X1636823Y1254724D02*
G02I-800J0D01*
G37*
G36*
G01X1644304D02*
G02I-800J0D01*
G37*
G36*
G01X1655524Y1228543D02*
G02I-800J0D01*
G37*
G36*
G01X1648044D02*
G02I-800J0D01*
G37*
G36*
G01X1659264Y1232283D02*
G02I-800J0D01*
G37*
G36*
G01X1655524Y1224803D02*
G02I-800J0D01*
G37*
G36*
G01X1659264Y1236023D02*
G02I-800J0D01*
G37*
G36*
G01X1651784D02*
G02I-800J0D01*
G37*
G36*
G01X1648044Y1224803D02*
G02I-800J0D01*
G37*
G36*
G01X1651784Y1232283D02*
G02I-800J0D01*
G37*
G36*
G01X1655524Y1243503D02*
G02I-800J0D01*
G37*
G36*
G01X1651784Y1250984D02*
G02I-800J0D01*
G37*
G36*
G01X1648044Y1247243D02*
G02I-800J0D01*
G37*
G36*
G01X1655524D02*
G02I-800J0D01*
G37*
G36*
G01X1648044Y1243503D02*
G02I-800J0D01*
G37*
G36*
G01X1659264Y1250984D02*
G02I-800J0D01*
G37*
G36*
G01X1651784Y1254724D02*
G02I-800J0D01*
G37*
G36*
G01X1659264D02*
G02I-800J0D01*
G37*
%LPD*%
G75*
G54D15*
X7271Y70981D03*
X11011Y79720D03*
X8786Y88425D03*
X14264Y94236D03*
X10292D03*
X12786Y87903D03*
X18000Y90000D03*
X18298Y102141D03*
X8000Y102500D03*
X10131Y115473D03*
X15143Y115581D03*
X14996Y133034D03*
X11442Y132719D03*
X19855Y133000D03*
X9082Y135789D03*
X19855Y141362D03*
X11999Y141415D03*
X15948Y141267D03*
X10966Y162073D03*
Y159073D03*
X16909Y153263D03*
X12247Y166341D03*
X17313Y166937D03*
X21909Y153263D03*
X22335Y166721D03*
X16709Y175943D03*
X19572Y219470D03*
Y221970D03*
X10259Y218085D03*
X13059D03*
X19638Y226320D03*
X16859Y216385D03*
X19572Y216970D03*
X22599Y228646D03*
X18206Y244571D03*
X15586Y249108D03*
X13715Y259381D03*
X8970Y254871D03*
X18206Y264571D03*
X7036Y272371D03*
X8335Y280663D03*
X14807Y282181D03*
X15586Y269108D03*
X15499Y288542D03*
X17033Y1006819D03*
X14357Y1009906D03*
X20216Y1009748D03*
X14197Y1014205D03*
Y1017759D03*
X20197Y1014205D03*
Y1017759D03*
X12599Y1438143D03*
X16304Y1468196D03*
X15889Y1494254D03*
X10089D03*
X6489Y1501334D03*
X19745Y1508846D03*
X19735Y1530499D03*
X19859Y1520657D03*
X6951Y1538547D03*
X18879Y1534334D03*
X10367Y1553080D03*
X32350Y67562D03*
X28442Y55340D03*
X32350Y59562D03*
Y63562D03*
X26588Y97667D03*
X35442D03*
X35048Y103411D03*
X22439Y102495D03*
X35207Y106561D03*
X22935Y162073D03*
Y159073D03*
X26565Y177448D03*
X32507Y180517D03*
X30567Y195176D03*
X28067D03*
X25567D03*
X33067D03*
X29585Y199248D03*
X32585D03*
X29921Y206806D03*
X32585Y202048D03*
X25648Y210509D03*
X28148D03*
X29585Y201748D03*
X27421Y206806D03*
X27340Y230556D03*
X36185Y230117D03*
X31595Y227824D03*
X32201Y238714D03*
X23844Y239299D03*
X21556Y232971D03*
X31682Y246874D03*
X33902Y244297D03*
X26325Y262078D03*
X25549Y256394D03*
X31682Y266874D03*
X29116Y281129D03*
X37117Y279991D03*
X25549Y276394D03*
X34845Y291756D03*
X26629Y295619D03*
X35650Y491982D03*
Y495982D03*
X30177Y534211D03*
X34359Y541135D03*
X34732Y534909D03*
X25819Y527726D03*
Y548726D03*
X34425Y546553D03*
X34448Y552726D03*
X25819Y544726D03*
X30123Y611071D03*
X27686Y621311D03*
X36494Y616905D03*
X36306Y622285D03*
X27686Y629311D03*
Y625311D03*
X36692Y633724D03*
X36575Y627713D03*
X35293Y662952D03*
X35250Y671508D03*
X34565Y699082D03*
X36529Y1006321D03*
X30479Y1006509D03*
X24456Y1006401D03*
X32093Y1009748D03*
X26155Y1009985D03*
X29197Y1014205D03*
X32197Y1017759D03*
X26197D03*
X35197Y1014205D03*
X21196Y1065529D03*
Y1063029D03*
X36089Y1062601D03*
Y1065101D03*
X35925Y1075663D03*
X33425D03*
X28996Y1065529D03*
X23796D03*
X26396D03*
Y1063029D03*
X23796D03*
X28996D03*
X28606Y1082678D03*
X23406D03*
X26006D03*
Y1080178D03*
X23406D03*
X28606D03*
X20806Y1082678D03*
Y1080178D03*
X21321Y1098769D03*
X26521D03*
X29121D03*
X23921D03*
Y1101335D03*
X29121D03*
X26521D03*
X21321D03*
X32574Y1111633D03*
X29874D03*
X27274D03*
X24674D03*
Y1121333D03*
X27274D03*
X29874D03*
X32574D03*
X24674Y1130333D03*
X21974D03*
X21209Y1138705D03*
X23709D03*
X31631Y1198651D03*
X29860Y1438552D03*
X23603Y1449735D03*
X29880Y1441702D03*
X33189Y1501373D03*
X22381Y1554152D03*
X26231Y1554167D03*
X45988Y90512D03*
X51550Y90615D03*
X48476Y180812D03*
X48643Y442919D03*
X48596Y451419D03*
X45643Y472905D03*
X41643Y473419D03*
X49643Y472905D03*
Y464419D03*
X41643Y464919D03*
X48390Y485128D03*
X51239Y485138D03*
X40009Y481467D03*
X43948Y492108D03*
X44563Y482165D03*
X39801Y504825D03*
X42301D03*
X44801D03*
X43804Y500202D03*
X45256Y495993D03*
X45293Y522569D03*
X39742Y517401D03*
X42242D03*
X44742D03*
X46993Y529169D03*
X41408Y531882D03*
X43908D03*
X45293Y525369D03*
X46408Y531882D03*
X38358Y531948D03*
X52869Y537958D03*
X46643Y555194D03*
X52869Y540458D03*
X43843Y555194D03*
X46643Y571194D03*
X43843D03*
Y563194D03*
X46643D03*
X51000Y581222D03*
X45400D03*
X48200D03*
X51000Y591215D03*
X45400D03*
X48200D03*
X51172Y607762D03*
X48372D03*
X45572D03*
Y610562D03*
X48372D03*
X51172D03*
X40362Y610548D03*
X54192Y633473D03*
X42172Y633716D03*
X49192Y628078D03*
X47179Y633736D03*
X37847Y662910D03*
X39549Y682108D03*
X36910D03*
X37804Y671508D03*
X40165Y699082D03*
X37365D03*
X49249Y837718D03*
X52349D03*
X46049D03*
X53549Y843118D03*
X52077Y905295D03*
X48429Y916430D03*
X47264Y919649D03*
X48683Y1006510D03*
X42470Y1006738D03*
X50541Y1009589D03*
X44999Y1009510D03*
X38823Y1009273D03*
X47197Y1014205D03*
X41197D03*
X44197Y1017759D03*
X38197D03*
X48704Y1017982D03*
X43889Y1062601D03*
X38689D03*
X41289D03*
Y1065101D03*
X38689D03*
X43889D03*
X47314Y1072228D03*
X41172Y1079064D03*
X46166Y1093757D03*
X39659Y1105100D03*
X42259D03*
X44859D03*
X47559D03*
X48585Y1123867D03*
X47559Y1114800D03*
X44859D03*
X42259D03*
X39659D03*
X48547Y1133688D03*
X51047D03*
X55188Y1205179D03*
X51023Y1201416D03*
X48842Y1211109D03*
X53479Y1216256D03*
X43198Y1254055D03*
X45698D03*
X48198D03*
X45698Y1251555D03*
X43198D03*
X48198D03*
X47621Y1343672D03*
X48089Y1501387D03*
X39095Y1501361D03*
X47074Y1555923D03*
X40951Y1555932D03*
X64785Y79993D03*
Y82593D03*
Y85193D03*
Y74793D03*
Y77393D03*
X64829Y92874D03*
X55871Y99961D03*
X55921Y95236D03*
X66856Y104249D03*
Y107649D03*
X66478Y162368D03*
X63878D03*
X69261Y211695D03*
Y208695D03*
X65189Y210713D03*
Y213213D03*
Y208213D03*
X54733Y212978D03*
Y215478D03*
Y207978D03*
Y210478D03*
X65189Y215713D03*
X57987Y258880D03*
X60562Y264180D03*
X58062D03*
X66956Y267526D03*
Y270026D03*
X54167Y457339D03*
X56667D03*
X65737Y445603D03*
X57857Y446071D03*
X56667Y459839D03*
X54167D03*
Y462339D03*
X56667D03*
X62224Y473045D03*
X67670Y464818D03*
X58224Y465004D03*
X63154Y462371D03*
X55124Y478625D03*
X53739Y485138D03*
X56239D03*
X56824Y482425D03*
X55124Y475825D03*
X62700Y491214D03*
X66403Y495487D03*
X62700Y493714D03*
X66403Y492987D03*
X68202Y537877D03*
X56572Y539731D03*
X68202Y542877D03*
Y545377D03*
Y540377D03*
X61330Y544895D03*
X56572Y542231D03*
X64130Y541895D03*
Y544895D03*
X61630Y541895D03*
X68188Y548358D03*
X64408Y582747D03*
X63859Y590801D03*
X67684Y597232D03*
X63684Y597130D03*
X67684Y605637D03*
X61854Y617853D03*
Y620653D03*
X53972Y607762D03*
Y610562D03*
X59684Y605443D03*
X63684D03*
X66530Y625013D03*
X58181Y627908D03*
X64692Y642184D03*
X56049Y827218D03*
X68649D03*
X69049Y847718D03*
X65549Y850718D03*
X68598Y859415D03*
X68778Y873821D03*
X63969Y869475D03*
X63930Y874694D03*
X68100Y910122D03*
X71528Y913190D03*
X64632Y901500D03*
X59962Y910251D03*
X53197Y1014205D03*
Y1017759D03*
X55699Y1072761D03*
X61588Y1074481D03*
X62109Y1087656D03*
Y1084656D03*
Y1079656D03*
Y1091656D03*
X60269Y1198820D03*
X63094Y1207604D03*
X55596Y1210466D03*
X68245Y1212054D03*
X58443Y1272257D03*
X54843Y1501625D03*
X60227Y1514751D03*
X60277Y1528395D03*
X55862Y1541791D03*
X65478Y1541980D03*
X60303Y1534436D03*
X60747Y1555890D03*
X64747D03*
X60864Y1583484D03*
X58064D03*
X55264D03*
X69816Y1592527D03*
X60554Y1615152D03*
X73110Y98551D03*
X77804Y95879D03*
X76660Y103783D03*
X75194Y141247D03*
X71422Y147540D03*
X82661Y143740D03*
X80041Y148277D03*
X73578Y165393D03*
Y162793D03*
Y170493D03*
Y167993D03*
X80502Y177616D03*
X81083Y172190D03*
X72575Y181426D03*
X75786Y181366D03*
X78581Y181009D03*
X83756Y168697D03*
X84844Y191941D03*
X75400Y184012D03*
X72783Y184221D03*
X72061Y208695D03*
X71761Y211695D03*
X76819Y213859D03*
Y211359D03*
X80522Y213132D03*
Y215632D03*
X80766Y256303D03*
X75438Y265701D03*
X85541Y266114D03*
X80525Y265896D03*
X72256Y267526D03*
X69756D03*
Y270026D03*
X72256D03*
X83014Y281982D03*
X77073Y281716D03*
X71130Y462152D03*
Y459652D03*
Y464652D03*
X73630Y459652D03*
Y462152D03*
Y464652D03*
X78033Y491133D03*
X71461Y498151D03*
Y495151D03*
X73961D03*
X78033Y498633D03*
Y496133D03*
Y493633D03*
X73961Y498151D03*
X78133Y553297D03*
Y555897D03*
X75688Y548358D03*
X73188D03*
X70688D03*
X78133Y558497D03*
Y566597D03*
Y563697D03*
Y561097D03*
X72128Y570686D03*
X74923Y570478D03*
X75340Y576484D03*
X74983Y573689D03*
X72337Y573303D03*
X78733Y578405D03*
X84159Y578986D03*
X83684Y596729D03*
X72515Y596089D03*
X77734Y596782D03*
X81740Y619758D03*
Y616958D03*
Y614158D03*
X69670Y619513D03*
Y616713D03*
Y613913D03*
X79684Y605443D03*
X82648Y670679D03*
X73914Y660107D03*
X79043Y667391D03*
X84845Y659857D03*
X84314Y686107D03*
X82562Y680037D03*
X78735Y683426D03*
X72149Y827318D03*
X74349Y824718D03*
Y821918D03*
X74700Y842890D03*
X84367Y878286D03*
X76528Y878533D03*
X74028Y889065D03*
X83079Y888515D03*
X72035Y898346D03*
X80339Y897943D03*
X76203Y897910D03*
X80593Y946082D03*
X78167Y949261D03*
X76332Y953421D03*
X87632Y1007522D03*
X70059Y1075656D03*
X70302Y1067656D03*
X77734Y1095676D03*
X70947Y1201565D03*
Y1205835D03*
X71006Y1228684D03*
X71020Y1224323D03*
X74909Y1593009D03*
X71910Y1625009D03*
X78291Y1625743D03*
X83689Y1624736D03*
X82291Y1633801D03*
X78291D03*
X70291D03*
X91224Y141247D03*
X92337Y144172D03*
X95711Y143518D03*
X94811Y152373D03*
X97961Y152562D03*
X103456Y157370D03*
X98826Y172665D03*
X98763Y178560D03*
X98653Y183834D03*
X99639Y186629D03*
X98943Y200864D03*
X92898Y192490D03*
X98173Y190185D03*
X89353Y206767D03*
X86853D03*
X91853D03*
X98966Y207037D03*
X99032Y212455D03*
X89483Y221708D03*
X86983D03*
X86398Y224421D03*
X88098Y231021D03*
Y228221D03*
X96333Y221642D03*
X91983Y221708D03*
X103841Y228631D03*
X93649Y236189D03*
X91149D03*
X88649D03*
X91090Y248765D03*
X88590D03*
X93590D03*
X97747Y265897D03*
X100247D03*
X94087Y270695D03*
X91287D03*
X88787D03*
Y268195D03*
X91287D03*
X94087D03*
X98255Y374510D03*
X100120Y377898D03*
X100066Y381976D03*
X86788Y581659D03*
X87684Y605443D03*
X95973Y655660D03*
X92897Y658359D03*
X95917Y658374D03*
X95539Y664443D03*
X86289Y822088D03*
X86367Y848086D03*
X90000Y871389D03*
X103770Y868206D03*
X103692Y900295D03*
X91387Y905295D03*
X100058Y977651D03*
X99836Y980330D03*
X103836Y988813D03*
X100200Y988800D03*
X95836Y988813D03*
X85706Y998507D03*
X94398Y1006648D03*
X101025Y1009655D03*
X94586Y1023900D03*
X91765Y1018307D03*
X88007Y1013678D03*
X88479Y1023731D03*
X88287Y1026537D03*
X97609Y1018469D03*
X90450Y1033542D03*
X93496Y1547768D03*
X107364Y116594D03*
X118307Y110784D03*
X113307D03*
X107364Y119594D03*
X117886Y124663D03*
X112864Y124879D03*
X107798Y124283D03*
X119230Y138838D03*
X106205Y161306D03*
X107540Y176665D03*
Y168665D03*
Y196665D03*
Y192665D03*
X107653Y186778D03*
X107572Y204864D03*
Y208864D03*
X112621Y218085D03*
X115421D03*
X103213Y219379D03*
X117948Y249108D03*
X109329Y248371D03*
X111993Y710102D03*
X120250Y758841D03*
X113505Y796856D03*
X109591Y796905D03*
X102355Y874267D03*
X102947Y877196D03*
X102320Y891043D03*
X110887Y884000D03*
X103972Y977609D03*
X103836Y980330D03*
X111836Y988813D03*
X119836D03*
X115836D03*
X107836D03*
X103825Y1009655D03*
X105971Y1025745D03*
X114770Y1016827D03*
X110409Y1024094D03*
X114770Y1029427D03*
X110970Y1030672D03*
X101970D03*
X104970D03*
X107970D03*
X102761Y1096233D03*
X108971Y1109564D03*
X103124D03*
Y1122164D03*
X108971D03*
X103124Y1134764D03*
X108971D03*
X103124Y1147364D03*
X108971D03*
X103124Y1172564D03*
X108971D03*
X103124Y1159964D03*
X108971D03*
X103861Y1182703D03*
X118533Y1207737D03*
X112048Y1214372D03*
X107803Y1218169D03*
X128950Y97667D03*
X133200Y95111D03*
X124606Y102495D03*
X119333Y116594D03*
Y119594D03*
X122867Y125107D03*
X124340Y142862D03*
X131481Y143762D03*
X125381Y148717D03*
X131947Y199248D03*
X127929Y195176D03*
X130429D03*
X132929D03*
X134947Y199248D03*
X128010Y210509D03*
X130510D03*
X132283Y206806D03*
X129783D03*
X131947Y201748D03*
X122000Y226320D03*
X119221Y216385D03*
X121934Y216970D03*
Y219470D03*
Y221970D03*
X129702Y230556D03*
X133957Y227824D03*
X124961Y228646D03*
X128687Y242078D03*
X123918Y232971D03*
X134044Y246874D03*
X120568Y244571D03*
X127911Y256394D03*
X126131Y359511D03*
X125753Y365856D03*
X119099Y755052D03*
X118467Y796785D03*
X122437Y860775D03*
X125698Y857515D03*
X122432Y857540D03*
X129666Y857514D03*
X133424Y857303D03*
X122887Y888000D03*
X123387Y892000D03*
X135836Y988813D03*
X131836D03*
X123836D03*
X127836D03*
X120617Y1029427D03*
Y1016827D03*
X133579Y1097469D03*
X124925Y1102091D03*
X130380Y1105091D03*
X124880D03*
X124925Y1114691D03*
Y1127291D03*
X124880Y1117691D03*
X130380D03*
X124925Y1139891D03*
X124880Y1130291D03*
X130380D03*
X130434Y1144964D03*
X124474Y1142997D03*
X130380Y1155491D03*
X124880D03*
X124925Y1152491D03*
X124474Y1168197D03*
X130434Y1170164D03*
X124925Y1165091D03*
Y1177691D03*
X131000Y1180266D03*
X124765Y1180691D03*
X135757Y1221407D03*
X135448Y1229402D03*
Y1234921D03*
X126433Y1230407D03*
X129250Y1227650D03*
X137410Y103411D03*
X137804Y97667D03*
X148600Y90650D03*
X148350Y95236D03*
X137569Y106561D03*
X135429Y195176D03*
X134947Y202048D03*
X138547Y230117D03*
X134563Y238714D03*
X138664Y241699D03*
X148061Y378600D03*
Y382600D03*
X148176Y458711D03*
X148940Y455921D03*
X145376Y458711D03*
X147520Y463600D03*
X142024Y552466D03*
X147925Y603600D03*
Y619600D03*
Y623600D03*
X149469Y634190D03*
X152658Y645389D03*
X136862Y857244D03*
X147836Y988813D03*
X139836D03*
X151836D03*
X143836D03*
X142026Y1012354D03*
X136571Y1009354D03*
X136526Y1012354D03*
X136571Y1021954D03*
X142026Y1024954D03*
X136526D03*
X144640Y1039439D03*
X150952Y1040115D03*
X146595Y1053457D03*
X136432Y1224472D03*
X167191Y92874D03*
X153912Y90615D03*
X158283Y95236D03*
X158233Y99961D03*
X166240Y162368D03*
X157095Y210478D03*
Y207978D03*
Y215478D03*
Y212978D03*
X160424Y264180D03*
X162924D03*
X160349Y258880D03*
X164496Y309405D03*
X150703Y453682D03*
X159836Y988813D03*
X155836Y997860D03*
X160733Y1056594D03*
X153693Y1051037D03*
X160547Y1049283D03*
X160627Y1053561D03*
X160807Y1043955D03*
X166188Y1066551D03*
X163191Y1065313D03*
X159228Y1065613D03*
X165649Y1159350D03*
Y1151870D03*
X167147Y77393D03*
Y74793D03*
Y85193D03*
Y82593D03*
Y79993D03*
X175472Y98551D03*
X179022Y103783D03*
X169218Y107649D03*
Y104249D03*
X173784Y147540D03*
X177556Y141247D03*
X185023Y143740D03*
X182403Y148277D03*
X175940Y162793D03*
Y165393D03*
X168840Y162368D03*
X175940Y167993D03*
Y170493D03*
X178148Y181366D03*
X180943Y181009D03*
X174937Y181426D03*
X182864Y177616D03*
X183445Y172190D03*
X175145Y184221D03*
X177762Y184012D03*
X171623Y211695D03*
X182884Y213132D03*
X179181Y211359D03*
Y213859D03*
X174123Y211695D03*
X167551Y208213D03*
Y213213D03*
Y210713D03*
X171623Y208695D03*
X174423D03*
X167551Y215713D03*
X182884Y215632D03*
X177800Y265701D03*
X182887Y265896D03*
X174618Y267526D03*
Y270026D03*
X169318Y267526D03*
X172118D03*
Y270026D03*
X169318D03*
X179435Y281716D03*
X170215Y311671D03*
X175615Y550907D03*
X173115D03*
X175615Y553407D03*
X173115D03*
X174923Y545263D03*
Y541863D03*
X177385Y566929D03*
X171339Y572070D03*
X172686Y569928D03*
X175033Y570962D03*
X174776Y568475D03*
X177099Y569426D03*
X169389Y1155610D03*
X191568Y76587D03*
Y72615D03*
X193007Y100625D03*
X186026Y97475D03*
X185957Y106186D03*
X197380Y112083D03*
X193586Y141247D03*
X198073Y143518D03*
X197173Y152373D03*
X201015Y183834D03*
X201125Y178560D03*
X186118Y168697D03*
X201188Y172665D03*
X187206Y191941D03*
X195260Y192490D03*
X200535Y190185D03*
X201305Y200864D03*
X189215Y206767D03*
X191715D03*
X194215D03*
X201394Y212455D03*
X201328Y207037D03*
X194345Y221708D03*
X198695Y221642D03*
X190460Y228221D03*
Y231021D03*
X191845Y221708D03*
X188760Y224421D03*
X189345Y221708D03*
X191011Y236189D03*
X193511D03*
X196011D03*
X190952Y248765D03*
X193452D03*
X195952D03*
X183128Y256303D03*
X187903Y266114D03*
X196449Y268195D03*
X193649D03*
X196449Y270695D03*
X193649D03*
X191149D03*
Y268195D03*
X185376Y281982D03*
X185328Y545528D03*
X194063Y577716D03*
X191125Y610400D03*
X203248Y55513D03*
X199473Y68581D03*
X205848Y60513D03*
X208645Y60369D03*
X199486Y80581D03*
X214389Y86012D03*
X203616Y88801D03*
X214389Y94374D03*
X206533Y94351D03*
X210482Y94279D03*
X209530Y86046D03*
X205976Y85731D03*
X209726Y116594D03*
X201669Y103621D03*
X215669Y110784D03*
X209726Y119594D03*
X210160Y124283D03*
X215226Y124879D03*
X208567Y161306D03*
X200323Y152562D03*
X205818Y157370D03*
X209902Y176665D03*
Y168665D03*
X202001Y186629D03*
X209902Y196665D03*
Y192665D03*
X210015Y186778D03*
X209934Y204864D03*
Y208864D03*
X214983Y218085D03*
X205575Y219379D03*
X206203Y228631D03*
X211691Y248371D03*
X200109Y265897D03*
X202609D03*
X204675Y382109D03*
X204674Y551683D03*
Y558917D03*
Y561420D03*
X200495Y577937D03*
X208500Y595500D03*
X203500Y606929D03*
X208000Y604567D03*
X203460Y618400D03*
X203741Y612592D03*
X209158Y610072D03*
X209094Y616317D03*
X208540Y621591D03*
X205941Y668934D03*
X201115Y695581D03*
X203046Y693716D03*
X213969Y1447453D03*
Y1461853D03*
Y1458453D03*
Y1450853D03*
X231312Y97667D03*
X221695Y116594D03*
X226968Y102495D03*
X220669Y110784D03*
X221695Y119594D03*
X225229Y125107D03*
X220248Y124663D03*
X226702Y142862D03*
X227743Y148717D03*
X221592Y138838D03*
X230291Y195176D03*
X230372Y210509D03*
X224362Y226320D03*
X224296Y216970D03*
Y219470D03*
Y221970D03*
X221583Y216385D03*
X217783Y218085D03*
X232064Y230556D03*
X227323Y228646D03*
X231049Y242078D03*
X226280Y232971D03*
X220310Y249108D03*
X222930Y244571D03*
X233417Y253198D03*
X230842Y313888D03*
X233258Y359186D03*
X228267Y396718D03*
X221375Y455024D03*
X220349Y465622D03*
X225500Y530000D03*
X225000Y540500D03*
X224000Y547075D03*
X224200Y549800D03*
X223500Y568000D03*
X224104Y562800D03*
X224040Y558800D03*
X221693Y594982D03*
X222289Y590895D03*
X220333Y617930D03*
X220255Y629749D03*
X217906Y1430452D03*
Y1427052D03*
X219525Y1440028D03*
X216125D03*
X227249Y1447453D03*
Y1450853D03*
Y1458453D03*
Y1461853D03*
X224780Y1478149D03*
X217985Y1483055D03*
X225765Y1471985D03*
X233313Y1476699D03*
X221899Y1488800D03*
X218021Y1494724D03*
X222843Y1498442D03*
X217614Y1489671D03*
X233180Y1486442D03*
X233166Y1491454D03*
X226135Y1502442D03*
X230758Y1505046D03*
X226971Y1514578D03*
X227552Y1530675D03*
X232622Y1531104D03*
X226971Y1522578D03*
X219981Y1530797D03*
X223322Y1518578D03*
X222119Y1539941D03*
X227882Y1540816D03*
X233753Y1539752D03*
X239772Y103411D03*
X240166Y97667D03*
X235562Y95111D03*
X239931Y106561D03*
X233843Y143762D03*
X232791Y195176D03*
X235291D03*
X237309Y199248D03*
X234309D03*
X237791Y195176D03*
X237309Y202048D03*
X232872Y210509D03*
X234645Y206806D03*
X232145D03*
X234309Y201748D03*
X240909Y230117D03*
X236319Y227824D03*
X236925Y238714D03*
X236406Y246874D03*
X238626Y244297D03*
X234986Y336161D03*
X236264Y342494D03*
X245362Y546712D03*
Y542712D03*
X247536Y602689D03*
X247278Y618288D03*
X243278D03*
X240194Y643113D03*
X242102Y656321D03*
X250102D03*
X246102D03*
X245000Y678462D03*
X244267Y696911D03*
X235790Y754332D03*
X241204Y814841D03*
X237591Y815266D03*
X248556Y824003D03*
X246311Y819000D03*
X238400Y836900D03*
X234976Y1481676D03*
X243535Y1511473D03*
X245500Y1517033D03*
X237633Y1511909D03*
X244600Y1531700D03*
X240808Y1519942D03*
X235687Y1522578D03*
X237580Y1528604D03*
X245937Y1524237D03*
X239949Y1541327D03*
X244912Y1539389D03*
X250962Y90650D03*
X256274Y90615D03*
X260595Y99961D03*
X260645Y95236D03*
X250712D03*
X259457Y210478D03*
Y207978D03*
Y215478D03*
Y212978D03*
X262786Y264180D03*
X262711Y258880D03*
X257993Y307994D03*
X256475Y422088D03*
X252695Y442956D03*
X254512Y438323D03*
X261965Y458455D03*
X250336Y456386D03*
X254678Y445873D03*
X263301Y444232D03*
X262526Y451108D03*
X249125Y465874D03*
X252688Y636364D03*
X248690Y678519D03*
X248090Y691114D03*
X254634Y698241D03*
X248506Y812042D03*
X256303Y812254D03*
X250700Y819900D03*
X254058Y819851D03*
X255289Y824340D03*
X252305Y831018D03*
X252100Y836800D03*
X250876Y1532782D03*
X255909Y1542043D03*
X250790Y1539759D03*
X269509Y77393D03*
Y74793D03*
Y85193D03*
Y82593D03*
Y79993D03*
X277834Y98551D03*
X269553Y92874D03*
X271580Y107649D03*
Y104249D03*
X276146Y147540D03*
X279918Y141247D03*
X268602Y162368D03*
X271202D03*
X278302Y162793D03*
Y165393D03*
Y167993D03*
Y170493D03*
X277299Y181426D03*
X280124Y184012D03*
X277507Y184221D03*
X269913Y210713D03*
X273985Y208695D03*
X276785D03*
X273985Y211695D03*
X276485D03*
X269913Y208213D03*
Y213213D03*
Y215713D03*
X265286Y264180D03*
X280162Y265701D03*
X276980Y267526D03*
Y270026D03*
X271680Y267526D03*
X274480D03*
Y270026D03*
X271680D03*
X281797Y281716D03*
X277575Y395084D03*
X274425Y381500D03*
X278784Y435158D03*
X278529Y440489D03*
X274949Y442606D03*
X278827Y444841D03*
X282230Y458572D03*
X265011Y453881D03*
X280220Y448493D03*
X274866Y446606D03*
X265011Y446595D03*
X275873Y463479D03*
X276344Y467367D03*
X274096Y820725D03*
X274697Y830951D03*
X275123Y847874D03*
X269700Y853100D03*
X275400Y864400D03*
X278400Y890839D03*
X275400Y899400D03*
X279261Y926339D03*
X278739Y936439D03*
X289797Y36735D03*
X290113Y23188D03*
X284666Y34068D03*
X289631Y28281D03*
X293930Y76587D03*
Y72615D03*
X295369Y100625D03*
X288388Y97475D03*
X281384Y103783D03*
X288319Y106186D03*
X295948Y141247D03*
X287385Y143740D03*
X284765Y148277D03*
X285807Y172190D03*
X280510Y181366D03*
X283305Y181009D03*
X288480Y168697D03*
X285226Y177616D03*
X289568Y191941D03*
X297622Y192490D03*
X291577Y206767D03*
X294077D03*
X296577D03*
X285246Y213132D03*
X281543Y211359D03*
Y213859D03*
X296707Y221708D03*
X292822Y228221D03*
Y231021D03*
X294207Y221708D03*
X291122Y224421D03*
X291707Y221708D03*
X285246Y215632D03*
X293373Y236189D03*
X295873D03*
X293314Y248765D03*
X295814D03*
X285490Y256303D03*
X290265Y266114D03*
X285249Y265896D03*
X296011Y270695D03*
X293511D03*
Y268195D03*
X296011D03*
X287738Y281982D03*
X286940Y315039D03*
X297719Y339559D03*
X291396Y350223D03*
X292520Y384410D03*
X292358Y393858D03*
X298000Y391496D03*
X295699Y382047D03*
X296000Y403500D03*
X298000Y409000D03*
X294000Y398583D03*
X295253Y440869D03*
Y438269D03*
X292453D03*
Y440869D03*
Y435669D03*
Y430469D03*
Y433069D03*
X295253D03*
Y430469D03*
Y435669D03*
X293307Y451677D03*
X295807D03*
X293307Y454177D03*
X295807D03*
X295011Y460218D03*
Y463618D03*
X281980Y953926D03*
X312256Y37543D03*
X305610Y55513D03*
X301835Y68581D03*
X310817Y60393D03*
X307916Y60529D03*
X301848Y80581D03*
X305978Y88801D03*
X312844Y94279D03*
X308895Y94351D03*
X308338Y85731D03*
X311892Y86046D03*
X312088Y116594D03*
X299742Y112083D03*
X304031Y103621D03*
X312088Y119594D03*
X312522Y124283D03*
X300435Y143518D03*
X299535Y152373D03*
X310929Y161306D03*
X302685Y152562D03*
X308180Y157370D03*
X312264Y176665D03*
Y168665D03*
X303377Y183834D03*
X303550Y172665D03*
X303487Y178560D03*
X304363Y186629D03*
X302897Y190185D03*
X312264Y196665D03*
Y192665D03*
X303667Y200864D03*
X312377Y186778D03*
X300814Y192859D03*
X312296Y204864D03*
Y208864D03*
X303756Y212455D03*
X303690Y207037D03*
X301057Y221642D03*
X307937Y219379D03*
X308565Y228631D03*
X298373Y236189D03*
X298314Y248765D03*
X302471Y265897D03*
X304971D03*
X298811Y270695D03*
Y268195D03*
X315079Y314890D03*
X312263Y324518D03*
X301943Y328867D03*
X308952Y356875D03*
X312316Y356747D03*
X299000Y377912D03*
Y386500D03*
X299088Y397912D03*
X322847Y19806D03*
X321840Y14408D03*
X322113Y26187D03*
X316751Y86012D03*
Y94374D03*
X324057Y116594D03*
X318031Y110784D03*
X323031D03*
X324057Y119594D03*
X327591Y125107D03*
X322610Y124663D03*
X317588Y124879D03*
X329064Y142862D03*
X330105Y148717D03*
X323954Y138838D03*
X317345Y218085D03*
X320145D03*
X323945Y216385D03*
X326658Y216970D03*
Y219470D03*
X326724Y226320D03*
X326658Y221970D03*
X329685Y228646D03*
X328642Y232971D03*
X322672Y249108D03*
X325292Y244571D03*
X314053Y248371D03*
X327032Y303962D03*
X314855Y311740D03*
X318508Y324322D03*
X315944Y332584D03*
X316067Y347937D03*
X321416Y348015D03*
X317333Y353470D03*
X318500Y356519D03*
X315310Y356712D03*
X318660Y539315D03*
X320785Y553287D03*
X327456Y550065D03*
X321119Y622912D03*
X330905Y15806D03*
Y19806D03*
Y27806D03*
X333674Y97667D03*
X342134Y103411D03*
X342528Y97667D03*
X337924Y95111D03*
X329330Y102495D03*
X342293Y106561D03*
X336205Y143762D03*
X335153Y195176D03*
X332653D03*
X336671Y199248D03*
X337653Y195176D03*
X340153D03*
X339671Y199248D03*
X336671Y201748D03*
X334507Y206806D03*
X337007D03*
X335234Y210509D03*
X332734D03*
X339671Y202048D03*
X343271Y230117D03*
X338681Y227824D03*
X334426Y230556D03*
X339287Y238714D03*
X333411Y242078D03*
X338768Y246874D03*
X340988Y244297D03*
X332635Y256394D03*
X347058Y399918D03*
X339072Y416888D03*
Y419488D03*
Y422088D03*
X345050Y454334D03*
X337078Y551381D03*
X335399Y544718D03*
X333985Y1017945D03*
X341077Y1018056D03*
X339251Y1138130D03*
X336755Y1143489D03*
X340500Y1147500D03*
X335190Y1173065D03*
X341266Y1171956D03*
X330800Y1174500D03*
X343121Y1188412D03*
X342009Y1176100D03*
X339776Y1187962D03*
X335502Y1188222D03*
X339540Y1196894D03*
X358636Y90615D03*
X353324Y90650D03*
X362957Y99961D03*
X353074Y95236D03*
X359376Y290592D03*
X348351Y319372D03*
X348806Y315427D03*
X351132Y322202D03*
X349120Y336100D03*
X351136Y372334D03*
X350486Y377173D03*
X358491D03*
X347591Y391533D03*
X359486Y385123D03*
X349311Y385644D03*
X354486Y385123D03*
X357655Y405889D03*
Y408489D03*
X358248Y403300D03*
X353894Y406060D03*
X354155Y421489D03*
Y418889D03*
Y416289D03*
X350163Y412106D03*
X357655Y413689D03*
Y416289D03*
Y421489D03*
Y418889D03*
Y424089D03*
Y411089D03*
X358042Y432718D03*
X357655Y426689D03*
X358042Y435518D03*
X358754Y450091D03*
X356241Y447001D03*
X359241D03*
X353320Y454214D03*
X353663Y449045D03*
X353367Y459330D03*
X358754Y462060D03*
X353670Y473571D03*
Y481071D03*
Y478571D03*
Y476071D03*
X360242Y477053D03*
X357742D03*
X358207Y836462D03*
X346366Y1134729D03*
X361621D03*
X349748D03*
X357748D03*
X353748D03*
X352545Y1142666D03*
X360877Y1157404D03*
X354420Y1157544D03*
X352931Y1167768D03*
X357950D03*
X357057Y1179542D03*
X357796Y1188058D03*
X357083Y1185205D03*
X361792Y1187310D03*
X348432Y1187215D03*
X348125Y1180175D03*
X358368Y1201043D03*
X354398D03*
X350402D03*
X346387Y1199256D03*
X360523Y1192282D03*
X349276Y1217228D03*
X351940Y1219895D03*
X362332Y1230265D03*
X355215Y1223170D03*
X360273Y1228226D03*
X358062Y1226016D03*
X371871Y85193D03*
Y82593D03*
Y79993D03*
Y77393D03*
Y74793D03*
X371915Y92874D03*
X363007Y95236D03*
X373942Y104249D03*
Y107649D03*
X370964Y162368D03*
X373564D03*
X372275Y208213D03*
X379147Y208695D03*
X376347D03*
Y211695D03*
X372275Y210713D03*
Y213213D03*
X361819Y207978D03*
Y212978D03*
Y215478D03*
Y210478D03*
X372275Y215713D03*
X367648Y264180D03*
X365148D03*
X365073Y258880D03*
X374042Y270026D03*
X376842D03*
X374042Y267526D03*
X376842D03*
X371417Y353820D03*
X365559Y354300D03*
X377237Y371060D03*
X373264Y379429D03*
X378875Y379088D03*
X366526Y377173D03*
X370486D03*
X362486Y385123D03*
X366486D03*
X370160Y391569D03*
X368587Y401066D03*
X378927Y406739D03*
X367919Y439318D03*
X375919Y442118D03*
Y439318D03*
X367919Y442118D03*
X361754Y450091D03*
X367564Y456034D03*
Y461034D03*
X373546Y470001D03*
X376046D03*
X361754Y462060D03*
X373971Y489036D03*
X371832Y485580D03*
X374332D03*
X376832D03*
X366420Y479986D03*
Y477486D03*
X363686Y478668D03*
Y476168D03*
X376207Y492836D03*
Y495636D03*
X376881Y518564D03*
X363015Y710365D03*
X365887Y710329D03*
X372400Y746300D03*
X372300Y750000D03*
X373500Y767300D03*
X376300D03*
X370415Y766108D03*
X373703Y782555D03*
X365850Y773950D03*
X371436Y791188D03*
X365691Y815127D03*
X371507Y815303D03*
X362042Y814772D03*
X368067Y925136D03*
X370214Y943812D03*
X368626Y931346D03*
X368964Y937738D03*
X372858Y935136D03*
X366761Y934550D03*
X363893Y946863D03*
X379928Y949774D03*
X379245Y956643D03*
X378875Y961862D03*
X370214Y947812D03*
X370101Y953699D03*
X370214Y963812D03*
Y971812D03*
X378928Y967812D03*
X372501Y1123695D03*
X365748Y1134325D03*
X368657Y1150087D03*
X366133Y1170767D03*
X366429Y1185238D03*
X366222Y1180235D03*
X362402Y1201039D03*
X366402Y1200969D03*
X366521Y1208993D03*
X370202Y1314764D03*
Y1311364D03*
X383612Y33768D03*
X388612Y31168D03*
X387948Y27288D03*
X380196Y98551D03*
X390750Y97475D03*
X383746Y103783D03*
X390681Y106186D03*
X380664Y165393D03*
Y162793D03*
Y167993D03*
Y170493D03*
X387588Y177616D03*
X382872Y181366D03*
X379661Y181426D03*
X385667Y181009D03*
X390842Y168697D03*
X388169Y172190D03*
X391930Y191941D03*
X382486Y184012D03*
X379869Y184221D03*
X393939Y206767D03*
X383905Y211359D03*
X387608Y213132D03*
X378847Y211695D03*
X383905Y213859D03*
X394069Y221708D03*
X393484Y224421D03*
X387608Y215632D03*
X387852Y256303D03*
X387611Y265896D03*
X382524Y265701D03*
X392627Y266114D03*
X379342Y270026D03*
Y267526D03*
X384159Y281716D03*
X390100Y281982D03*
X391737Y377581D03*
X384173Y379028D03*
X381237Y371076D03*
X394237Y379591D03*
X391940Y383817D03*
Y388817D03*
Y386317D03*
X385864Y398278D03*
X383364D03*
X378927Y409539D03*
X381927D03*
Y407039D03*
X381591Y401981D03*
X384091D03*
X378210Y424067D03*
X380710D03*
X385710D03*
X383210D03*
X378445Y413611D03*
X380945D03*
X385945D03*
X383445D03*
X385584Y438293D03*
Y441093D03*
Y443893D03*
X393646Y474382D03*
X385634Y472020D03*
X393662Y470382D03*
X385694Y477318D03*
X385293Y466409D03*
X387141Y484882D03*
X385131Y487382D03*
X391470Y732865D03*
X380963Y731000D03*
X381875Y740341D03*
X379800Y769200D03*
X380331Y782627D03*
X380607Y786932D03*
X387958Y813700D03*
X381631Y814147D03*
X384666Y814103D03*
X383391Y804000D03*
X386589Y864408D03*
X383462Y860535D03*
X392584Y875845D03*
X382675Y870151D03*
X391614Y930676D03*
X384856Y947987D03*
X378119Y953696D03*
X392910Y948536D03*
X393998Y971780D03*
X378790Y1001083D03*
X380280Y1006071D03*
X383710Y1007283D03*
X382465Y1012430D03*
X378410Y1131573D03*
X380261Y1129692D03*
X385091Y1297453D03*
Y1300853D03*
X386415Y1321645D03*
X391691Y1326715D03*
X392234Y1369579D03*
Y1364501D03*
X391757Y1383480D03*
X391852Y1389931D03*
X393951Y1447455D03*
X381900Y1544800D03*
X389700Y1536900D03*
X391740Y1545629D03*
Y1540529D03*
X382017Y1559700D03*
X395296Y1561024D03*
X391740Y1550729D03*
Y1555829D03*
X410789Y22627D03*
X408680Y37530D03*
X396680Y37543D03*
X400714Y45448D03*
X404686D03*
X397731Y100625D03*
X402104Y112083D03*
X406393Y103621D03*
X405912Y172665D03*
X405739Y183834D03*
X405849Y178560D03*
X406725Y186629D03*
X399984Y192490D03*
X405259Y190185D03*
X406029Y200864D03*
X395942Y192300D03*
X398939Y206767D03*
X396439D03*
X406118Y212455D03*
X406052Y207037D03*
X395184Y228221D03*
X399069Y221708D03*
X396569D03*
X403419Y221642D03*
X395184Y231021D03*
X410299Y219379D03*
X410927Y228631D03*
X400735Y236189D03*
X398235D03*
X395735D03*
X400676Y248765D03*
X398176D03*
X395676D03*
X407333Y265897D03*
X404833D03*
X401173Y268195D03*
Y270695D03*
X398373Y268195D03*
X395873D03*
Y270695D03*
X398373D03*
X405843Y315158D03*
X403343D03*
X394883Y341777D03*
Y338377D03*
X410086Y336795D03*
X409655Y331589D03*
X410688Y344736D03*
X400993Y331589D03*
Y335589D03*
X400728Y353152D03*
X411007Y356743D03*
X406421Y387151D03*
Y382151D03*
Y384651D03*
X398453Y387702D03*
X401253D03*
X394653Y389402D03*
X395577Y438293D03*
Y441093D03*
Y443893D03*
X397315Y471560D03*
X405801Y475560D03*
X405301Y467560D03*
X397315Y475560D03*
X406200Y741300D03*
X397223Y796792D03*
X400023D03*
X397900Y789000D03*
X407000Y784700D03*
X404468Y864407D03*
X396306Y864409D03*
X406770Y869767D03*
X405466Y881299D03*
X397431Y870654D03*
X401108Y878487D03*
X401121Y929686D03*
X409121D03*
X401121Y932186D03*
X409121D03*
X405179Y959051D03*
X404971Y956256D03*
X402354Y956465D03*
X401968Y959111D03*
X399173Y959468D03*
X397252Y962861D03*
X404176Y977684D03*
Y975084D03*
Y969984D03*
Y972484D03*
X396671Y968287D03*
X406954Y982970D03*
X409554D03*
X404354D03*
X407547Y1058097D03*
X410047D03*
X405047D03*
X407547Y1060697D03*
X410047D03*
X405047D03*
X408989Y1082501D03*
X409015Y1087705D03*
Y1085205D03*
X408847Y1090956D03*
Y1093956D03*
X406895Y1107997D03*
X402695D03*
Y1110897D03*
X407780Y1113648D03*
X409231Y1118801D03*
X406995Y1110597D03*
X404895Y1112397D03*
X404795Y1109397D03*
X402695Y1113797D03*
X408961Y1162384D03*
Y1164884D03*
Y1167384D03*
Y1169884D03*
Y1172384D03*
X403263Y1160834D03*
X408961Y1174884D03*
X406319Y1186709D03*
Y1184209D03*
Y1181709D03*
Y1179209D03*
X404004Y1192621D03*
Y1190121D03*
X397063Y1221428D03*
X401063D03*
X405063D03*
X409063D03*
X397063Y1233428D03*
Y1229428D03*
Y1225428D03*
X401063Y1237428D03*
Y1233428D03*
Y1229428D03*
Y1225428D03*
X405063Y1237428D03*
Y1233428D03*
Y1229428D03*
Y1225428D03*
X409063Y1237428D03*
Y1233428D03*
Y1229428D03*
Y1225428D03*
X401063Y1241428D03*
X405063Y1245428D03*
Y1241428D03*
X409063Y1245428D03*
Y1241428D03*
X404324Y1271889D03*
Y1275889D03*
X407767Y1292198D03*
X403678Y1295426D03*
X398584Y1313443D03*
X401011Y1307258D03*
X402967Y1319815D03*
X409220Y1315516D03*
X404583Y1316131D03*
X404921Y1321819D03*
X408787Y1321795D03*
X399959Y1352153D03*
X408159Y1349072D03*
X404759D03*
X395112Y1395690D03*
X398340Y1399779D03*
X395770Y1389817D03*
X410172Y1402446D03*
X402489Y1417275D03*
X405889D03*
X407970Y1449751D03*
X404500Y1452500D03*
X395888Y1450022D03*
X395199Y1482223D03*
X395380Y1485778D03*
X397266Y1514647D03*
X398747Y1500959D03*
X395370Y1501022D03*
X397266Y1518047D03*
X408964Y1531149D03*
X394391Y1537786D03*
Y1535286D03*
X399373Y1555855D03*
X405496Y1561024D03*
X400396D03*
X410596D03*
X397461Y1569560D03*
X401461D03*
X416900Y33400D03*
X422473Y22627D03*
X422450Y30483D03*
X422378Y26534D03*
X414145Y27486D03*
X413904Y32569D03*
X426147Y147540D03*
X414626Y176665D03*
Y168665D03*
Y196665D03*
Y192665D03*
X414739Y186778D03*
X414658Y204864D03*
Y208864D03*
X423651Y307470D03*
X419177Y304470D03*
X415777D03*
X422988Y323627D03*
X415129Y325181D03*
X412671Y333418D03*
X412812Y330617D03*
X426830Y359026D03*
X426138Y355079D03*
X416574Y357528D03*
X421413Y359053D03*
X412318Y367903D03*
X420422Y367859D03*
X418997Y382210D03*
Y384710D03*
Y387210D03*
X422215Y424939D03*
Y427439D03*
X414924Y435321D03*
Y438121D03*
X412124Y435321D03*
Y438121D03*
X414924Y440921D03*
X412124D03*
X414924Y443721D03*
X412124D03*
X426647Y452987D03*
X421267Y452799D03*
X414910Y448931D03*
X415433Y459170D03*
X425673Y461607D03*
X424876Y471334D03*
X418801Y474513D03*
X414275Y492469D03*
X424731Y492704D03*
X414275Y497469D03*
Y499969D03*
X427693Y498943D03*
X424731Y497704D03*
Y495204D03*
Y500204D03*
X414275Y494969D03*
X419340Y549990D03*
X419140Y547390D03*
Y544790D03*
X419340Y552590D03*
Y555190D03*
X423963Y625778D03*
X426607Y712360D03*
Y709760D03*
X424993Y728291D03*
X423700Y795500D03*
X426300Y797400D03*
X421200Y786400D03*
X411267Y829193D03*
Y831693D03*
X416267D03*
X413767D03*
Y829193D03*
X416267D03*
X425062Y883981D03*
X417121Y929686D03*
X425121D03*
X417121Y932186D03*
X425121D03*
X411960Y962261D03*
X414560D03*
X417160D03*
X411276Y978109D03*
X416476D03*
X413876D03*
X415047Y1058097D03*
X412547D03*
X415047Y1060697D03*
X412547D03*
X411989Y1082501D03*
X412015Y1085205D03*
X414989Y1082501D03*
X415015Y1085205D03*
Y1088205D03*
X412015D03*
X412297Y1091227D03*
X425060Y1101917D03*
X420782Y1105552D03*
X423340Y1104335D03*
X424995Y1106897D03*
X416988Y1104792D03*
X418495Y1106867D03*
X414580Y1113648D03*
X412080D03*
X411461Y1162384D03*
Y1164884D03*
Y1167384D03*
Y1169884D03*
Y1172384D03*
X420619Y1179421D03*
Y1181921D03*
Y1184421D03*
Y1186921D03*
X411461Y1174884D03*
X422934Y1192621D03*
Y1190121D03*
X417469Y1192621D03*
Y1190121D03*
X413063Y1221428D03*
X417063D03*
X421063D03*
X425063D03*
X413063Y1237428D03*
Y1233428D03*
Y1229428D03*
Y1225428D03*
X417063Y1237428D03*
Y1233428D03*
Y1229428D03*
Y1225428D03*
X421063Y1237428D03*
Y1233428D03*
Y1229428D03*
Y1225428D03*
X425063Y1237428D03*
Y1233428D03*
Y1229428D03*
Y1225428D03*
X413063Y1245428D03*
Y1241428D03*
X417063Y1245428D03*
Y1241428D03*
X421063Y1245428D03*
Y1241428D03*
X425063Y1245428D03*
Y1241428D03*
X425702Y1257160D03*
X422702Y1260160D03*
Y1257160D03*
X425702Y1260160D03*
X419702Y1257160D03*
Y1260160D03*
X413526Y1288938D03*
X419977Y1288843D03*
X413640Y1292856D03*
X419545Y1317722D03*
X413127Y1318011D03*
X425283Y1364023D03*
X417305Y1359169D03*
X425855Y1360495D03*
X425912Y1357141D03*
X416029Y1371572D03*
X420636Y1383912D03*
X418610Y1371590D03*
X423400Y1394500D03*
X423200Y1397500D03*
X418430Y1394237D03*
X422729Y1400490D03*
X420925Y1390330D03*
X419045Y1398874D03*
X421300Y1415400D03*
X419100Y1402200D03*
X421200Y1417900D03*
X411000Y1463500D03*
Y1460500D03*
Y1457500D03*
Y1454500D03*
Y1451000D03*
X413934Y1477101D03*
X417334D03*
X415202Y1496118D03*
Y1499518D03*
X417153Y1516886D03*
X413753D03*
X419619Y1539978D03*
X421454Y1544625D03*
X422539Y1534361D03*
X426701Y1541947D03*
X418151Y1552470D03*
X417461Y1569584D03*
X429919Y141247D03*
X437386Y143740D03*
X434766Y148277D03*
X431525Y304470D03*
X434925D03*
X427051Y307470D03*
X441296Y325061D03*
X436666Y322583D03*
X427713Y321965D03*
X430361Y323187D03*
X443424Y332988D03*
X440538Y355372D03*
X428420Y353578D03*
X435886Y353867D03*
X431524Y370309D03*
X434924D03*
X428637Y408104D03*
X431437D03*
X434237D03*
X428354Y420375D03*
X431154D03*
X433954D03*
X438098Y442114D03*
X437835Y435101D03*
X432270Y431112D03*
X432440Y440101D03*
X432075Y452718D03*
X438086Y452601D03*
X438078Y447121D03*
X433673Y461607D03*
X429673D03*
X435789Y501525D03*
X427568Y502003D03*
X435831Y498923D03*
X438644Y500461D03*
X428740Y549990D03*
X442804Y546990D03*
Y544390D03*
X428740Y546990D03*
Y544390D03*
Y555190D03*
Y552590D03*
X431384D03*
Y555190D03*
Y544390D03*
Y546990D03*
Y549990D03*
X443144Y628667D03*
X441162Y638313D03*
X439290Y712399D03*
X436790D03*
X439290Y709799D03*
X436790D03*
X434290Y712399D03*
Y709799D03*
X429290D03*
X431790Y712399D03*
X429290D03*
X431790Y709799D03*
X429253Y759847D03*
X432303Y785067D03*
X434100Y797400D03*
X430600D03*
X443091Y1026266D03*
X432678Y1016186D03*
X429878D03*
X427078D03*
X427052Y1019384D03*
X429852D03*
X432652D03*
X433378Y1091816D03*
Y1089316D03*
X430878Y1084316D03*
Y1086816D03*
X433378D03*
Y1084316D03*
X436244Y1090288D03*
X433378Y1081816D03*
X430878D03*
X429677Y1106955D03*
X439023Y1107997D03*
X436244Y1093088D03*
X434823Y1107997D03*
X431476Y1115896D03*
X427810Y1110092D03*
X439908Y1113648D03*
X441359Y1116101D03*
Y1118801D03*
X439123Y1110597D03*
X434823Y1113797D03*
Y1110897D03*
X437023Y1112397D03*
X436923Y1109397D03*
X431476Y1118396D03*
X429348Y1129092D03*
X432838Y1128821D03*
X436789Y1167384D03*
Y1164884D03*
Y1162384D03*
Y1172384D03*
Y1169884D03*
X439289Y1167384D03*
Y1164884D03*
Y1162384D03*
X427231D03*
X429731D03*
Y1164884D03*
Y1167384D03*
Y1169884D03*
Y1172384D03*
X427231D03*
Y1169884D03*
Y1167384D03*
Y1164884D03*
X439289Y1172384D03*
Y1169884D03*
X437132Y1158266D03*
X433249Y1186709D03*
Y1184209D03*
Y1181709D03*
Y1179209D03*
X429731Y1174884D03*
X427231D03*
X436789D03*
X439289D03*
X430934Y1190121D03*
Y1192621D03*
X429063Y1221428D03*
X433063D03*
X429063Y1237428D03*
Y1233428D03*
Y1229428D03*
Y1225428D03*
X433063Y1237428D03*
Y1233428D03*
Y1229428D03*
Y1225428D03*
X429063Y1245428D03*
Y1241428D03*
X433063Y1245428D03*
Y1241428D03*
X440702Y1260160D03*
Y1257160D03*
X437702Y1260160D03*
Y1257160D03*
X428702D03*
X431702Y1260160D03*
Y1257160D03*
X434702Y1260160D03*
Y1257160D03*
X428702Y1260160D03*
X434424Y1286274D03*
X430527Y1289198D03*
X440906D03*
X431867Y1315696D03*
X431885Y1313115D03*
X439434Y1322369D03*
X429530Y1325051D03*
X445949Y141247D03*
X450436Y143518D03*
X449536Y152373D03*
X452686Y152562D03*
X458181Y157370D03*
X443508Y337713D03*
X446566Y337917D03*
X443480Y344014D03*
X450852Y372054D03*
X455885Y367702D03*
X448391Y382641D03*
X448323Y379643D03*
X451144Y468809D03*
X459414Y468689D03*
X459757Y463520D03*
X459461Y473805D03*
X459929Y491669D03*
X450942Y506449D03*
X448442D03*
X445942D03*
X460537Y501905D03*
X459952Y496842D03*
X459645Y509486D03*
X446025Y511512D03*
X448525D03*
X446025Y519699D03*
X448525D03*
X452404Y549790D03*
X443004Y549890D03*
X452404Y546990D03*
Y544390D03*
X443004Y555090D03*
X452404Y552390D03*
Y554990D03*
X443004Y552490D03*
X455009Y554912D03*
Y552312D03*
Y544312D03*
Y546912D03*
Y549712D03*
X447279Y637031D03*
X447921Y630789D03*
X453552Y631779D03*
X446987Y643360D03*
X456469Y638302D03*
X460498Y870334D03*
X458120Y974701D03*
X451460Y974695D03*
X450591Y1004766D03*
X453270Y1003763D03*
X459360Y1012325D03*
X443591Y1019766D03*
X459885Y1018860D03*
X451140Y1021793D03*
X447091Y1019766D03*
X450875Y1028416D03*
X443091Y1034266D03*
X452091Y1039880D03*
X459700Y1032266D03*
X455468Y1104335D03*
X457188Y1101917D03*
X452910Y1105552D03*
X457123Y1106897D03*
X449116Y1104792D03*
X450623Y1106867D03*
X444208Y1113648D03*
X446708D03*
X457559Y1169884D03*
Y1167384D03*
Y1164884D03*
Y1162384D03*
X455059D03*
Y1164884D03*
Y1167384D03*
Y1169884D03*
Y1172384D03*
X457559D03*
X455059Y1174884D03*
X457559D03*
X447549Y1179421D03*
Y1181921D03*
Y1184421D03*
Y1186921D03*
X449864Y1190121D03*
Y1192621D03*
X449702Y1260160D03*
Y1257160D03*
X443702Y1260160D03*
X446702D03*
Y1257160D03*
X443702D03*
X451304Y1297045D03*
X454385Y1301845D03*
Y1305245D03*
X444288Y1314391D03*
X462089Y116594D03*
X474058D03*
X473032Y110784D03*
X468032D03*
X462089Y119594D03*
X474058D03*
X477592Y125107D03*
X462523Y124283D03*
X467589Y124879D03*
X472611Y124663D03*
X473955Y138838D03*
X460930Y161306D03*
X467346Y218085D03*
X470146D03*
X473946Y216385D03*
X475293Y244571D03*
X472673Y249108D03*
X464054Y248371D03*
X460950Y328185D03*
Y324785D03*
X463950Y332659D03*
Y336059D03*
X460950Y343933D03*
Y340533D03*
X472810Y347995D03*
X472913Y360089D03*
X472608Y352495D03*
X467335Y359944D03*
X463950Y351807D03*
Y348407D03*
X472913Y369089D03*
Y373589D03*
X469530Y366754D03*
X472913Y387089D03*
Y391589D03*
Y382589D03*
Y378089D03*
X470796Y394592D03*
X464848Y464566D03*
X467848D03*
X465126Y460435D03*
X462126D03*
X473658Y470509D03*
Y475509D03*
X467848Y476535D03*
X464848D03*
X468558Y495669D03*
Y499669D03*
Y516609D03*
X464199Y510184D03*
X468850Y545586D03*
X469300Y799500D03*
X459245Y807152D03*
X473654Y821234D03*
X472399Y839566D03*
X463404Y846870D03*
X465492Y861970D03*
X471726Y883705D03*
X474540Y927341D03*
X471110Y921577D03*
X471876Y937236D03*
X471068Y930235D03*
X473992Y952546D03*
X475018Y992568D03*
X467345Y996480D03*
X459360Y1004680D03*
X464795Y1000647D03*
X462185Y1016825D03*
X459860Y1015825D03*
X464385Y1038534D03*
X471558Y1029482D03*
X471755Y1038665D03*
X470610Y1033783D03*
X475588Y1043055D03*
X473639Y1030952D03*
X459700Y1035716D03*
X470978Y1046591D03*
X474348Y1090171D03*
X462913Y1106365D03*
X474277Y1093048D03*
X472482Y1107997D03*
X468282D03*
X459938Y1110092D03*
X463604Y1115896D03*
X473367Y1113648D03*
X474818Y1116101D03*
Y1118801D03*
X472582Y1110597D03*
X470482Y1112397D03*
X468282Y1110897D03*
Y1113797D03*
X470382Y1109397D03*
X463604Y1118396D03*
X462687Y1160834D03*
X474548Y1172384D03*
Y1169884D03*
Y1167384D03*
Y1164884D03*
Y1162384D03*
X468850Y1160834D03*
X474548Y1174884D03*
X465785Y1197471D03*
X461285Y1193471D03*
Y1197471D03*
X465785Y1193471D03*
X474647Y1260160D03*
Y1257160D03*
X471647D03*
Y1260160D03*
X459290Y1297035D03*
X463290D03*
X492135Y103411D03*
X492529Y97667D03*
X483675D03*
X487925Y95111D03*
X479331Y102495D03*
X479065Y142862D03*
X486206Y143762D03*
X480106Y148717D03*
X487654Y195176D03*
X489672Y199248D03*
X485154Y195176D03*
X482654D03*
X486672Y199248D03*
X490154Y195176D03*
X485235Y210509D03*
X482735D03*
X489672Y202048D03*
X486672Y201748D03*
X484508Y206806D03*
X487008D03*
X476659Y216970D03*
Y219470D03*
X476725Y226320D03*
X476659Y221970D03*
X493272Y230117D03*
X484427Y230556D03*
X488682Y227824D03*
X479686Y228646D03*
X483412Y242078D03*
X478643Y232971D03*
X488769Y246874D03*
X489288Y238714D03*
X490989Y244297D03*
X482636Y256394D03*
X492817Y357111D03*
X491843Y351089D03*
X481724Y373589D03*
Y369089D03*
X490885Y373589D03*
X491053Y365423D03*
X491289Y391589D03*
X481724Y382589D03*
Y378089D03*
X490885Y382570D03*
X490985Y412342D03*
X488438Y418417D03*
X485485Y439903D03*
X489485D03*
X481485Y439900D03*
Y431917D03*
X489485Y431417D03*
X492736Y491982D03*
X482836Y534249D03*
X491818Y534909D03*
X491445Y541135D03*
X482905Y527726D03*
Y548726D03*
Y544726D03*
X491534Y552726D03*
X491511Y546553D03*
X487209Y611071D03*
X484772Y621311D03*
X493392Y622285D03*
X493580Y616905D03*
X484772Y629311D03*
Y625311D03*
X493661Y627713D03*
X493778Y633724D03*
X481165Y646036D03*
X483059Y662649D03*
X488765Y667224D03*
X481742Y657477D03*
X486837Y701306D03*
Y704706D03*
X489406Y797558D03*
X489572Y822805D03*
X479448Y828594D03*
X479700Y847600D03*
X477574Y860815D03*
X490706Y859339D03*
X491616Y938771D03*
X476475Y952249D03*
X479613Y952189D03*
X489163Y977163D03*
X487091Y989550D03*
X480711Y999941D03*
X477857Y1004375D03*
X488041Y1020440D03*
X485678Y1039880D03*
X485633Y1036155D03*
X477765Y1093432D03*
X477607Y1089942D03*
X491503Y1086796D03*
Y1084296D03*
X478517Y1086724D03*
Y1084224D03*
Y1081724D03*
X476017D03*
Y1084224D03*
Y1086724D03*
X486369Y1105552D03*
X490647Y1101917D03*
X488927Y1104335D03*
X490582Y1106897D03*
X482575Y1104792D03*
X484082Y1106867D03*
X480167Y1113648D03*
X477667D03*
X477048Y1172384D03*
Y1169884D03*
Y1167384D03*
Y1164884D03*
Y1162384D03*
X479521Y1179209D03*
Y1181709D03*
Y1184209D03*
Y1186709D03*
X477048Y1174884D03*
X490671Y1192621D03*
Y1190121D03*
X477206Y1192621D03*
Y1190121D03*
X489647Y1260160D03*
Y1257160D03*
X486647D03*
Y1260160D03*
X480647Y1257160D03*
X477647D03*
Y1260160D03*
X480647D03*
X483647Y1257160D03*
Y1260160D03*
X490100Y1302100D03*
X487600D03*
X503325Y90650D03*
X508637Y90615D03*
X503075Y95236D03*
X492294Y106561D03*
X496023Y362913D03*
X497048Y369450D03*
X495750Y377531D03*
X506500Y379687D03*
X495203Y386890D03*
X503729Y439919D03*
X503682Y448419D03*
X500729Y469905D03*
X496729Y470419D03*
X504729Y469905D03*
X496729Y461919D03*
X504729Y461419D03*
X505476Y485128D03*
X497095Y481467D03*
X501224Y492050D03*
X501649Y482165D03*
X501887Y504825D03*
X499387D03*
X496887D03*
X500890Y500202D03*
X502493Y495917D03*
X492736Y495982D03*
X501828Y517401D03*
X499328D03*
X496828D03*
X502379Y522569D03*
X495444Y531948D03*
X503494Y531882D03*
X502379Y525369D03*
X500994Y531882D03*
X498494D03*
X504079Y529169D03*
X503729Y555194D03*
X500929D03*
Y571194D03*
X503729D03*
Y563194D03*
X500929D03*
X505286Y581222D03*
X502486D03*
X505286Y591215D03*
X502486D03*
X505458Y610562D03*
X502658D03*
Y607762D03*
X505458D03*
X497448Y610548D03*
X504265Y633736D03*
X499258Y633716D03*
X506278Y628078D03*
X494465Y657772D03*
X502755Y657694D03*
X496070Y665976D03*
X499528Y657843D03*
X504966Y678098D03*
X498284Y681453D03*
Y678953D03*
X500714Y708755D03*
X502832Y720491D03*
X504895Y770457D03*
X501495D03*
X504508Y783817D03*
X506166Y793224D03*
X504641Y789139D03*
X507095Y814784D03*
X494677Y830468D03*
X509665Y824512D03*
X495073Y835586D03*
X495470Y844271D03*
X495700Y849389D03*
X503383Y863025D03*
X498507Y865392D03*
X508248Y873319D03*
X509791Y881932D03*
X509017Y905295D03*
X494315Y941212D03*
X503144Y957934D03*
X504088Y985171D03*
X506888D03*
X506702Y978947D03*
X493091Y989550D03*
X503933Y981392D03*
X498435Y1008766D03*
X506566D03*
Y996766D03*
X498524Y997590D03*
X498585Y1016266D03*
X506566Y1012266D03*
X503177Y1058097D03*
X495677D03*
X493177D03*
X498177D03*
X500677D03*
X503177Y1060697D03*
X495677D03*
X493177D03*
X498177D03*
X500677D03*
X494003Y1086796D03*
X496503D03*
X499003D03*
X501503D03*
Y1084296D03*
X499003D03*
X496503D03*
X494003D03*
X501831Y1090288D03*
X496372Y1106298D03*
X504610Y1107997D03*
X501831Y1093088D03*
X500410Y1107997D03*
X497063Y1115896D03*
X505495Y1113648D03*
X506946Y1116101D03*
Y1118801D03*
X504710Y1110597D03*
X500410Y1113797D03*
X502610Y1112397D03*
X500410Y1110897D03*
X502510Y1109397D03*
X493397Y1110092D03*
X497063Y1118396D03*
X498727Y1128759D03*
X495236Y1129094D03*
X502376Y1172384D03*
Y1169884D03*
Y1167384D03*
Y1164884D03*
Y1162384D03*
X504876Y1172384D03*
Y1169884D03*
Y1167384D03*
Y1164884D03*
Y1162384D03*
X492818D03*
Y1164884D03*
Y1167384D03*
Y1169884D03*
Y1172384D03*
X495318D03*
Y1169884D03*
Y1167384D03*
Y1164884D03*
Y1162384D03*
X502562Y1158200D03*
X506451Y1179209D03*
Y1181709D03*
Y1184209D03*
Y1186709D03*
X504876Y1174884D03*
X493821Y1186921D03*
Y1184421D03*
Y1181921D03*
Y1179421D03*
X492818Y1174884D03*
X495318D03*
X502376D03*
X504136Y1190121D03*
Y1192621D03*
X496136Y1190121D03*
Y1192621D03*
X506562Y1222194D03*
X502562D03*
X498562D03*
X494562D03*
X506562Y1226194D03*
Y1230194D03*
Y1234194D03*
Y1238194D03*
X502562Y1226194D03*
Y1230194D03*
Y1234194D03*
Y1238194D03*
X498562Y1226194D03*
Y1230194D03*
Y1234194D03*
Y1238194D03*
X494562Y1226194D03*
Y1230194D03*
Y1234194D03*
Y1238194D03*
Y1246194D03*
Y1242194D03*
X506562D03*
Y1246194D03*
X502562Y1242194D03*
Y1246194D03*
X498562Y1242194D03*
Y1246194D03*
X504647Y1257160D03*
X507347D03*
X501647D03*
Y1260160D03*
X495647D03*
X492647D03*
Y1257160D03*
X495647D03*
X498647D03*
Y1260160D03*
X507347D03*
X504647D03*
X521872Y82593D03*
Y85193D03*
Y74793D03*
Y77393D03*
Y79993D03*
X521916Y92874D03*
X512958Y99961D03*
X513008Y95236D03*
X523943Y107649D03*
Y104249D03*
X520965Y162368D03*
X523565D03*
X511820Y207978D03*
Y210478D03*
Y215478D03*
Y212978D03*
X522276Y208213D03*
Y213213D03*
Y210713D03*
Y215713D03*
X515149Y264180D03*
X517649D03*
X515074Y258880D03*
X524043Y270026D03*
Y267526D03*
X514769Y312953D03*
X519638Y314346D03*
X511790Y313804D03*
X512943Y443071D03*
X520823Y442603D03*
X511753Y454339D03*
Y456839D03*
X509253D03*
Y454339D03*
X518240Y459371D03*
X509253Y459339D03*
X511753D03*
X512210Y475825D03*
X517310Y470045D03*
X513310Y462004D03*
X522756Y461818D03*
X508325Y485138D03*
X512210Y478625D03*
X513910Y482425D03*
X513325Y485138D03*
X510825D03*
X519786Y491214D03*
X523489Y492987D03*
X519786Y493714D03*
X523489Y495487D03*
X509955Y537958D03*
X513658Y539731D03*
X518716Y541895D03*
X521216Y544895D03*
Y541895D03*
X513658Y542231D03*
X518416Y544895D03*
X509955Y540458D03*
X521494Y582747D03*
X508086Y581222D03*
X520945Y590801D03*
X508086Y591215D03*
X520770Y597130D03*
X524770Y605637D03*
X518940Y620653D03*
Y617853D03*
X511058Y610562D03*
Y607762D03*
X508258Y610562D03*
Y607762D03*
X520770Y605443D03*
X516770D03*
X523616Y625013D03*
X515267Y627908D03*
X511278Y633473D03*
X521778Y642184D03*
X521868Y666577D03*
X518812Y662874D03*
X510425Y683246D03*
X522200Y677613D03*
X521540Y686319D03*
X515484Y695757D03*
X515504Y701351D03*
X521159Y706388D03*
X515649D03*
X512530Y718301D03*
X514531Y716398D03*
X523929Y706388D03*
X518389D03*
X521131Y741071D03*
X517731D03*
X511724Y741035D03*
X508324D03*
X520549Y761982D03*
X509096Y753072D03*
X515422Y753455D03*
X513504Y755804D03*
X513278Y783286D03*
X520833Y773389D03*
X513551Y773203D03*
X522697Y797102D03*
X519891Y795848D03*
X518157Y803973D03*
X518565Y811973D03*
X520741Y805149D03*
X522481Y824661D03*
X517702Y826600D03*
X514682Y834590D03*
X511741Y846649D03*
X524741Y845149D03*
X520870Y874694D03*
X525159Y913818D03*
X521572Y901500D03*
X516902Y910251D03*
X520146Y939241D03*
X523289Y939195D03*
X521353Y952266D03*
X522544Y992854D03*
X512232Y985172D03*
X514566Y1000766D03*
X514690Y996766D03*
Y1004766D03*
X514566Y1016266D03*
X514649Y1020266D03*
X514843Y1030766D03*
X519500Y1028377D03*
X518497Y1105552D03*
X522775Y1101917D03*
X521055Y1104335D03*
X514703Y1104792D03*
X522710Y1106897D03*
X516210Y1106867D03*
X509795Y1113648D03*
X512295D03*
X520646Y1169884D03*
Y1167384D03*
Y1164884D03*
Y1162384D03*
X523146D03*
Y1164884D03*
Y1167384D03*
Y1169884D03*
Y1172384D03*
X520646D03*
X520751Y1186921D03*
Y1184421D03*
Y1181921D03*
Y1179421D03*
X523146Y1174884D03*
X520646D03*
X523066Y1190121D03*
Y1192621D03*
X522562Y1222194D03*
X518562D03*
X514562D03*
X510562D03*
X522562Y1226194D03*
X518562D03*
Y1230194D03*
Y1234194D03*
X514562Y1226194D03*
Y1230194D03*
Y1234194D03*
Y1238194D03*
X510562Y1226194D03*
Y1230194D03*
Y1234194D03*
Y1238194D03*
X514562Y1242194D03*
Y1246194D03*
X510562Y1242194D03*
Y1246194D03*
X530197Y98551D03*
X540751Y97475D03*
X533747Y103783D03*
X532281Y141247D03*
X528509Y147540D03*
X539748Y143740D03*
X537128Y148277D03*
X530665Y162793D03*
Y165393D03*
Y170493D03*
Y167993D03*
X538170Y172190D03*
X535668Y181009D03*
X529662Y181426D03*
X532873Y181366D03*
X537589Y177616D03*
X529870Y184221D03*
X532487Y184012D03*
X533906Y211359D03*
Y213859D03*
X528848Y211695D03*
X537609Y213132D03*
X526348Y208695D03*
X529148D03*
X526348Y211695D03*
X537609Y215632D03*
X537853Y256303D03*
X532525Y265701D03*
X537612Y265896D03*
X526843Y270026D03*
X529343D03*
X526843Y267526D03*
X529343D03*
X534160Y281716D03*
X540101Y281982D03*
X532659Y359557D03*
X526388Y351301D03*
X531612Y354272D03*
X531636Y349057D03*
X528812Y369164D03*
X533211Y364746D03*
X533115Y371856D03*
X530144Y376062D03*
X531953Y380749D03*
X542034Y392209D03*
X541706Y386223D03*
X533189Y390723D03*
X531953Y385749D03*
X531992Y397552D03*
X526216Y456652D03*
X528716D03*
X526216Y459152D03*
Y461652D03*
X528716Y459152D03*
Y461652D03*
X535119Y491133D03*
X531047Y498151D03*
X535119Y493633D03*
Y496133D03*
Y498633D03*
X531047Y495151D03*
X528547D03*
X528247Y498151D03*
X525288Y537877D03*
X535219Y555897D03*
Y553297D03*
X533488Y548344D03*
X525288Y540377D03*
Y545377D03*
Y542877D03*
X528488Y548344D03*
X525988D03*
X530988D03*
X535219Y561097D03*
Y563697D03*
Y566797D03*
Y558497D03*
X532009Y570478D03*
X529214Y570686D03*
X529423Y573303D03*
X532069Y573689D03*
X532426Y576484D03*
X535819Y578405D03*
X541245Y578986D03*
X524770Y597232D03*
X534820Y596782D03*
X540770Y596729D03*
X529601Y596089D03*
X526756Y613913D03*
Y616713D03*
Y619513D03*
X538826Y614158D03*
Y616958D03*
Y619758D03*
X536770Y605443D03*
X537664Y661556D03*
X534264D03*
X529664Y664056D03*
X526264D03*
X538316Y687357D03*
X535738Y687489D03*
X536087Y702364D03*
X529469Y706230D03*
X526699Y706388D03*
X535585Y736593D03*
X538985D03*
X530985Y741593D03*
X527585D03*
X524598Y753387D03*
X539449Y782389D03*
X537578Y772428D03*
X532304Y806649D03*
X531313Y812850D03*
Y826630D03*
X532316Y833649D03*
X534000Y843000D03*
X537300Y842900D03*
X530741Y845149D03*
X534632Y849830D03*
X525718Y873821D03*
X533468Y878533D03*
X538468Y888033D03*
X530968Y888283D03*
X528975Y898346D03*
X537279Y897943D03*
X533143Y897910D03*
X531076Y913190D03*
X527879Y952189D03*
X530473Y961728D03*
X528500Y1106365D03*
X529191Y1115896D03*
X525525Y1110092D03*
X529191Y1118396D03*
X528274Y1160834D03*
X554198Y68581D03*
X554211Y80581D03*
X546293Y76587D03*
Y72615D03*
X547732Y100625D03*
X540682Y106186D03*
X552105Y112083D03*
X556394Y103621D03*
X548311Y141247D03*
X552798Y143518D03*
X551898Y152373D03*
X555048Y152562D03*
X540843Y168697D03*
X555850Y178560D03*
X555913Y172665D03*
X555740Y183834D03*
X541931Y191941D03*
X555260Y190185D03*
X549985Y192490D03*
X556030Y200864D03*
X548940Y206767D03*
X546440D03*
X543940D03*
X556119Y212455D03*
X556053Y207037D03*
X549070Y221708D03*
X546570D03*
X553420Y221642D03*
X545185Y231021D03*
Y228221D03*
X544070Y221708D03*
X543485Y224421D03*
X550736Y236189D03*
X548236D03*
X545736D03*
X550677Y248765D03*
X548177D03*
X545677D03*
X542628Y266114D03*
X545874Y268195D03*
X548374D03*
X551174Y270695D03*
X554834Y265897D03*
X551174Y268195D03*
X548374Y270695D03*
X545874D03*
X551536Y359223D03*
Y354723D03*
Y350223D03*
Y345723D03*
Y377223D03*
Y372723D03*
Y368223D03*
Y363723D03*
Y381723D03*
X551620Y390723D03*
X553563Y384987D03*
X544738Y581659D03*
X544770Y605443D03*
X551475Y661504D03*
X547227Y678299D03*
X547276Y675521D03*
X543101Y698772D03*
X540379Y719785D03*
X557751Y750851D03*
X550420Y793743D03*
X556326D03*
X540578Y793889D03*
X544515Y793875D03*
X544741Y809649D03*
X544878Y816309D03*
X546855Y829949D03*
X550087Y829836D03*
X556326Y829989D03*
X556741Y820149D03*
X544741Y823149D03*
X546241Y843149D03*
X557836Y851669D03*
X548665Y850399D03*
X540968Y878360D03*
X546940Y871389D03*
X548327Y905295D03*
X552238Y959102D03*
X552923Y988813D03*
X542793Y998507D03*
X544719Y1007522D03*
X551485Y1006648D03*
X551673Y1023900D03*
X548852Y1018307D03*
X545094Y1013678D03*
X545566Y1023731D03*
X554696Y1018469D03*
X556493Y1118351D03*
X557584Y1543411D03*
X560573Y60513D03*
X563433Y60438D03*
X557973Y55513D03*
X569114Y86012D03*
X558341Y88801D03*
X569114Y94374D03*
X561258Y94351D03*
X565207Y94279D03*
X560701Y85731D03*
X564255Y86046D03*
X564451Y116594D03*
X570394Y110784D03*
X564451Y119594D03*
X574973Y124663D03*
X564885Y124283D03*
X569951Y124879D03*
X563292Y161306D03*
X560543Y157370D03*
X564627Y176665D03*
Y168665D03*
X556726Y186629D03*
X564627Y196665D03*
Y192665D03*
X564740Y186778D03*
X564659Y204864D03*
Y208864D03*
X569708Y218085D03*
X572508D03*
X560300Y219379D03*
X560928Y228631D03*
X575035Y249108D03*
X566416Y248371D03*
X557334Y265897D03*
X573479Y374705D03*
X569938Y378317D03*
X559070Y684809D03*
Y700809D03*
Y688209D03*
X561570Y696209D03*
Y692809D03*
X559070Y716809D03*
X561570Y708809D03*
Y712209D03*
X559070Y704209D03*
Y720209D03*
X558616Y732530D03*
X562001Y732834D03*
X562374Y721593D03*
X567428Y750145D03*
X557847Y744599D03*
X563200Y739600D03*
X571493Y763090D03*
X570038Y752339D03*
X564362Y757979D03*
X560263Y782207D03*
X567126Y779066D03*
X571984Y784507D03*
X561001Y806889D03*
X567559Y803008D03*
Y824661D03*
X562400Y818900D03*
X560813Y840574D03*
X568990Y844721D03*
X572476Y845535D03*
X559295Y874267D03*
X559887Y877196D03*
X561134Y869291D03*
X559260Y891043D03*
X559214Y897425D03*
X564165Y894411D03*
X567827Y884000D03*
X562328Y957307D03*
X566303Y951807D03*
X569403D03*
X563103D03*
X570603Y957207D03*
X560923Y980443D03*
X556923Y980523D03*
X564923Y988813D03*
X560923D03*
X556923D03*
X568923D03*
X558112Y1009655D03*
X560912D03*
X567484Y1024003D03*
X571857Y1016827D03*
X559057Y1030563D03*
X562057D03*
X568057Y1030672D03*
X565057D03*
X571857Y1029427D03*
X566058Y1109564D03*
X560211D03*
X566058Y1122164D03*
X560211D03*
X566058Y1134764D03*
X560211D03*
X566058Y1147364D03*
X560211D03*
X566058Y1159964D03*
X560211D03*
X566058Y1172564D03*
X560211D03*
X566058Y1185164D03*
X560211D03*
X568532Y1200001D03*
X575620Y1207737D03*
X569135Y1214372D03*
X564890Y1218169D03*
X570796Y1530309D03*
X567324Y1528151D03*
X572432Y1521462D03*
X565400Y1535100D03*
X563968Y1541445D03*
X568279Y1538438D03*
X572507Y1541375D03*
X586037Y97667D03*
X581693Y102495D03*
X576420Y116594D03*
X575394Y110784D03*
X576420Y119594D03*
X579954Y125107D03*
X581427Y142862D03*
X588568Y143762D03*
X582468Y148717D03*
X576317Y138838D03*
X587516Y195176D03*
X585016D03*
X589034Y199248D03*
X587597Y210509D03*
X585097D03*
X589034Y201748D03*
X586870Y206806D03*
X576308Y216385D03*
X579021Y216970D03*
Y219470D03*
X579087Y226320D03*
X579021Y221970D03*
X586789Y230556D03*
X591044Y227824D03*
X582048Y228646D03*
X585774Y242078D03*
X581005Y232971D03*
X577655Y244571D03*
X584998Y256394D03*
X578193Y336391D03*
X584679Y336285D03*
X576556Y728219D03*
X575979Y732517D03*
X573778Y747437D03*
X577638Y769772D03*
X578271Y763556D03*
X583102Y767137D03*
X587183Y785008D03*
X578204Y775137D03*
X585912Y778470D03*
X588345Y798030D03*
X588659Y790336D03*
X582100Y787600D03*
X586060Y793145D03*
X581001Y810973D03*
X588377Y807536D03*
X588272Y804601D03*
X588231Y801520D03*
X577501Y829069D03*
X588001Y829624D03*
X582737Y819831D03*
X581158Y823473D03*
X573300Y829600D03*
X579827Y888000D03*
X580327Y892000D03*
X586136Y908935D03*
X583065Y903294D03*
X573103Y941307D03*
X585703D03*
X586103Y961807D03*
X573895Y965319D03*
X584923Y988813D03*
X576923D03*
X580923D03*
X588923D03*
X572923D03*
X577704Y1029427D03*
Y1016827D03*
X587880Y1034834D03*
X581967Y1105091D03*
X587467D03*
X582012Y1102091D03*
X587467Y1117691D03*
X581967D03*
X582012Y1127291D03*
Y1114691D03*
X587467Y1130291D03*
X581967D03*
X587467Y1142891D03*
X582012Y1139891D03*
X581967Y1155491D03*
X587467D03*
X581967Y1142891D03*
X582012Y1152491D03*
X581967Y1168091D03*
X587467D03*
X582012Y1165091D03*
X581967Y1180691D03*
X587467D03*
X582012Y1177691D03*
X586502Y1227300D03*
X583520Y1230407D03*
X581803Y1493687D03*
X578859Y1497758D03*
X588859Y1490895D03*
X590826Y1495688D03*
X588507Y1514141D03*
X582027Y1502800D03*
X581803Y1509687D03*
X577931Y1505687D03*
X575809Y1532912D03*
X572849Y1518702D03*
X587809Y1528389D03*
X583809Y1533025D03*
X579809Y1528163D03*
X587809Y1545854D03*
X583809Y1541607D03*
X577571Y1544013D03*
X594497Y103411D03*
X594891Y97667D03*
X605687Y90650D03*
X590287Y95111D03*
X594656Y106561D03*
X590016Y195176D03*
X592516D03*
X592034Y199248D03*
Y202048D03*
X589370Y206806D03*
X595634Y230117D03*
X591131Y246874D03*
X591650Y238714D03*
X593351Y244297D03*
X592900Y309871D03*
X605147Y378600D03*
Y382600D03*
X605262Y458711D03*
X602462D03*
X604606Y463600D03*
X598462Y504684D03*
X599110Y552466D03*
X605011Y603600D03*
Y619600D03*
Y623600D03*
X592272Y877262D03*
X592110Y895611D03*
X601084Y913544D03*
X604715Y914640D03*
X589203Y941407D03*
X591403Y938807D03*
Y936007D03*
X591754Y956979D03*
X597556Y965829D03*
X602484Y965764D03*
X600923Y988813D03*
X592923D03*
X604923D03*
X596923D03*
X599113Y1012354D03*
X593658Y1009354D03*
X593613Y1012354D03*
X599113Y1024954D03*
X593613D03*
X593658Y1021954D03*
X606434Y1041904D03*
X603682Y1053457D03*
X594183Y1220068D03*
X593519Y1224472D03*
X592885Y1229402D03*
X592634Y1234921D03*
X591487Y1501687D03*
X591481Y1509313D03*
X595809Y1532133D03*
X591872Y1518071D03*
X595809Y1546214D03*
X591809Y1542407D03*
X610999Y90615D03*
X615370Y95236D03*
X615320Y99961D03*
X605437Y95236D03*
X620727Y162368D03*
X614182Y210478D03*
Y215478D03*
Y212978D03*
Y207978D03*
X617511Y264180D03*
X620011D03*
X617436Y258880D03*
X607789Y453682D03*
X606026Y455921D03*
X609133Y941137D03*
X605733D03*
X608965Y966414D03*
X616923Y988813D03*
X608923D03*
X612923Y997860D03*
X618878Y1011914D03*
X621479Y1030482D03*
X607993Y1036920D03*
X610780Y1051037D03*
X617634Y1049283D03*
X617894Y1043955D03*
X612955Y1062941D03*
X622736Y1151870D03*
Y1159350D03*
X613738Y1546507D03*
X624234Y74793D03*
Y82593D03*
Y85193D03*
Y77393D03*
Y79993D03*
X624278Y92874D03*
X632559Y98551D03*
X636109Y103783D03*
X626305Y104249D03*
Y107649D03*
X630871Y147540D03*
X634643Y141247D03*
X639490Y148277D03*
X625927Y162368D03*
X623327D03*
X633027Y165393D03*
Y162793D03*
Y170493D03*
Y167993D03*
X639951Y177616D03*
X632024Y181426D03*
X635235Y181366D03*
X632232Y184221D03*
X634849Y184012D03*
X628710Y211695D03*
Y208695D03*
X631510D03*
X624638Y208213D03*
X636268Y211359D03*
Y213859D03*
X631210Y211695D03*
X624638Y213213D03*
Y210713D03*
Y215713D03*
X639974Y265896D03*
X634887Y265701D03*
X629205Y267526D03*
X626405D03*
X631705D03*
X629205Y270026D03*
X626405D03*
X631705D03*
X636522Y281716D03*
X632009Y541863D03*
Y545263D03*
X630201Y553407D03*
X632701D03*
X630201Y550907D03*
X632701D03*
X634185Y569426D03*
X634471Y566929D03*
X628425Y572070D03*
X629772Y569928D03*
X632119Y570962D03*
X631862Y568475D03*
X621592Y1033862D03*
X626476Y1155610D03*
X621727Y1556800D03*
X648655Y76587D03*
Y72615D03*
X650094Y100625D03*
X643113Y97475D03*
X643044Y106186D03*
X650673Y141247D03*
X655160Y143518D03*
X642110Y143740D03*
X654260Y152373D03*
X640532Y172190D03*
X638030Y181009D03*
X643205Y168697D03*
X644293Y191941D03*
X652347Y192490D03*
X646302Y206767D03*
X651302D03*
X648802D03*
X639971Y213132D03*
X648932Y221708D03*
X647547Y228221D03*
X645847Y224421D03*
X647547Y231021D03*
X646432Y221708D03*
X651432D03*
X639971Y215632D03*
X650598Y236189D03*
X648098D03*
X653098D03*
X653039Y248765D03*
X650539D03*
X648039D03*
X640215Y256303D03*
X644990Y266114D03*
X650736Y268195D03*
X653536Y270695D03*
Y268195D03*
X650736Y270695D03*
X648236D03*
Y268195D03*
X642463Y281982D03*
X642414Y545528D03*
X651149Y577716D03*
X648211Y610400D03*
X650958Y668153D03*
X662935Y60513D03*
X665795Y60438D03*
X657507Y58013D03*
X656560Y68581D03*
X671476Y86012D03*
X656573Y80581D03*
X660703Y88801D03*
X663620Y94351D03*
X667569Y94279D03*
X663063Y85731D03*
X666617Y86046D03*
X658756Y103621D03*
X666813Y116594D03*
X654467Y112083D03*
X666813Y119594D03*
X667247Y124283D03*
X672313Y124879D03*
X665654Y161306D03*
X657410Y152562D03*
X662905Y157370D03*
X666989Y176665D03*
Y168665D03*
X658275Y172665D03*
X658212Y178560D03*
X658102Y183834D03*
X659088Y186629D03*
X657622Y190185D03*
X658392Y200864D03*
X666989Y196665D03*
Y192665D03*
X667102Y186778D03*
X667021Y204864D03*
Y208864D03*
X658481Y212455D03*
X658415Y207037D03*
X655782Y221642D03*
X662662Y219379D03*
X663290Y228631D03*
X668886Y248371D03*
X657196Y265897D03*
X659696D03*
X661761Y382109D03*
X661760Y551683D03*
Y561420D03*
Y558917D03*
X657581Y577937D03*
X660586Y606929D03*
X665086Y604567D03*
X665586Y595500D03*
X660827Y612592D03*
X666244Y610072D03*
X660546Y618400D03*
X666180Y616317D03*
X665643Y646055D03*
X658233Y646449D03*
X658064Y650119D03*
X657967Y662981D03*
X662092Y666275D03*
X659209Y691851D03*
X661018Y707592D03*
X688399Y97667D03*
X671476Y94374D03*
X678782Y116594D03*
X684055Y102495D03*
X677756Y110784D03*
X672756D03*
X678782Y119594D03*
X682316Y125107D03*
X677335Y124663D03*
X683789Y142862D03*
X684830Y148717D03*
X678679Y138838D03*
X674870Y218085D03*
X681383Y219470D03*
Y216970D03*
X678670Y216385D03*
X681383Y221970D03*
X681449Y226320D03*
X672070Y218085D03*
X684410Y228646D03*
X683367Y232971D03*
X677397Y249108D03*
X680017Y244571D03*
X682857Y339477D03*
X687055Y376456D03*
X685353Y396718D03*
X678461Y455981D03*
X675237Y465611D03*
X682586Y530000D03*
X682086Y540500D03*
X681086Y547075D03*
X681286Y549800D03*
X680586Y568000D03*
X681126Y558800D03*
X681190Y562800D03*
X696859Y103411D03*
X697253Y97667D03*
X692649Y95111D03*
X697018Y106561D03*
X690930Y143762D03*
X691396Y199248D03*
X687378Y195176D03*
X689878D03*
X694396Y199248D03*
X694878Y195176D03*
X692378D03*
X691396Y201748D03*
X689232Y206806D03*
X687459Y210509D03*
X689959D03*
X694396Y202048D03*
X691732Y206806D03*
X697996Y230117D03*
X689151Y230556D03*
X693406Y227824D03*
X694012Y238714D03*
X688136Y242078D03*
X693493Y246874D03*
X695713Y244297D03*
X690504Y253198D03*
X689486Y339583D03*
X702448Y546712D03*
Y542712D03*
X699188Y656321D03*
X702086Y678462D03*
X692478Y730641D03*
X702691Y762971D03*
Y756971D03*
X692356Y764614D03*
X691991Y759581D03*
X702677Y780659D03*
Y775159D03*
X692155Y778974D03*
X692221Y773449D03*
X690449Y814406D03*
X708049Y90650D03*
X713361Y90615D03*
X717732Y95236D03*
X717682Y99961D03*
X707799Y95236D03*
X716544Y215478D03*
Y210478D03*
Y207978D03*
Y212978D03*
X718338Y305272D03*
X712692Y356779D03*
X717105Y410964D03*
X717420Y404334D03*
X709781Y442956D03*
X720996Y442856D03*
X711598Y438323D03*
X719051Y458455D03*
X719612Y451108D03*
X710643Y456335D03*
X711764Y445873D03*
X706211Y465874D03*
X711463Y546712D03*
X704364Y618288D03*
X711328Y653821D03*
X705390Y655789D03*
X705776Y678519D03*
X713200Y699676D03*
X716623Y702463D03*
X703600Y702212D03*
X703680Y697094D03*
X715802Y706446D03*
X710196Y707562D03*
X717434Y782500D03*
X710275Y786131D03*
X713222Y793312D03*
Y790812D03*
X712901Y821600D03*
X726596Y74793D03*
Y77393D03*
Y79993D03*
Y85193D03*
Y82593D03*
X726640Y92874D03*
X734921Y98551D03*
X728667Y104249D03*
Y107649D03*
X733233Y147540D03*
X728289Y162368D03*
X725689D03*
X734386Y181426D03*
X734594Y184221D03*
X727000Y213213D03*
Y208213D03*
X733872Y208695D03*
X731072D03*
X733572Y211695D03*
X731072D03*
X727000Y210713D03*
Y215713D03*
X722373Y264180D03*
X719873D03*
X719798Y258880D03*
X737249Y265701D03*
X731567Y267526D03*
X728767D03*
X734067D03*
Y270026D03*
X731567D03*
X728767D03*
X723404Y379657D03*
X721900Y384500D03*
X723440Y391496D03*
X734661Y393633D03*
X731511Y381113D03*
X723440Y398583D03*
X732035Y442606D03*
X722097Y453881D03*
X731952Y446606D03*
X722097Y446595D03*
X732959Y463479D03*
X733430Y467367D03*
X724362Y504731D03*
X722473Y693718D03*
X723656Y705858D03*
X720985Y711658D03*
X725667Y732161D03*
X723177Y728219D03*
X721163Y738981D03*
X733000Y816000D03*
X730880Y828924D03*
X733680Y828977D03*
X732713Y853890D03*
X722600Y869600D03*
X728503Y891692D03*
X736452Y890548D03*
X728692Y886653D03*
X724707Y893143D03*
X719661Y904900D03*
X722789Y927095D03*
X722400Y942500D03*
X725194Y942073D03*
X720271Y931730D03*
X732306Y942682D03*
X728846Y948331D03*
X733798Y950186D03*
X727116Y959326D03*
X732825Y1604100D03*
X736067Y1611892D03*
X729600Y1625165D03*
X732268Y1618260D03*
X751017Y76587D03*
Y72615D03*
X752456Y100625D03*
X745475Y97475D03*
X745406Y106186D03*
X738471Y103783D03*
X737005Y141247D03*
X744472Y143740D03*
X741852Y148277D03*
X735389Y165393D03*
Y162793D03*
Y170493D03*
Y167993D03*
X740392Y181009D03*
X737597Y181366D03*
X745567Y168697D03*
X742894Y172190D03*
X742313Y177616D03*
X746655Y191941D03*
X737211Y184012D03*
X750667Y192300D03*
X751164Y206767D03*
X748664D03*
X738630Y213859D03*
Y211359D03*
X742333Y213132D03*
X749909Y228221D03*
Y231021D03*
X751294Y221708D03*
X748209Y224421D03*
X748794Y221708D03*
X742333Y215632D03*
X750460Y236189D03*
X750401Y248765D03*
X742577Y256303D03*
X747352Y266114D03*
X742336Y265896D03*
X750598Y268195D03*
Y270695D03*
X744825Y281982D03*
X738884Y281716D03*
X741051Y316389D03*
X749444Y393858D03*
X749606Y384410D03*
X752785Y382047D03*
X753086Y403500D03*
X751086Y398583D03*
X749539Y438269D03*
Y440869D03*
Y435669D03*
Y430469D03*
Y433069D03*
X735599Y449961D03*
X739316Y458572D03*
X750393Y451677D03*
Y454177D03*
X741992Y763480D03*
X742000Y768137D03*
X743428Y772418D03*
X741993Y775909D03*
X736000Y864266D03*
X742407Y988452D03*
X743062Y1004460D03*
X749439Y1458777D03*
X740530Y1524113D03*
X747140Y1581335D03*
X749786Y1590517D03*
X738775Y1597866D03*
X737892Y1602340D03*
X749704Y1608631D03*
X744924Y1617709D03*
X743331Y1627871D03*
X741705Y1622015D03*
X738325Y1634485D03*
X762697Y55513D03*
X758922Y68581D03*
X765297Y60513D03*
X758935Y80581D03*
X763065Y88801D03*
X765982Y94351D03*
X769931Y94279D03*
X765425Y85731D03*
X756829Y112083D03*
X761118Y103621D03*
X769609Y124283D03*
X753035Y141247D03*
X757522Y143518D03*
X756622Y152373D03*
X759772Y152562D03*
X765267Y157370D03*
X760637Y172665D03*
X760464Y183834D03*
X760574Y178560D03*
X761450Y186629D03*
X754709Y192490D03*
X759984Y190185D03*
X760754Y200864D03*
X753182Y198671D03*
X753664Y206767D03*
X769383Y208864D03*
X760843Y212455D03*
X760777Y207037D03*
X753794Y221708D03*
X758144Y221642D03*
X765024Y219379D03*
X763653Y224536D03*
X752960Y236189D03*
X755460D03*
X755401Y248765D03*
X752901D03*
X753098Y268195D03*
X755898D03*
X753098Y270695D03*
X755898D03*
X759558Y265897D03*
X762058D03*
X769349Y324518D03*
X759029Y328867D03*
X754805Y339559D03*
X759624Y353961D03*
X756086Y377912D03*
X766344D03*
X755086Y391496D03*
X756086Y386500D03*
X766344Y381912D03*
X756174Y397912D03*
X755086Y409000D03*
X766344Y397912D03*
X752339Y438269D03*
Y433069D03*
Y430469D03*
Y435669D03*
Y440869D03*
X752893Y451677D03*
Y454177D03*
X752097Y460218D03*
Y463618D03*
X755035Y1443524D03*
X765713Y1437365D03*
X760398Y1440276D03*
X755187Y1580821D03*
X759802Y1590864D03*
X763542Y1590186D03*
X768361Y1610083D03*
X762671Y1619367D03*
X756358Y1613767D03*
X768157Y60438D03*
X773838Y86012D03*
Y94374D03*
X768979Y86046D03*
X781144Y116594D03*
X769175D03*
X775118Y110784D03*
X780118D03*
X781144Y119594D03*
X769175D03*
X784678Y125107D03*
X779697Y124663D03*
X774675Y124879D03*
X781041Y138838D03*
X768016Y161306D03*
X769351Y176665D03*
Y168665D03*
Y192665D03*
X769464Y186778D03*
X769383Y204864D03*
X774432Y218085D03*
X777232D03*
X783745Y216970D03*
X781032Y216385D03*
X783745Y221970D03*
X783811Y226320D03*
X783745Y219470D03*
X782379Y244571D03*
X779759Y249108D03*
X771140Y248371D03*
X772165Y314890D03*
X784118Y303962D03*
X771941Y311740D03*
X772162Y332584D03*
X778502Y348015D03*
X772859Y347937D03*
X774419Y353470D03*
X784902Y428653D03*
X775746Y539315D03*
X777708Y553287D03*
X781429Y545017D03*
X778860Y626912D03*
X778205Y622912D03*
X783694Y1410977D03*
X778685Y1416198D03*
X780162Y1412848D03*
X777749Y1431432D03*
X783469Y1424655D03*
X771557Y1446818D03*
X768910Y1437741D03*
X777749Y1435432D03*
Y1439432D03*
X777260Y1446237D03*
X778428Y1455156D03*
X777725Y1450193D03*
X783620Y1460108D03*
X768812Y1453306D03*
X781124Y1583553D03*
X781110Y1595254D03*
X777059Y1608982D03*
X784046Y1600438D03*
X778045Y1619395D03*
X778358Y1627418D03*
X771383Y1616917D03*
X799221Y103411D03*
X799615Y97667D03*
X790761D03*
X795011Y95111D03*
X786417Y102495D03*
X799380Y106561D03*
X786151Y142862D03*
X793292Y143762D03*
X787192Y148717D03*
X796758Y199248D03*
X797240Y195176D03*
X794740D03*
X789740D03*
X792240D03*
X793758Y199248D03*
X794094Y206806D03*
X791594D03*
X789821Y210509D03*
X792321D03*
X793758Y201748D03*
X796758Y202048D03*
X800358Y230117D03*
X795768Y227824D03*
X791513Y230556D03*
X786772Y228646D03*
X796374Y238714D03*
X790498Y242078D03*
X785729Y232971D03*
X795855Y246874D03*
X798075Y244297D03*
X789722Y256394D03*
X786461Y293028D03*
X790280Y287421D03*
X800155Y337368D03*
X800029Y333368D03*
X797141Y350368D03*
X795445Y356950D03*
X789581Y405011D03*
X793893Y409502D03*
X784804Y425371D03*
X794173Y450510D03*
X802136Y448334D03*
X796000Y553101D03*
X788600Y1006923D03*
X799631Y1025440D03*
X795631D03*
X789050Y1026150D03*
X796338Y1138130D03*
X793842Y1143384D03*
X797160Y1146609D03*
X792277Y1173065D03*
X799020Y1175975D03*
X798353Y1172011D03*
X787887Y1174500D03*
X798542Y1188345D03*
X792382Y1191664D03*
X794533Y1195766D03*
X794983Y1334030D03*
Y1331230D03*
X793548Y1397690D03*
X795296Y1416995D03*
X792848Y1414718D03*
X793459Y1429165D03*
X789647Y1427518D03*
X788648Y1422044D03*
X785820Y1425993D03*
X798601Y1431673D03*
X793288Y1450918D03*
X793744Y1437159D03*
X786787Y1433800D03*
X787694Y1442749D03*
X800607Y1440760D03*
X790361Y1447895D03*
X790754Y1441399D03*
X793994Y1441499D03*
X799057Y1449158D03*
X797083Y1467883D03*
X799057Y1456016D03*
X794005Y1464178D03*
X790296Y1463459D03*
X787038Y1460533D03*
X786591Y1452803D03*
X790989Y1455695D03*
X799314Y1475693D03*
X797318Y1471242D03*
X810411Y90650D03*
X815723Y90615D03*
X810161Y95236D03*
X805952Y301675D03*
X817456Y305368D03*
Y313368D03*
X809490Y305368D03*
X809466Y310604D03*
X801097Y325858D03*
X817100Y319600D03*
X809457Y330459D03*
X809490Y325368D03*
Y317368D03*
X809489Y313830D03*
X809490Y321368D03*
Y333368D03*
X816177Y441442D03*
X813456Y441474D03*
X810749Y443045D03*
X815840Y444091D03*
Y456060D03*
X810453Y453330D03*
X810406Y448214D03*
X810756Y471071D03*
Y468571D03*
X814580Y468806D03*
X814828Y472053D03*
X810756Y473571D03*
Y476071D03*
X813902Y730738D03*
X813678Y740979D03*
X813653Y746856D03*
X817584Y764219D03*
X813635Y762000D03*
X818000Y797000D03*
X817845Y817879D03*
X818500Y810135D03*
X813000Y805000D03*
X813548Y814000D03*
X813009Y819734D03*
X815500Y824000D03*
X815863Y830097D03*
X814299Y840877D03*
X813887Y835146D03*
X816037Y845578D03*
X812440Y862306D03*
X814080Y864464D03*
X812575Y880834D03*
X812219Y883586D03*
X817884Y915425D03*
X803673Y1025440D03*
X803453Y1134729D03*
X814835D03*
X806835D03*
X809632Y1142666D03*
X817964Y1157404D03*
X811507Y1157544D03*
X810018Y1167768D03*
X815037D03*
X814160Y1178240D03*
X814170Y1185205D03*
X805212Y1180175D03*
X805519Y1187215D03*
X815455Y1201043D03*
X811485D03*
X807489D03*
X804452Y1199814D03*
X804458Y1193112D03*
X809027Y1219895D03*
X807020Y1217900D03*
X812302Y1223170D03*
X815149Y1226016D03*
X810148Y1374884D03*
X806148Y1383715D03*
Y1375208D03*
X810204Y1401661D03*
X804654Y1404769D03*
X812901Y1432804D03*
X815901D03*
X810059Y1432778D03*
X812104Y1426483D03*
X809986Y1438785D03*
X812986D03*
X815986D03*
X809986Y1441485D03*
X812986D03*
X815986D03*
X812901Y1435504D03*
X815901D03*
X810001D03*
X803057Y1449158D03*
X801057Y1447158D03*
X805569Y1441519D03*
X803057Y1456016D03*
X801057Y1458016D03*
X802684Y1465549D03*
X801354Y1478681D03*
X807576Y1469584D03*
X804919Y1489247D03*
X828958Y79993D03*
Y77393D03*
Y74793D03*
Y85193D03*
Y82593D03*
X829002Y92874D03*
X820094Y95236D03*
X820044Y99961D03*
X831029Y104249D03*
Y107649D03*
X830651Y162368D03*
X828051D03*
X829362Y213213D03*
X818906Y207978D03*
Y212978D03*
Y215478D03*
Y210478D03*
X829362Y208213D03*
Y210713D03*
Y215713D03*
X822235Y264180D03*
X824735D03*
X822160Y258880D03*
X831129Y267526D03*
Y270026D03*
X822477Y309368D03*
X825971Y345101D03*
X829485D03*
X822626Y348066D03*
X818840Y444091D03*
X825103Y430358D03*
Y435558D03*
Y432958D03*
X831378Y433086D03*
Y435686D03*
Y430486D03*
X818840Y456060D03*
X824650Y455034D03*
Y450034D03*
X817328Y472053D03*
X820810Y471243D03*
X817380Y468806D03*
X823544Y475061D03*
Y472561D03*
X820810Y473743D03*
X828918Y480580D03*
X831418D03*
X831057Y484036D03*
X834282Y536085D03*
X828272Y535462D03*
X827291Y533100D03*
X829496Y676793D03*
X829784Y716589D03*
Y705489D03*
X823890Y703415D03*
X823670Y710542D03*
X824387Y726246D03*
X818307Y724144D03*
X821582Y727140D03*
X826484Y747127D03*
X827500Y750000D03*
X819788Y739634D03*
X830484Y738750D03*
X824500Y760500D03*
X830075Y769000D03*
X822151Y752283D03*
X824500Y756000D03*
X817365Y756827D03*
X824500Y778500D03*
Y774000D03*
Y782500D03*
X830075Y787000D03*
X824500Y796500D03*
X824342Y792315D03*
X824500Y800500D03*
X830075Y805000D03*
X824500Y814500D03*
X830075Y823000D03*
X829946Y829788D03*
X825721Y839816D03*
X830014Y833046D03*
X829757Y842672D03*
X822608Y848526D03*
X822916Y852576D03*
X823540Y857956D03*
X831654Y864494D03*
X831583Y853454D03*
X822938Y863298D03*
X826209Y866052D03*
X823234Y870830D03*
X833194Y873561D03*
X827992Y874107D03*
X826070Y893014D03*
X817152Y896380D03*
X817139Y890330D03*
X830063Y898500D03*
X819918Y889365D03*
X823900Y882083D03*
X824804Y898395D03*
X834465Y884538D03*
X829848Y914211D03*
X818031Y907747D03*
X825336Y916774D03*
X831057Y916745D03*
X834751Y922368D03*
X823552Y930700D03*
X829617Y939583D03*
X824414Y939655D03*
X816519Y931147D03*
X824168Y949538D03*
X825670Y964671D03*
X832423Y964669D03*
X828964Y977780D03*
X830356Y1116251D03*
X827856D03*
X825335Y1137129D03*
X819449Y1134534D03*
X819026Y1128137D03*
X825744Y1150087D03*
X823220Y1170767D03*
X818879Y1187310D03*
X823309Y1180235D03*
X823516Y1185238D03*
X819489Y1201039D03*
X823489Y1200969D03*
X823608Y1208993D03*
X819419Y1230265D03*
X817360Y1228226D03*
X816648Y1380758D03*
X824901Y1427404D03*
X827901D03*
X821901D03*
X818901Y1430104D03*
X821901D03*
X830901D03*
X827901D03*
X824901D03*
Y1432804D03*
X827901D03*
X830901D03*
X821901D03*
X818901D03*
X824901Y1435504D03*
X827901D03*
X821901D03*
X818901D03*
X821986Y1441485D03*
X818986D03*
Y1438785D03*
X821986D03*
X826204Y1444689D03*
Y1440689D03*
X826341Y1451236D03*
X826365Y1458974D03*
X826219Y1455244D03*
X837283Y98551D03*
X847837Y97475D03*
X840833Y103783D03*
X847768Y106186D03*
X837751Y165393D03*
Y162793D03*
Y170493D03*
Y167993D03*
X842754Y181009D03*
X839959Y181366D03*
X836748Y181426D03*
X847929Y168697D03*
X844675Y177616D03*
X845256Y172190D03*
X839573Y184012D03*
X836956Y184221D03*
X836234Y208695D03*
X833434D03*
X835934Y211695D03*
X840992Y213859D03*
Y211359D03*
X833434Y211695D03*
X844695Y213132D03*
Y215632D03*
X844939Y256303D03*
X844698Y265896D03*
X839611Y265701D03*
X849714Y266114D03*
X836429Y267526D03*
X833929D03*
Y270026D03*
X836429D03*
X841246Y281716D03*
X847187Y281982D03*
X842240Y324854D03*
X848879Y360849D03*
X845435Y356172D03*
X846098Y408715D03*
X849591Y411388D03*
X842515Y461382D03*
X850732Y469382D03*
X842779Y473076D03*
X842916Y467009D03*
X833293Y490636D03*
Y487836D03*
X833918Y480580D03*
X834215Y484138D03*
X844227Y479882D03*
X842476Y482382D03*
X833269Y506683D03*
X833953Y530621D03*
X848444Y657756D03*
X837272Y663910D03*
X839636Y666533D03*
X842352Y659243D03*
X842640Y662814D03*
X838152Y700215D03*
X845784Y705489D03*
Y716589D03*
X845850Y710969D03*
X845784Y708089D03*
X836078Y709619D03*
X835987Y713745D03*
X838484Y746701D03*
X846484Y738750D03*
X836713Y738751D03*
X842661Y769521D03*
X846000Y772079D03*
X840136Y830903D03*
X836839Y831301D03*
X836894Y824401D03*
X848224Y823502D03*
X835626Y843629D03*
X838189Y843459D03*
Y847490D03*
X835215Y847719D03*
X848384Y843459D03*
X846239Y847490D03*
X835553Y835119D03*
X848384Y839459D03*
Y835459D03*
X838194Y836962D03*
X848739Y847459D03*
X837183Y855459D03*
X840234Y851459D03*
X847138Y859459D03*
X839530Y859408D03*
X848384Y863459D03*
X846336Y855459D03*
X845820Y863413D03*
X848384Y851459D03*
X843574Y859423D03*
X837434Y851459D03*
X833327Y855560D03*
X837383Y879530D03*
X837396Y871459D03*
X840234Y875459D03*
X836999Y867413D03*
X845876Y879459D03*
X848384Y867459D03*
X845820Y867413D03*
X848384Y879459D03*
Y871459D03*
Y875459D03*
X837290Y887490D03*
X842827Y895443D03*
X835346Y891346D03*
X848322Y888421D03*
X848792Y896472D03*
X836066Y894955D03*
X847098Y891213D03*
X845633Y883492D03*
X845964Y887490D03*
X837276Y883459D03*
X848200Y883400D03*
X841329Y926602D03*
X841274Y914060D03*
X843315Y916612D03*
X836909Y916618D03*
Y914018D03*
X833683Y939579D03*
X836243D03*
X833683Y949105D03*
X836243D03*
X842856Y949146D03*
X836423Y964669D03*
X835431Y977775D03*
X840935Y1011499D03*
X844058Y1011738D03*
X848045Y1019310D03*
X848070Y1022190D03*
X839744Y1444959D03*
Y1440859D03*
Y1448959D03*
X836704Y1448849D03*
Y1440849D03*
X836744Y1444849D03*
X845306Y1438269D03*
X846844Y1454334D03*
X837685Y1453196D03*
X839744Y1457959D03*
X835474Y1457397D03*
X846044Y1451459D03*
X839744Y1461959D03*
X834475Y1460059D03*
X865059Y55513D03*
X861284Y68581D03*
X861297Y80581D03*
X853379Y76587D03*
Y72615D03*
X854818Y100625D03*
X859191Y112083D03*
X863480Y103621D03*
X862826Y183834D03*
X862999Y172665D03*
X862936Y178560D03*
X849017Y191941D03*
X863812Y186629D03*
X857071Y192490D03*
X862346Y190185D03*
X863116Y200864D03*
X853029Y192300D03*
X853526Y206767D03*
X856026D03*
X851026D03*
X863205Y212455D03*
X863139Y207037D03*
X860506Y221642D03*
X852271Y228221D03*
Y231021D03*
X853656Y221708D03*
X856156D03*
X850571Y224421D03*
X851156Y221708D03*
X866015Y224536D03*
X852822Y236189D03*
X855322D03*
X857822D03*
X852763Y248765D03*
X855263D03*
X857763D03*
X852960Y268195D03*
Y270695D03*
X855460D03*
X864420Y265897D03*
X858260Y268195D03*
Y270695D03*
X861920Y265897D03*
X855460Y268195D03*
X863430Y309368D03*
Y316970D03*
X863114Y324505D03*
X863040Y330140D03*
X861770Y343006D03*
X852569Y356712D03*
X856069Y356426D03*
X854086Y374500D03*
X858586D03*
X863086D03*
X860586Y383000D03*
X861235Y394000D03*
X854086Y392999D03*
X864086Y384000D03*
X855017Y411969D03*
X861413Y417071D03*
X858827Y419896D03*
X858410Y413890D03*
X858767Y416685D03*
X861622Y419688D03*
X862882Y458991D03*
X854882D03*
X862882Y461791D03*
X854882D03*
X850748Y465382D03*
X861468Y483303D03*
Y487303D03*
X858169Y495032D03*
X853989Y630453D03*
Y632953D03*
X861663Y646653D03*
X855300Y646819D03*
X853982Y657506D03*
X859441Y678015D03*
X849680Y694789D03*
X858186Y701170D03*
X855646Y692710D03*
X864029Y688970D03*
X867455Y710611D03*
X858002Y707244D03*
X857986Y722670D03*
X854484Y746701D03*
X859199Y744517D03*
X854484Y738633D03*
X859000Y756000D03*
X849500Y758500D03*
Y763500D03*
X863443Y753254D03*
X859000Y764000D03*
Y760000D03*
Y774000D03*
X849500Y776500D03*
Y781500D03*
X861425Y770500D03*
X859000Y781000D03*
Y778000D03*
X853282Y789887D03*
X857632Y789385D03*
X859000Y792000D03*
X849500Y794500D03*
Y799500D03*
X861425Y788500D03*
X859000Y800000D03*
Y796000D03*
X861425Y806500D03*
X859000Y810000D03*
X849500Y812500D03*
X859000Y814000D03*
X850496Y831469D03*
X861425Y824500D03*
X849500Y817500D03*
X859000Y818000D03*
X851184Y839459D03*
Y835459D03*
X859165Y848728D03*
X851239Y847459D03*
X851184Y843459D03*
Y863459D03*
X862114Y859479D03*
X851184Y851459D03*
X859603Y863570D03*
X859461Y859459D03*
X851184Y867459D03*
Y871459D03*
Y875459D03*
X859234Y879600D03*
X859463Y866125D03*
X851184Y879459D03*
X849267Y892567D03*
X859614Y883800D03*
Y887846D03*
X850900Y888359D03*
X850800Y883500D03*
X858988Y898307D03*
X855524Y898505D03*
X864253Y918042D03*
X856628D03*
X849600Y918028D03*
X849205Y924129D03*
X867096Y935963D03*
X858601Y934505D03*
X853030Y934690D03*
X851925Y951350D03*
X850686Y1006923D03*
X853449Y1007048D03*
X863334Y1009393D03*
X861047Y1018909D03*
X860887Y1023208D03*
Y1026762D03*
X863956Y1020763D03*
X863689Y1024974D03*
X863944Y1432359D03*
Y1429359D03*
X860944Y1432359D03*
X857944Y1429359D03*
X860944D03*
Y1426359D03*
X857944D03*
X863944D03*
X857944Y1432359D03*
X863944Y1435359D03*
Y1441359D03*
Y1438359D03*
X860944Y1441359D03*
X857944Y1435359D03*
X860944D03*
X857944Y1441359D03*
Y1438359D03*
X860944D03*
X850544Y1447559D03*
X853514Y1457510D03*
X850644Y1457359D03*
X870519Y60438D03*
X867659Y60513D03*
X876200Y86012D03*
X867787Y85731D03*
X865427Y88801D03*
X876200Y94374D03*
X872293Y94279D03*
X868344Y94351D03*
X871341Y86046D03*
X871713Y168665D03*
Y176665D03*
Y196665D03*
Y192665D03*
X871826Y186778D03*
X871745Y204864D03*
Y208864D03*
X867386Y219379D03*
X883118Y262687D03*
X876622Y293721D03*
X872050Y302644D03*
X873262Y300030D03*
X869924Y305368D03*
X879112Y302369D03*
X877977Y305368D03*
Y309368D03*
X869924Y313368D03*
X877977D03*
Y325368D03*
Y317368D03*
Y321368D03*
X869924D03*
Y328722D03*
X874005Y344917D03*
X870413Y342791D03*
X869924Y333722D03*
X877977Y333368D03*
Y329368D03*
X872158Y359962D03*
X868086Y373750D03*
X876736Y383125D03*
X877909Y391731D03*
X880736Y383125D03*
X882925Y391099D03*
X872736Y391754D03*
X867586Y393000D03*
Y385000D03*
X869342Y407627D03*
X868586Y398500D03*
X877253Y420380D03*
X876917Y415322D03*
X879417D03*
X881190Y411619D03*
X878690D03*
X874253Y422880D03*
Y420080D03*
X877253Y422880D03*
X881271Y426952D03*
X878771D03*
X873536Y437408D03*
X876036D03*
X881036D03*
X878536D03*
X873771Y426952D03*
X876271D03*
X870882Y458991D03*
X880910Y454634D03*
Y457434D03*
Y460234D03*
X870882Y461791D03*
X869454Y479303D03*
X869954Y487303D03*
X882954Y486256D03*
X882195Y539204D03*
X867093Y554703D03*
X866938Y549771D03*
X878382Y554942D03*
X874649Y545296D03*
X876949Y571419D03*
X867093Y586828D03*
Y574703D03*
X881476Y588202D03*
X881131Y577349D03*
X875290Y578703D03*
X876351Y605023D03*
Y608523D03*
X879135Y632552D03*
X872862Y666859D03*
X878881Y667156D03*
X876286Y690970D03*
X868919Y700894D03*
X876286Y694970D03*
Y698970D03*
X881157Y749148D03*
X874142Y748914D03*
X879875Y753612D03*
X873728Y752692D03*
X875473Y742056D03*
X878670Y742841D03*
X869325Y761259D03*
X870017Y757313D03*
X867000Y774000D03*
X870000Y780000D03*
X879887Y784719D03*
X880040Y792851D03*
X867000Y792000D03*
X876402Y797415D03*
X874925Y800746D03*
X870035Y801032D03*
X867000Y810000D03*
X879916Y808965D03*
X877407Y828017D03*
X877818Y824214D03*
X876475Y830372D03*
X871600Y898584D03*
X872628Y918042D03*
X876628Y915242D03*
X880628Y918042D03*
X876628D03*
X872126Y934766D03*
X865830Y961600D03*
X870209Y949384D03*
X865973Y978187D03*
X874066Y977928D03*
X875391Y993796D03*
X872183Y993980D03*
X878976Y994020D03*
X871069Y1023114D03*
X878927Y1022387D03*
X878783Y1018751D03*
X872845Y1018988D03*
X866906Y1018751D03*
X866887Y1023208D03*
X875887D03*
X878887Y1026762D03*
X872887D03*
X866887D03*
X869741Y1025895D03*
X873824Y1071604D03*
X871224D03*
X876424D03*
Y1074104D03*
X871224D03*
X873824D03*
X868624Y1071604D03*
Y1074104D03*
X870057Y1091604D03*
X875257D03*
Y1089104D03*
X870057D03*
X872657D03*
X880115Y1084666D03*
X867457Y1091604D03*
Y1089104D03*
X872657Y1091604D03*
X875375Y1107647D03*
X872675D03*
X870075D03*
X867475D03*
X871364Y1120636D03*
X873964D03*
X876564D03*
X879264D03*
X875376Y1110175D03*
X872676D03*
X870076D03*
X867476D03*
X871364Y1139336D03*
X868664D03*
X879264Y1130336D03*
X876564D03*
X873964D03*
X871364D03*
X870522Y1148080D03*
X868022D03*
X875321Y1207654D03*
X872600Y1300833D03*
Y1298333D03*
X872944Y1432359D03*
Y1429359D03*
Y1426359D03*
X869944Y1432359D03*
Y1429359D03*
Y1426359D03*
X866944Y1432359D03*
Y1429359D03*
Y1426359D03*
X872944Y1435359D03*
Y1441359D03*
Y1438359D03*
X869944Y1435359D03*
X866944D03*
X869944Y1441359D03*
Y1438359D03*
X866944Y1441359D03*
Y1438359D03*
X881244Y1448859D03*
Y1440859D03*
X878244Y1451605D03*
X881244Y1464859D03*
Y1453059D03*
Y1456859D03*
X875744Y1453573D03*
X881244Y1476859D03*
X883233Y147540D03*
X887005Y141247D03*
X894472Y143740D03*
X891852Y148277D03*
X893284Y233339D03*
Y236739D03*
X895064Y250186D03*
X891383Y243203D03*
X896034Y243307D03*
X885884Y255118D03*
X897004Y257480D03*
X892484Y260860D03*
X887148Y249670D03*
X896953Y272012D03*
X886496Y268968D03*
X895140Y265236D03*
X886059Y284644D03*
X885918Y289500D03*
X885989Y309368D03*
Y305368D03*
Y317368D03*
X885953Y325368D03*
X885989Y313368D03*
X885953Y321368D03*
Y329368D03*
Y333368D03*
X896592Y358369D03*
Y354369D03*
X888812Y357372D03*
X883552Y357276D03*
X896592Y374369D03*
X891251Y387484D03*
X890553Y392038D03*
X887266Y400158D03*
Y405158D03*
Y402658D03*
X896579Y404043D03*
X893779D03*
X889979Y405743D03*
X890903Y454634D03*
Y457434D03*
Y460234D03*
X891454Y486303D03*
X892931Y534093D03*
X885931D03*
X891449Y547363D03*
X893949D03*
X886549Y553963D03*
X885556Y543664D03*
X887417Y566713D03*
X891673Y600049D03*
X891933Y618143D03*
X895933Y609696D03*
X883309Y666608D03*
X892461Y666671D03*
X886304Y666650D03*
X884903Y696678D03*
X884911Y690279D03*
X886836Y715970D03*
X893241Y704656D03*
X883686Y729778D03*
X889525Y722060D03*
X882098Y741565D03*
X884976Y740891D03*
X884463Y744757D03*
X881637Y744154D03*
X883126Y766124D03*
X883413Y759855D03*
X892040Y784511D03*
X889763Y788159D03*
X898737Y792289D03*
X889516Y792851D03*
X891916Y799605D03*
X884002Y797616D03*
X887916Y800815D03*
X895916Y808965D03*
X883916D03*
X887916D03*
X895829Y800660D03*
X883916Y800815D03*
X890326Y828548D03*
X895050D03*
X889178Y905619D03*
X884628Y915242D03*
Y918042D03*
X896553D03*
X892628Y915242D03*
X888628D03*
Y918042D03*
X882763Y933472D03*
X891367Y941126D03*
X888400Y994579D03*
X894660Y994330D03*
X891343Y994378D03*
X885099Y1021685D03*
X881887Y1023208D03*
X888743Y1019931D03*
X895394Y1026985D03*
X893147Y1020025D03*
X893887Y1023208D03*
X887887D03*
X890887Y1026762D03*
X884887D03*
X882779Y1074104D03*
Y1071604D03*
X887979Y1074104D03*
X885379D03*
X890579D03*
Y1071604D03*
X885379D03*
X887979D03*
X882615Y1084666D03*
X887862Y1088067D03*
X894004Y1081231D03*
X892856Y1102760D03*
X894249Y1114103D03*
X891549D03*
X888949D03*
X886349D03*
Y1123803D03*
X888949D03*
X891549D03*
X894249D03*
X895275Y1132870D03*
X892575D03*
X895547Y1145169D03*
X894713Y1210419D03*
X898878Y1214182D03*
X899286Y1219469D03*
X892532Y1220112D03*
X897169Y1225259D03*
X886888Y1263058D03*
X889388D03*
X891888D03*
X889388Y1260558D03*
X886888D03*
X891888D03*
X886926Y1298712D03*
X889729Y1295516D03*
X891107Y1314305D03*
X887342Y1314990D03*
X889244Y1444859D03*
X892244Y1449636D03*
Y1440859D03*
X889944Y1457959D03*
X889244Y1460859D03*
X895244Y1457510D03*
X889336Y1452554D03*
X893919Y1462132D03*
X889244Y1472859D03*
Y1468859D03*
X903035Y141247D03*
X907522Y143518D03*
X906622Y152373D03*
X909772Y152562D03*
X899573Y158195D03*
X910977Y243307D03*
Y248032D03*
Y262205D03*
X898048Y269387D03*
X913057Y311046D03*
X915653Y307438D03*
X899352Y308560D03*
Y311960D03*
X909298Y302347D03*
X905898D03*
X898533Y334498D03*
X908521Y356708D03*
X908625Y359317D03*
X905483Y355262D03*
X905000Y362158D03*
X898869Y351114D03*
X906161Y367191D03*
X913288Y372752D03*
X910646Y376084D03*
X906344Y372524D03*
X911072Y386992D03*
X897736Y383125D03*
X901747Y398492D03*
Y403492D03*
Y400992D03*
X910250Y457262D03*
Y454462D03*
X907450D03*
Y457262D03*
X910250Y451662D03*
X907450D03*
X910250Y460062D03*
X907450D03*
X910236Y465272D03*
X910759Y475511D03*
X899931Y534093D03*
X899530Y530753D03*
X914296Y558143D03*
X913728Y550495D03*
X899407Y560019D03*
X908846Y560124D03*
X910789Y598726D03*
X898207Y599891D03*
X900676Y621536D03*
X904076D03*
X909508Y621616D03*
X912908D03*
X900753Y656925D03*
X912462Y683770D03*
X909265Y677795D03*
X912462Y687770D03*
X906886Y702285D03*
X902236Y689332D03*
Y694332D03*
X908699Y709387D03*
X913247Y714204D03*
X902841Y703665D03*
X910836Y721570D03*
X913858Y721289D03*
X907866Y795572D03*
X911028Y796598D03*
X909785Y810778D03*
X903916Y810809D03*
X913716Y811954D03*
X899916Y808965D03*
X902641Y800748D03*
X907884Y829866D03*
X908920Y905630D03*
X900628Y918042D03*
X912628Y915242D03*
X908628Y918042D03*
X900628Y915242D03*
X912628Y918042D03*
X904838D03*
X908628Y915242D03*
X900983Y940895D03*
X903759Y951358D03*
X909811Y962400D03*
X913005Y969605D03*
X912690Y994350D03*
X897825Y994413D03*
X909166Y994188D03*
X897717Y1019915D03*
X899887Y1023208D03*
Y1026762D03*
X908422Y1023103D03*
X908856Y1017677D03*
X902389Y1081764D03*
X908799Y1093659D03*
Y1088659D03*
X908278Y1083484D03*
X908799Y1096659D03*
Y1100659D03*
X902353Y1104333D03*
X898278Y1136426D03*
X898047Y1145169D03*
X903959Y1207823D03*
X906784Y1216607D03*
X913784Y1221057D03*
X910633Y1222799D03*
X906309Y1226647D03*
X909077Y1232724D03*
X899699Y1283872D03*
X910788Y1299456D03*
X906506Y1299188D03*
X902908Y1299828D03*
X911117Y1314130D03*
X902875Y1309301D03*
X905740Y1309264D03*
X908700Y1316300D03*
X911135Y1345560D03*
X904177Y1359955D03*
X899944Y1432359D03*
X908944Y1426359D03*
Y1429359D03*
Y1432359D03*
X911944Y1426359D03*
Y1429359D03*
Y1432359D03*
X905944Y1426359D03*
X899944D03*
X902944D03*
Y1429359D03*
X899944D03*
X902944Y1432359D03*
X905944Y1429359D03*
Y1432359D03*
X902944Y1438359D03*
X899944D03*
Y1441359D03*
X902944Y1435359D03*
X899944D03*
X908944Y1438359D03*
Y1441359D03*
X911944Y1438359D03*
Y1441359D03*
X902944D03*
X905944Y1438359D03*
Y1441359D03*
X908944Y1435359D03*
X911944D03*
X905944D03*
X919175Y116594D03*
X930118Y110784D03*
X925118D03*
X919175Y119594D03*
X924675Y124879D03*
X929697Y124663D03*
X919609Y124283D03*
X931041Y138838D03*
X918016Y161306D03*
X915267Y157370D03*
X916453Y167975D03*
X927898Y203256D03*
X925098D03*
X919577Y240945D03*
Y250394D03*
Y271654D03*
X919616Y268462D03*
X919577Y264567D03*
X923732Y304585D03*
X917882Y328216D03*
Y324816D03*
X915954Y344150D03*
X916229Y336333D03*
X919354Y344150D03*
X919629Y336333D03*
X927964Y344041D03*
X924564D03*
X923311Y349959D03*
X929943Y372600D03*
X921343Y376888D03*
X916330Y377748D03*
X929947Y376821D03*
X915072Y386992D03*
X914323Y398551D03*
Y403551D03*
Y401051D03*
X927563Y424445D03*
X924763D03*
X921963D03*
X927280Y436716D03*
X921680D03*
X924480D03*
X917541Y441280D03*
Y443780D03*
X927766Y456442D03*
X927596Y447453D03*
X921973Y469328D03*
X927401Y469059D03*
X916593Y469140D03*
X928999Y477948D03*
X920999D03*
X924999D03*
X917811Y544325D03*
X923453Y569578D03*
X923642Y561578D03*
X919080Y587640D03*
X921507Y578791D03*
X919038Y579378D03*
X923599Y581578D03*
X921217Y589216D03*
X913998Y597103D03*
X925949Y612363D03*
Y608863D03*
X922626Y633772D03*
X915800Y629700D03*
X918300D03*
X929690Y666593D03*
X920090Y666714D03*
X928353Y686342D03*
X928704Y680261D03*
X921061Y715386D03*
X926961Y723797D03*
X914202Y797460D03*
X923872Y798271D03*
X922352Y800809D03*
X917803Y811365D03*
X927916Y800909D03*
X929790Y828603D03*
X927916Y817015D03*
X925228Y816934D03*
X929181Y895029D03*
X921451Y903800D03*
X920628Y918042D03*
X916628D03*
X924628D03*
X928628D03*
X924628Y915242D03*
X920628D03*
X928628D03*
X916628D03*
X914193Y945318D03*
X928227Y951125D03*
X921364Y951251D03*
X918265Y969745D03*
X923289Y965780D03*
X926796Y966297D03*
X929741Y967006D03*
X916932Y994405D03*
X924956Y994321D03*
X924864Y1026762D03*
Y1023208D03*
X925024Y1018909D03*
X927861Y1024768D03*
X916749Y1084659D03*
X916992Y1076659D03*
X916749Y1092664D03*
X916875Y1098643D03*
X916749Y1104659D03*
X914637Y1210568D03*
Y1214838D03*
X930754Y1310564D03*
X924650Y1327819D03*
Y1324419D03*
X914033Y1345613D03*
X927193Y1361547D03*
X931159Y1379427D03*
X920360Y1387039D03*
X920255Y1383264D03*
X931199Y1371951D03*
X931159Y1390827D03*
Y1406027D03*
X914944Y1426359D03*
Y1429359D03*
Y1432359D03*
Y1438359D03*
Y1441359D03*
Y1435359D03*
X921498Y1446692D03*
X925697Y1460109D03*
X917744Y1453573D03*
X920244Y1451605D03*
X919285Y1456226D03*
X924803Y1474743D03*
X925435Y1478114D03*
X940761Y97667D03*
X945011Y95111D03*
X931144Y116594D03*
X936417Y102495D03*
X931144Y119594D03*
X934678Y125107D03*
X936151Y142862D03*
X943292Y143762D03*
X937192Y148717D03*
X945406Y180347D03*
X940406D03*
X942906D03*
X947424Y184419D03*
X944424Y186919D03*
X944760Y191977D03*
X942260D03*
X940487Y195680D03*
X942987D03*
X944424Y184419D03*
X934411Y202141D03*
X931698Y201556D03*
X934411Y207141D03*
X934477Y211491D03*
X934411Y204641D03*
X946234Y213390D03*
X942179Y215727D03*
X937438Y213817D03*
X936395Y218142D03*
X933403Y245507D03*
X936962Y249807D03*
X944248Y239844D03*
X945018Y276051D03*
X943183Y281652D03*
X930727Y302571D03*
X937000Y312284D03*
Y315684D03*
X940997Y331912D03*
Y335312D03*
X934128Y355168D03*
X934464Y358618D03*
X944238Y360828D03*
X934047Y369160D03*
X936175Y364823D03*
X931072Y386992D03*
X941872Y440942D03*
X933424Y458455D03*
X933161Y451442D03*
X933404Y463462D03*
X933412Y468942D03*
X936653Y526836D03*
X944351Y534211D03*
X948532Y541135D03*
X939992Y527726D03*
Y548726D03*
Y544726D03*
X948598Y546553D03*
X948621Y552726D03*
X931627Y557641D03*
Y569578D03*
Y581578D03*
Y577578D03*
Y573578D03*
X933725Y585936D03*
X933741Y598087D03*
Y594687D03*
X933725Y589336D03*
X944296Y611071D03*
X941859Y621311D03*
Y629311D03*
X943181Y632536D03*
X945434Y634325D03*
X941859Y625311D03*
X946128Y666522D03*
X935281Y680945D03*
X936026Y727450D03*
X933974Y719371D03*
X942676Y789286D03*
X933201Y798297D03*
X946970Y786366D03*
X944916Y808965D03*
X938357Y808856D03*
X931916Y817015D03*
X942858Y819430D03*
X945736Y819397D03*
X935124Y831382D03*
X940100Y830700D03*
X935262Y825135D03*
X932418D03*
X940716Y840074D03*
X944297Y839975D03*
X933021Y840893D03*
X933054Y843804D03*
X937200Y841000D03*
X936450Y858327D03*
X937551Y860801D03*
X932770Y878233D03*
X935765Y878317D03*
X934928Y871727D03*
X932319Y871626D03*
X938729Y874396D03*
X932300Y890200D03*
X942194Y891216D03*
X930800Y904840D03*
X941592Y900908D03*
X936628Y915242D03*
X940628D03*
X932628D03*
X936628Y918042D03*
X932628D03*
X936371Y951484D03*
X940716Y951733D03*
X946363Y951179D03*
X935255Y962725D03*
X945671Y982191D03*
X940015Y1020176D03*
X934911Y1023579D03*
X945864Y1023208D03*
X930864Y1026762D03*
X936864D03*
X942864D03*
X939864Y1023208D03*
X930864D03*
X930883Y1018751D03*
X936822Y1018988D03*
X942760Y1018751D03*
X943093Y1021769D03*
X932289Y1074182D03*
Y1071682D03*
X937489Y1074182D03*
X934889D03*
X940089D03*
Y1071682D03*
X934889D03*
X937489D03*
X944092Y1084666D03*
X931628Y1091409D03*
Y1088909D03*
X936828Y1091409D03*
X934228D03*
X939428D03*
Y1088909D03*
X934228D03*
X936828D03*
X943241Y1120636D03*
X940541D03*
X937941D03*
X935341D03*
X937941Y1130336D03*
X940541D03*
X943241D03*
X932641Y1139336D03*
X935341Y1130336D03*
Y1139336D03*
X934500Y1147708D03*
X932000D03*
X939298Y1207654D03*
X943891Y1306608D03*
X944207Y1320739D03*
X947308Y1325035D03*
X931137Y1375878D03*
X931159Y1383227D03*
X939559Y1398427D03*
X931159Y1394627D03*
Y1387027D03*
Y1398427D03*
Y1402227D03*
X939559D03*
X944235Y1406262D03*
X943725Y1430744D03*
Y1427744D03*
X934725Y1430744D03*
X940725Y1427744D03*
Y1430744D03*
X934725Y1427744D03*
X937725D03*
Y1430744D03*
X943725Y1433744D03*
Y1439744D03*
Y1436744D03*
X940725Y1433744D03*
Y1439744D03*
Y1436744D03*
X934725Y1433744D03*
X937725D03*
X934725Y1439744D03*
X937725D03*
X934725Y1436744D03*
X937725D03*
X937671Y1492139D03*
Y1488139D03*
X949221Y103411D03*
X949615Y97667D03*
X960411Y90650D03*
X960161Y95236D03*
X949380Y106561D03*
X947906Y180347D03*
X947424Y187219D03*
X950177Y215730D03*
X947040Y223885D03*
X948741Y229468D03*
X948785Y242464D03*
X951278Y250583D03*
X946482Y255940D03*
X949974Y291554D03*
X947733Y319680D03*
X950953Y317947D03*
X960376Y392807D03*
X962769Y451419D03*
X959816Y472905D03*
X955816Y473419D03*
Y464919D03*
X963816Y464419D03*
X962563Y485128D03*
X954182Y481467D03*
X958124Y492354D03*
X958736Y482165D03*
X958974Y504825D03*
X956474D03*
X953974D03*
X949823Y491982D03*
X959600Y496486D03*
X949823Y495982D03*
X957977Y500202D03*
X958915Y517401D03*
X956415D03*
X953915D03*
X959466Y522569D03*
Y525369D03*
X958081Y531882D03*
X955581D03*
X961166Y529169D03*
X952531Y531948D03*
X960581Y531882D03*
X948905Y534909D03*
X958016Y555194D03*
X960816D03*
X958016Y563194D03*
X960816D03*
Y571194D03*
X958016D03*
X959573Y581222D03*
X962373D03*
X959573Y591215D03*
X962373D03*
X962545Y607762D03*
X959745D03*
Y610562D03*
X962545D03*
X950479Y622285D03*
X954535Y610548D03*
X950667Y616905D03*
X963365Y628078D03*
X961352Y633736D03*
X950865Y633724D03*
X950748Y627713D03*
X956345Y633716D03*
X949137Y666660D03*
X954526Y666671D03*
X947556Y699550D03*
X956023Y706907D03*
X951151Y730111D03*
X963869Y725057D03*
X955950Y734178D03*
X957763Y725336D03*
X959950Y734178D03*
X957579Y744168D03*
X953837Y763025D03*
X950699Y779711D03*
X956017Y770300D03*
X957500Y780800D03*
X955076Y784861D03*
X950475Y789361D03*
X955225Y788984D03*
X949609Y796051D03*
X957487Y798553D03*
X951461Y812223D03*
X951791Y808121D03*
X957379Y826586D03*
X954760Y826734D03*
X951708Y818894D03*
X955712Y833988D03*
X956239Y829577D03*
X960100Y846665D03*
X954700Y837700D03*
X961175Y838525D03*
X955343Y866850D03*
X955850Y862902D03*
X957900Y856300D03*
X950300Y877800D03*
X953240Y876834D03*
X954567Y927654D03*
X964280Y927777D03*
X958567Y927654D03*
X947029Y915242D03*
X959545Y918306D03*
X951863Y936168D03*
X957235Y936398D03*
X962329Y936229D03*
X957671Y977921D03*
X949671D03*
X961671Y991564D03*
X953671D03*
X949671D03*
X953671Y982191D03*
X954937Y1021998D03*
X948864Y1026762D03*
X954864D03*
X951864Y1023208D03*
X957864D03*
X957678Y1018555D03*
X961208Y1018592D03*
X960636Y1021917D03*
X959371Y1026985D03*
X948975Y1021325D03*
X951956Y1071604D03*
X949356D03*
X954556D03*
Y1074104D03*
X949356D03*
X951956D03*
X946756Y1071604D03*
Y1074104D03*
X946592Y1084666D03*
X957981Y1081231D03*
X951839Y1088067D03*
X956833Y1102760D03*
X950326Y1114103D03*
Y1123803D03*
X952926D03*
X955526D03*
Y1114103D03*
X958226D03*
X952926D03*
X958226Y1123803D03*
X956552Y1132870D03*
X959252D03*
X962255Y1136426D03*
X962024Y1145169D03*
X959524D03*
X958690Y1210419D03*
X963263Y1219469D03*
X962855Y1214182D03*
X956509Y1220112D03*
X961146Y1225259D03*
X950865Y1263058D03*
X953365D03*
X955865D03*
X953365Y1260558D03*
X950865D03*
X955865D03*
X948259Y1295965D03*
X948832Y1371654D03*
X951832D03*
X952561Y1383465D03*
X952417Y1379528D03*
X949469D03*
X949385Y1375591D03*
X952385D03*
X952514Y1391339D03*
X952395Y1395276D03*
X952716Y1387402D03*
X952180Y1407087D03*
X950239Y1409555D03*
X948235Y1406262D03*
X946725Y1427744D03*
Y1430744D03*
X949725D03*
Y1427744D03*
X960883Y1427997D03*
Y1430997D03*
X946725Y1433744D03*
X949725D03*
X946725Y1439744D03*
X949725D03*
X946725Y1436744D03*
X949725D03*
X960883Y1433997D03*
Y1436997D03*
Y1439997D03*
X952695Y1444139D03*
X979002Y92874D03*
X965723Y90615D03*
X970094Y95236D03*
X970044Y99961D03*
X978051Y162368D03*
X968906Y207978D03*
Y212978D03*
Y215478D03*
Y210478D03*
X970865Y264068D03*
X973365D03*
X972160Y258880D03*
X977150Y331972D03*
Y338972D03*
X975631Y343112D03*
Y346612D03*
X971721Y407762D03*
X968348Y402369D03*
X971826Y430187D03*
X966694Y427599D03*
X968462Y429368D03*
X970840Y457339D03*
X968340D03*
X962816Y442919D03*
X972030Y446071D03*
X979910Y445603D03*
X970840Y459839D03*
Y462339D03*
X968340D03*
Y459839D03*
X963816Y472905D03*
X976397Y473045D03*
X972397Y465004D03*
X977327Y462371D03*
X965412Y485138D03*
X969297Y478625D03*
Y475825D03*
X970997Y482425D03*
X970412Y485138D03*
X967912D03*
X976873Y491214D03*
Y493714D03*
X970745Y539731D03*
X967042Y537658D03*
X970745Y542231D03*
X978303Y541895D03*
X975803D03*
X967042Y540458D03*
X975503Y544895D03*
X978303D03*
X978581Y582747D03*
X965173Y581222D03*
X978032Y590801D03*
X965173Y591215D03*
X977857Y597130D03*
X976027Y620653D03*
Y617853D03*
X968145Y610562D03*
X965345Y607762D03*
Y610562D03*
X968145Y607762D03*
X977857Y605443D03*
X973857D03*
X972354Y627908D03*
X968365Y633473D03*
X978865Y642184D03*
X966797Y667653D03*
X970197D03*
X965774Y706907D03*
X973712Y722064D03*
X968589Y722434D03*
X970839Y729923D03*
X965042Y722234D03*
X971081Y722637D03*
X978352Y730766D03*
X963950Y734178D03*
X973450Y747280D03*
X965983Y763567D03*
X966127Y776382D03*
X968094Y799792D03*
X976186Y789819D03*
X967562Y802982D03*
X978978Y817618D03*
X978214Y821224D03*
X967337Y828901D03*
X970040Y842903D03*
X969309Y839334D03*
X974437Y849140D03*
X973510Y834991D03*
X967842Y864801D03*
X970299Y853773D03*
X978880Y869552D03*
X967510Y868971D03*
X966813Y904556D03*
X973988Y910038D03*
X968507Y937615D03*
X971443Y938828D03*
X965671Y991564D03*
Y982191D03*
X963864Y1026762D03*
Y1023208D03*
X966366Y1081764D03*
X972776Y1093659D03*
X972255Y1083484D03*
X972776Y1088659D03*
Y1096659D03*
X966330Y1104333D03*
X972776Y1100659D03*
X967936Y1207823D03*
X978614Y1210568D03*
X970761Y1216607D03*
X978614Y1214838D03*
X978169Y1221268D03*
X974985Y1290950D03*
X979996Y1386100D03*
X963883Y1430997D03*
Y1427997D03*
X966883Y1430997D03*
Y1427997D03*
X969883D03*
Y1430997D03*
X975883Y1427997D03*
Y1430997D03*
X972883D03*
Y1427997D03*
X963883Y1433997D03*
X966883D03*
X969883D03*
X963883Y1436997D03*
Y1439997D03*
X966883Y1436997D03*
Y1439997D03*
X969883Y1436997D03*
Y1439997D03*
X975883Y1433997D03*
X972883D03*
X975883Y1436997D03*
X972883D03*
X975883Y1439997D03*
X972883D03*
X977547Y1546081D03*
X974547D03*
X971547D03*
X978958Y85193D03*
Y82593D03*
Y77393D03*
Y74793D03*
Y79993D03*
X987283Y98551D03*
X990833Y103783D03*
X981029Y104249D03*
Y107649D03*
X985595Y147540D03*
X989367Y141247D03*
X996834Y143740D03*
X994214Y148277D03*
X980651Y162368D03*
X987751Y162793D03*
Y165393D03*
Y167993D03*
Y170493D03*
X995256Y172190D03*
X994675Y177616D03*
X989959Y181366D03*
X986748Y181426D03*
X992754Y181009D03*
X986956Y184221D03*
X989573Y184012D03*
X994695Y213132D03*
X979362Y208213D03*
Y210713D03*
Y213213D03*
X986234Y208695D03*
X983434D03*
X985934Y211695D03*
X990992Y213859D03*
Y211359D03*
X983434Y211695D03*
X979362Y215713D03*
X994695Y215632D03*
X994939Y256303D03*
X989611Y265701D03*
X994698Y265896D03*
X986429Y270026D03*
X983929D03*
X981129D03*
X983929Y267526D03*
X986429D03*
X981129D03*
X991246Y281716D03*
X997187Y281982D03*
X987517Y314092D03*
X993552Y318175D03*
X990420Y340454D03*
Y337954D03*
X989630Y343862D03*
X983717Y341665D03*
X983956Y346652D03*
X993026Y353813D03*
X981719Y352217D03*
X988631Y349496D03*
X980045Y366559D03*
X986373Y370467D03*
X991392Y409230D03*
X985303Y464652D03*
Y462152D03*
Y459652D03*
X987803Y464652D03*
Y462152D03*
Y459652D03*
X981843Y464818D03*
X992206Y491133D03*
Y498633D03*
X988134Y495151D03*
X985634D03*
X980576Y492987D03*
X985334Y498151D03*
X980576Y495487D03*
X988134Y498151D03*
X992206Y493633D03*
Y496133D03*
X982375Y537877D03*
X992306Y555897D03*
Y553297D03*
X989888Y548366D03*
X987388D03*
X982388D03*
X984888D03*
X982375Y542877D03*
Y545377D03*
Y540377D03*
X992306Y561097D03*
Y563697D03*
Y566797D03*
Y558497D03*
X986301Y570686D03*
X989096Y570478D03*
X989513Y576484D03*
X989156Y573689D03*
X986510Y573303D03*
X992906Y578405D03*
X981857Y597232D03*
X991907Y596782D03*
X986688Y596089D03*
X983843Y619513D03*
Y616713D03*
Y613913D03*
X993857Y605443D03*
X981857Y605637D03*
X980703Y625013D03*
X986600Y717641D03*
X987461Y745796D03*
X981876Y745179D03*
X988371Y764143D03*
X983786Y765647D03*
X984357Y777555D03*
X997051Y778833D03*
X990699Y778630D03*
X987990Y774005D03*
X987394Y787490D03*
X987501Y812573D03*
X985921Y805135D03*
X994051Y810871D03*
X996385Y816141D03*
X979203Y829159D03*
X994094Y829000D03*
X982300Y821200D03*
X987702Y829159D03*
X989700Y846500D03*
X987202Y846395D03*
X987319Y843589D03*
X979203Y833159D03*
X989800Y843900D03*
X987200Y848940D03*
X987703Y837159D03*
X990457Y852043D03*
X983269Y853883D03*
X981700Y856300D03*
X979891Y876589D03*
X992441Y870398D03*
X988054Y888283D03*
X990300Y897500D03*
X979592Y902849D03*
X982783Y909995D03*
X979498Y907500D03*
X989311Y920364D03*
X983227Y968565D03*
X988240Y1020015D03*
Y1016923D03*
Y1023968D03*
X984909Y1081071D03*
X983751Y1078675D03*
X980969Y1076659D03*
X980726Y1084659D03*
X980852Y1098643D03*
X980726Y1104659D03*
Y1092664D03*
X986645Y1108465D03*
X989513Y1097683D03*
X995009Y1131223D03*
X991763Y1140378D03*
Y1128378D03*
Y1134378D03*
X984558Y1140774D03*
X988112Y1137774D03*
X984558Y1128774D03*
Y1134774D03*
X987804Y1131619D03*
X984817Y1303297D03*
X979001Y1288925D03*
X990613Y1324248D03*
Y1327048D03*
X993413Y1324248D03*
Y1327048D03*
X990501Y1320756D03*
X988784Y1361974D03*
X980139Y1381496D03*
X980166Y1373622D03*
X980203Y1377559D03*
X980047Y1397245D03*
X985448Y1398271D03*
X980092Y1389370D03*
X980139Y1393308D03*
X984136Y1401636D03*
X987136D03*
X986949Y1430997D03*
Y1427997D03*
X983949D03*
X989949Y1430997D03*
Y1427997D03*
X983949Y1430997D03*
X992949Y1427997D03*
Y1430997D03*
X986949Y1433997D03*
X983949D03*
X989949D03*
X992949D03*
X986949Y1436997D03*
X983949D03*
X986949Y1439997D03*
X983949D03*
X989949Y1436997D03*
Y1439997D03*
X992949Y1436997D03*
Y1439997D03*
X978934Y1444392D03*
X978987Y1489832D03*
X982241Y1489637D03*
X986773Y1546081D03*
X983773D03*
X980773D03*
X1011284Y68581D03*
X1011297Y80581D03*
X1003379Y72615D03*
Y76587D03*
X1004818Y100625D03*
X997837Y97475D03*
X1013480Y103621D03*
X997768Y106186D03*
X1009191Y112083D03*
X1005397Y141247D03*
X1009884Y143518D03*
X1008984Y152373D03*
X1012936Y178560D03*
X997929Y168697D03*
X1012826Y183834D03*
X1012999Y172665D03*
X999017Y191941D03*
X1003029Y192300D03*
X1012346Y190185D03*
X1007071Y192490D03*
X1013116Y200864D03*
X1003526Y206767D03*
X1006026D03*
X1001026D03*
X1010291Y199582D03*
X1013139Y207037D03*
X1013205Y212455D03*
X1002271Y228221D03*
Y231021D03*
X1010506Y221642D03*
X1003656Y221708D03*
X1006156D03*
X1000571Y224421D03*
X1001156Y221708D03*
X1002822Y236189D03*
X1005322D03*
X1007822D03*
X1002763Y248765D03*
X1005263D03*
X1007763D03*
X999714Y266114D03*
X1008260Y268195D03*
X1005460D03*
X1002960D03*
X1008260Y270695D03*
X1002960D03*
X1005460D03*
X1000698Y300276D03*
X1002580Y309619D03*
X1010499Y309062D03*
X1003181Y323057D03*
X1001105Y318006D03*
X1009770Y344486D03*
X997020Y345354D03*
X1003076Y332496D03*
X1000420Y353954D03*
X996024Y352132D03*
X1001825Y581659D03*
X998332Y578986D03*
X997857Y596729D03*
X995913Y619758D03*
Y616958D03*
Y614158D03*
X1001857Y605443D03*
X1003900Y628700D03*
X1001605Y627605D03*
X1005800Y637600D03*
X1002883Y622521D03*
X1001676Y678015D03*
X1011185Y724519D03*
X1009562Y722438D03*
X1003990Y765899D03*
X1007990D03*
X1002751Y757169D03*
X999990Y764566D03*
X1013151Y756726D03*
X1012695Y776728D03*
X999990Y774671D03*
X1013319Y785929D03*
X1007027Y792973D03*
X998376Y810970D03*
X1006054Y810969D03*
X1010699Y803454D03*
X1002699Y819475D03*
X1011144Y844340D03*
X1010977Y841737D03*
X1012703Y837659D03*
X1001187Y850084D03*
X1004577Y853679D03*
X1004713Y871389D03*
X998313Y888295D03*
X1005413Y905295D03*
X1004953Y923995D03*
X1008935Y924007D03*
X1004994Y955372D03*
X1007919Y948822D03*
X1011019D03*
X1004719D03*
X1012219Y954222D03*
X1006222Y980337D03*
X1009564Y988874D03*
X999879Y998507D03*
X1001805Y1007522D03*
X1008571Y1006648D03*
X1008759Y1023900D03*
X1002180Y1013678D03*
X1002652Y1023731D03*
X1005938Y1018307D03*
X995317Y1137378D03*
X996213Y1324248D03*
Y1327048D03*
X1009333Y1346693D03*
Y1343293D03*
X998600Y1369200D03*
X1008387Y1380797D03*
X998600Y1373400D03*
X997401Y1381200D03*
X999283Y1377400D03*
X1007850Y1368835D03*
X998643Y1398271D03*
X1008138Y1407186D03*
Y1409986D03*
X1005338Y1407186D03*
Y1409986D03*
X1008138Y1415586D03*
Y1412786D03*
X1005338Y1415586D03*
Y1412786D03*
X1008138Y1418386D03*
X1005338D03*
X998949Y1427997D03*
Y1430997D03*
X995949D03*
Y1427997D03*
X1009981Y1431097D03*
Y1428097D03*
X1006981D03*
Y1431097D03*
X998949Y1433997D03*
X995949D03*
X998949Y1436997D03*
X995949D03*
X998949Y1439997D03*
X995949D03*
X1009981Y1434097D03*
X1006981D03*
X1009981Y1437097D03*
X1006981D03*
X1009981Y1440097D03*
X1006981D03*
X1002194Y1444392D03*
X1015059Y55513D03*
X1020519Y60438D03*
X1017659Y60513D03*
X1026200Y86012D03*
X1017787Y85731D03*
X1026200Y94374D03*
X1015427Y88801D03*
X1022293Y94279D03*
X1018344Y94351D03*
X1021341Y86046D03*
X1021537Y116594D03*
X1027480Y110784D03*
X1021537Y119594D03*
X1021971Y124283D03*
X1027037Y124879D03*
X1020378Y161306D03*
X1012134Y152562D03*
X1017629Y157370D03*
X1021713Y176665D03*
Y168665D03*
X1013812Y186629D03*
X1021713Y196665D03*
X1021826Y186778D03*
X1021713Y192665D03*
X1021745Y204864D03*
Y208864D03*
X1026794Y218085D03*
X1017386Y219379D03*
X1018014Y228631D03*
X1023502Y248371D03*
X1014420Y265897D03*
X1011920D03*
X1027216Y289440D03*
X1022604Y290262D03*
X1016635Y300276D03*
X1012635D03*
X1025749D03*
X1020635D03*
X1022435Y312865D03*
X1021848Y310396D03*
X1020406Y350772D03*
X1012188Y443421D03*
X1015659Y679654D03*
Y683054D03*
X1021885Y698974D03*
X1022937Y691421D03*
X1014641Y724436D03*
X1012851Y722417D03*
X1026916Y719769D03*
X1018015Y751565D03*
X1013486Y750773D03*
X1024684Y756485D03*
X1017664Y779101D03*
X1014064Y793660D03*
X1018071Y798490D03*
X1013821Y813520D03*
X1014781Y810319D03*
X1017955Y812097D03*
X1021895Y818974D03*
X1020703Y837659D03*
X1013918Y851306D03*
X1017800Y867065D03*
X1016973Y877196D03*
X1016574Y874537D03*
X1016798Y890299D03*
X1021408Y895008D03*
X1024913Y884000D03*
X1012842Y910685D03*
X1022346Y917669D03*
X1029570Y917718D03*
X1018419Y917575D03*
X1014719Y938322D03*
X1027319D03*
X1027719Y958822D03*
X1014009Y980356D03*
X1018009D03*
X1014009Y988813D03*
X1018009D03*
X1021924Y980456D03*
X1026009Y988813D03*
X1022009D03*
X1017998Y1009655D03*
X1015198D03*
X1024570Y1024003D03*
X1011782Y1016591D03*
X1022143Y1030672D03*
X1019143D03*
X1016143D03*
X1025143D03*
X1023144Y1109564D03*
X1017297D03*
X1023144Y1122164D03*
X1017297D03*
X1023144Y1134764D03*
X1017297D03*
X1023144Y1147364D03*
X1017297D03*
X1023144Y1159964D03*
X1017297D03*
Y1172564D03*
X1023162Y1174445D03*
X1023139Y1184856D03*
X1017297Y1185164D03*
X1026221Y1214372D03*
X1021976Y1218169D03*
X1023358Y1363921D03*
X1013991Y1360842D03*
X1019391Y1377061D03*
X1012981Y1431097D03*
Y1428097D03*
X1015981D03*
Y1431097D03*
X1021981Y1428097D03*
Y1431097D03*
X1018981D03*
Y1428097D03*
X1012981Y1434097D03*
X1015981D03*
X1012981Y1437097D03*
Y1440097D03*
X1015981Y1437097D03*
Y1440097D03*
X1021981Y1434097D03*
X1018981D03*
X1021981Y1437097D03*
X1018981D03*
X1021981Y1440097D03*
X1018981D03*
X1025615Y1444492D03*
X1020023Y1489637D03*
X1016769Y1489832D03*
X1043123Y97667D03*
X1033506Y116594D03*
X1038779Y102495D03*
X1032480Y110784D03*
X1033506Y119594D03*
X1037040Y125107D03*
X1032059Y124663D03*
X1038513Y142862D03*
X1045654Y143762D03*
X1039554Y148717D03*
X1033403Y138838D03*
X1042102Y195176D03*
X1042183Y210509D03*
X1029594Y218085D03*
X1036107Y221970D03*
X1036173Y226320D03*
X1036107Y219470D03*
Y216970D03*
X1033394Y216385D03*
X1043875Y230556D03*
X1039134Y228646D03*
X1042860Y242078D03*
X1038091Y232971D03*
X1034741Y244571D03*
X1032121Y249108D03*
X1042084Y256394D03*
X1037290Y296293D03*
X1033890D03*
X1045650Y300093D03*
X1029639Y300141D03*
X1041783Y321114D03*
X1030220Y313554D03*
X1042948Y333696D03*
X1043106Y340230D03*
X1031259Y350427D03*
X1029885Y711762D03*
X1033200Y731700D03*
X1035619Y755809D03*
X1038344Y756476D03*
X1043016Y782161D03*
X1038678Y776750D03*
X1039251Y812340D03*
X1042414Y801443D03*
X1043425Y830800D03*
X1043626Y836563D03*
X1041100Y838500D03*
X1037527Y836486D03*
X1031813Y850273D03*
X1046045Y841217D03*
X1040822Y841339D03*
X1044390Y861210D03*
X1035185Y862793D03*
X1037685Y862789D03*
X1038363Y875288D03*
X1037709Y886209D03*
X1038010Y902565D03*
X1033019Y933022D03*
Y935822D03*
X1030819Y938422D03*
X1033370Y953994D03*
X1038009Y988813D03*
X1030009D03*
X1042009D03*
X1034009D03*
X1028943Y1016827D03*
X1034790D03*
X1028943Y1029427D03*
X1034790D03*
X1039499Y1098758D03*
X1039053Y1105091D03*
X1044553D03*
X1039098Y1102091D03*
X1039053Y1117691D03*
X1044553D03*
X1039098Y1114691D03*
Y1127291D03*
X1039053Y1130291D03*
X1044553D03*
Y1142891D03*
X1039098Y1139891D03*
X1039053Y1142891D03*
Y1155491D03*
X1044553D03*
X1039098Y1152491D03*
X1044553Y1168091D03*
X1039053D03*
X1039098Y1165091D03*
X1044553Y1180691D03*
X1039053D03*
X1039098Y1177691D03*
X1032831Y1207950D03*
X1029797Y1220921D03*
X1040606Y1230407D03*
X1043588Y1227300D03*
X1032867Y1431213D03*
Y1428213D03*
X1029867D03*
X1035867Y1431213D03*
Y1428213D03*
X1029867Y1431213D03*
X1038867Y1428213D03*
Y1431213D03*
X1041867D03*
Y1428213D03*
X1032867Y1434213D03*
X1029867D03*
X1035867D03*
X1038867D03*
X1032867Y1437213D03*
X1029867D03*
X1032867Y1440213D03*
X1029867D03*
X1035867Y1437213D03*
Y1440213D03*
X1038867Y1437213D03*
Y1440213D03*
X1041867Y1434213D03*
Y1437213D03*
Y1440213D03*
X1051583Y103411D03*
X1051977Y97667D03*
X1047373Y95111D03*
X1051742Y106561D03*
X1047102Y195176D03*
X1046120Y199248D03*
X1044602Y195176D03*
X1049120Y199248D03*
X1049602Y195176D03*
X1046120Y201748D03*
X1049120Y202048D03*
X1044683Y210509D03*
X1046456Y206806D03*
X1043956D03*
X1052720Y230117D03*
X1048130Y227824D03*
X1048736Y238714D03*
X1048217Y246874D03*
X1050437Y244297D03*
X1045364Y279895D03*
X1051796Y279965D03*
X1050164Y302748D03*
X1050076Y305512D03*
X1061387Y343509D03*
X1060679Y356151D03*
X1059549Y458711D03*
X1055885Y554555D03*
X1046068Y792742D03*
X1046930Y796557D03*
X1048314Y833102D03*
X1053392Y832788D03*
X1051550Y823146D03*
X1055700Y840900D03*
X1053913Y837718D03*
X1050358Y837793D03*
X1052500Y841200D03*
X1049087Y856033D03*
X1053909Y855472D03*
X1045300Y872352D03*
X1054900Y879321D03*
X1058155Y887635D03*
X1050295Y891100D03*
X1054009Y988813D03*
X1046009D03*
X1050009D03*
X1058009D03*
X1056199Y1012354D03*
X1050744Y1009354D03*
X1056199Y1024954D03*
X1050699D03*
Y1012354D03*
X1050744Y1021954D03*
X1046485Y1034538D03*
X1057212Y1040356D03*
X1049930Y1221407D03*
X1050605Y1224472D03*
X1049770Y1229402D03*
X1049720Y1234921D03*
X1052660Y1293257D03*
X1050002Y1293283D03*
X1049204Y1337377D03*
X1049670Y1347462D03*
X1046075Y1350650D03*
X1049493Y1350694D03*
X1044867Y1428213D03*
Y1431213D03*
Y1434213D03*
Y1437213D03*
Y1440213D03*
X1048403Y1444608D03*
X1062773Y90650D03*
X1068085Y90615D03*
X1072456Y95236D03*
X1072406Y99961D03*
X1062523Y95236D03*
X1071268Y207978D03*
Y212978D03*
Y215478D03*
Y210478D03*
X1074597Y264180D03*
X1074522Y258880D03*
X1076571Y310574D03*
X1060679Y368276D03*
X1062234Y378600D03*
Y382600D03*
X1062349Y458711D03*
X1064876Y453682D03*
X1063113Y455921D03*
X1061693Y463600D03*
X1062098Y603600D03*
X1061342Y610269D03*
X1061496Y612786D03*
X1062098Y619600D03*
X1063642Y634190D03*
X1062098Y623600D03*
X1066931Y645389D03*
X1060698Y931619D03*
X1069685Y933391D03*
X1066878Y931909D03*
X1070009Y988813D03*
X1069607Y980131D03*
X1066009Y980330D03*
X1062009Y988813D03*
X1065823Y988773D03*
X1074009Y988813D03*
X1070009Y997860D03*
X1073525Y1012428D03*
X1076110Y1029535D03*
X1065079Y1036920D03*
X1076577Y1041332D03*
X1074232Y1055836D03*
X1067866Y1051037D03*
X1060768Y1053457D03*
X1074650Y1070006D03*
X1069642Y1445541D03*
X1068861Y1451311D03*
X1081320Y85193D03*
Y82593D03*
Y79993D03*
Y77393D03*
Y74793D03*
X1089645Y98551D03*
X1081364Y92874D03*
X1083391Y104249D03*
Y107649D03*
X1087957Y147540D03*
X1091729Y141247D03*
X1083013Y162368D03*
X1090113Y165393D03*
Y162793D03*
X1080413Y162368D03*
X1090113Y170493D03*
Y167993D03*
X1092321Y181366D03*
X1089110Y181426D03*
X1091935Y184012D03*
X1089318Y184221D03*
X1081724Y208213D03*
X1085796Y208695D03*
Y211695D03*
X1081724Y210713D03*
Y213213D03*
X1088596Y208695D03*
X1088296Y211695D03*
X1081724Y215713D03*
X1077097Y264180D03*
X1091973Y265701D03*
X1083491Y267526D03*
X1088791D03*
X1086291D03*
X1083491Y270026D03*
X1086291D03*
X1088791D03*
X1093608Y281716D03*
X1080351Y328256D03*
X1079748Y322743D03*
Y319343D03*
X1080351Y331656D03*
X1082297Y340770D03*
X1092554Y340318D03*
X1085615Y339815D03*
X1092561Y353374D03*
X1082787Y348501D03*
X1091031Y374810D03*
X1089788Y550907D03*
X1087288D03*
X1089788Y553407D03*
X1087288D03*
X1089096Y541863D03*
Y545263D03*
X1091558Y566929D03*
X1091272Y569426D03*
X1088949Y568475D03*
X1089206Y570962D03*
X1086859Y569928D03*
X1085512Y572070D03*
X1078920Y856700D03*
X1090375Y899047D03*
X1076800Y1012900D03*
X1078755Y1031518D03*
X1079178Y1037884D03*
X1076868Y1047293D03*
X1079910Y1045264D03*
X1079822Y1151870D03*
X1083562Y1155610D03*
X1079822Y1159350D03*
X1083283Y1526583D03*
X1084000Y1529600D03*
X1091529Y1528718D03*
X1091525Y1546300D03*
X1090876Y1554183D03*
X1091569Y1561300D03*
X1092527Y1579422D03*
X1086469Y1588435D03*
X1090469D03*
X1083900Y1593206D03*
X1082176Y1600598D03*
X1090904Y1599047D03*
X1088021Y1606949D03*
X1093778Y1599574D03*
X1086904Y1599004D03*
X1090093Y1628297D03*
X1085474Y1629028D03*
X1089474Y1638213D03*
X1105741Y76587D03*
Y72615D03*
X1100199Y97475D03*
X1107180Y100625D03*
X1100130Y106186D03*
X1093195Y103783D03*
X1107759Y141247D03*
X1099196Y143740D03*
X1096576Y148277D03*
X1095116Y181009D03*
X1100291Y168697D03*
X1097618Y172190D03*
X1109903Y171523D03*
X1097037Y177616D03*
X1101379Y191941D03*
X1109433Y192490D03*
X1105888Y206767D03*
X1108388D03*
X1103388D03*
X1093354Y213859D03*
Y211359D03*
X1097057Y213132D03*
X1104633Y228221D03*
X1106018Y221708D03*
X1108518D03*
X1102933Y224421D03*
X1103518Y221708D03*
X1104633Y231021D03*
X1097057Y215632D03*
X1105184Y236189D03*
X1107684D03*
X1105125Y248765D03*
X1107625D03*
X1097301Y256303D03*
X1102076Y266114D03*
X1097060Y265896D03*
X1107822Y268195D03*
X1105322D03*
Y270695D03*
X1107822D03*
X1099549Y281982D03*
X1093478Y310305D03*
X1108779Y327705D03*
X1103432Y340544D03*
X1097976Y340477D03*
X1105012Y353504D03*
X1098845Y353404D03*
X1093841Y371335D03*
X1099501Y545528D03*
X1108236Y577716D03*
X1105298Y610400D03*
X1108045Y668153D03*
X1092769Y936975D03*
X1095080Y1513398D03*
X1096780Y1526700D03*
X1101402Y1531702D03*
X1095250Y1531600D03*
X1098617Y1546183D03*
X1096780Y1535400D03*
X1100876Y1554183D03*
X1099371Y1561153D03*
X1100476Y1579318D03*
X1102904Y1566668D03*
X1093682Y1582433D03*
X1098498Y1590435D03*
X1104233Y1587983D03*
X1100233Y1588000D03*
X1107620Y1603602D03*
X1098904Y1602138D03*
X1101946Y1614709D03*
X1096941Y1627905D03*
X1105474Y1629450D03*
X1101474Y1637820D03*
X1093474Y1638213D03*
X1105474Y1638426D03*
X1097474Y1637753D03*
X1114781Y58013D03*
X1113646Y68581D03*
X1120021Y60513D03*
X1122881Y60438D03*
X1113659Y80581D03*
X1120149Y85731D03*
X1117789Y88801D03*
X1123703Y86046D03*
X1120706Y94351D03*
X1124655Y94279D03*
X1115842Y103621D03*
X1123899Y116594D03*
X1111553Y112083D03*
X1123899Y119594D03*
X1124333Y124283D03*
X1112246Y143518D03*
X1111346Y152373D03*
X1122740Y161306D03*
X1114496Y152562D03*
X1119991Y157370D03*
X1124075Y168665D03*
Y176665D03*
X1115188Y183834D03*
X1115298Y178560D03*
X1115361Y172665D03*
X1116174Y186629D03*
X1124075Y192665D03*
Y196665D03*
X1115478Y200864D03*
X1114708Y190185D03*
X1124188Y186778D03*
X1124107Y204864D03*
X1115501Y207037D03*
X1115567Y212455D03*
X1124107Y208864D03*
X1112868Y221642D03*
X1119748Y219379D03*
X1120376Y228631D03*
X1110184Y236189D03*
X1110125Y248765D03*
X1116782Y265897D03*
X1114282D03*
X1110622Y268195D03*
Y270695D03*
X1115000Y329000D03*
Y334000D03*
Y339000D03*
X1118848Y382109D03*
X1118847Y551683D03*
Y561420D03*
Y558917D03*
X1122705Y588515D03*
X1114668Y577937D03*
X1117673Y606929D03*
X1122673Y595500D03*
X1122173Y604567D03*
X1122705Y591015D03*
X1123331Y610072D03*
X1123267Y616317D03*
X1117633Y618400D03*
X1117914Y612592D03*
X1115151Y650119D03*
X1115320Y646449D03*
X1115054Y662981D03*
X1116296Y691851D03*
X1111785Y686971D03*
X1118105Y707592D03*
X1128562Y86012D03*
Y94374D03*
X1135868Y116594D03*
X1141141Y102495D03*
X1129842Y110784D03*
X1134842D03*
X1135868Y119594D03*
X1139402Y125107D03*
X1129399Y124879D03*
X1134421Y124663D03*
X1140875Y142862D03*
X1141916Y148717D03*
X1135765Y138838D03*
X1129156Y218085D03*
X1131956D03*
X1138469Y221970D03*
X1138535Y226320D03*
X1138469Y219470D03*
Y216970D03*
X1135756Y216385D03*
X1141496Y228646D03*
X1140453Y232971D03*
X1137103Y244571D03*
X1134483Y249108D03*
X1125864Y248371D03*
X1137830Y336230D03*
X1135548Y455804D03*
X1134629Y465551D03*
X1126622Y506256D03*
X1139673Y530000D03*
X1139173Y540500D03*
X1138373Y549800D03*
X1138173Y547075D03*
X1137673Y568000D03*
X1138213Y558800D03*
X1138277Y562800D03*
X1129471Y732571D03*
X1153945Y103411D03*
X1145485Y97667D03*
X1154339D03*
X1149735Y95111D03*
X1154104Y106561D03*
X1148016Y143762D03*
X1149464Y195176D03*
X1148482Y199248D03*
X1151482D03*
X1144464Y195176D03*
X1146964D03*
X1151964D03*
X1151482Y202048D03*
X1146318Y206806D03*
X1144545Y210509D03*
X1147045D03*
X1148818Y206806D03*
X1148482Y201748D03*
X1146237Y230556D03*
X1155082Y230117D03*
X1150492Y227824D03*
X1151098Y238714D03*
X1145222Y242078D03*
X1150579Y246874D03*
X1152799Y244297D03*
X1147590Y253198D03*
X1145587Y339148D03*
X1142440Y396718D03*
X1157451Y618288D03*
X1156275Y656321D03*
X1155146Y699491D03*
X1152512Y728543D03*
X1148962Y747253D03*
X1152485Y764552D03*
X1147468Y766093D03*
X1154652Y791056D03*
X1145910Y803642D03*
X1153485Y813142D03*
X1154985Y802897D03*
X1153229Y848581D03*
X1170447Y90615D03*
X1165135Y90650D03*
X1174768Y99961D03*
X1164885Y95236D03*
X1173630Y207978D03*
Y210478D03*
Y212978D03*
Y215478D03*
X1173559Y304948D03*
X1171445Y422088D03*
X1166868Y442956D03*
X1168685Y438323D03*
X1168398Y456309D03*
X1168851Y445873D03*
X1163298Y465874D03*
X1159535Y546712D03*
Y542712D03*
X1165400Y553300D03*
X1167900D03*
X1161451Y618288D03*
X1160275Y656321D03*
X1164275D03*
X1162863Y678519D03*
X1159173Y678462D03*
X1170465Y677836D03*
X1157646Y699491D03*
X1162646D03*
X1160146D03*
X1169256Y694983D03*
X1163774Y713347D03*
X1166115Y718469D03*
X1171934Y733857D03*
X1173034Y765060D03*
X1169697Y791935D03*
X1164925Y791607D03*
X1164732Y802269D03*
X1173122Y802759D03*
X1163579Y850774D03*
X1161535Y844167D03*
X1159887Y869106D03*
X1174461Y914515D03*
X1183682Y85193D03*
Y82593D03*
Y74793D03*
Y79993D03*
Y77393D03*
X1183726Y92874D03*
X1174818Y95236D03*
X1185753Y107649D03*
Y104249D03*
X1182775Y162368D03*
X1185375D03*
X1188158Y211695D03*
X1184086Y210713D03*
Y213213D03*
Y208213D03*
X1190958Y208695D03*
X1188158D03*
X1184086Y215713D03*
X1176959Y264180D03*
X1179459D03*
X1177035Y257919D03*
X1185853Y267526D03*
X1188653D03*
X1185853Y270026D03*
X1188653D03*
X1179901Y306366D03*
X1181706Y310131D03*
X1178045Y312193D03*
X1181379Y316049D03*
X1174929Y319167D03*
X1179761Y336380D03*
X1187996Y331992D03*
X1191748Y392676D03*
X1188598Y381500D03*
X1178083Y442856D03*
X1189122Y442606D03*
X1176699Y451108D03*
X1176138Y458455D03*
X1179184Y453881D03*
Y446595D03*
X1188739Y446606D03*
X1190046Y463479D03*
X1174595Y771744D03*
X1176500Y784933D03*
X1185516Y844248D03*
X1190968Y848703D03*
X1184340Y851072D03*
X1183012Y856553D03*
X1190213Y856816D03*
X1187431Y868340D03*
X1180239Y868430D03*
X1179858Y883455D03*
X1179727Y886197D03*
X1181654Y894671D03*
X1185058Y883475D03*
X1187151Y921000D03*
X1182000Y936500D03*
X1189219Y940703D03*
X1192007Y98551D03*
X1202561Y97475D03*
X1195557Y103783D03*
X1202492Y106186D03*
X1190319Y147540D03*
X1194091Y141247D03*
X1201558Y143740D03*
X1198938Y148277D03*
X1192475Y165393D03*
Y162793D03*
Y167993D03*
Y170493D03*
X1199980Y172190D03*
X1194683Y181366D03*
X1191472Y181426D03*
X1197478Y181009D03*
X1202653Y168697D03*
X1199399Y177616D03*
X1203741Y191941D03*
X1194297Y184012D03*
X1191680Y184221D03*
X1205750Y206767D03*
X1195716Y211359D03*
Y213859D03*
X1199419Y213132D03*
X1190658Y211695D03*
X1205295Y224421D03*
X1205880Y221708D03*
X1199419Y215632D03*
X1199663Y256303D03*
X1199422Y265896D03*
X1204438Y266114D03*
X1194335Y265701D03*
X1191153Y267526D03*
Y270026D03*
X1201911Y281982D03*
X1195970Y281716D03*
X1201113Y315039D03*
X1190127Y324142D03*
X1195800Y324000D03*
X1206531Y393858D03*
X1208173Y398583D03*
X1192702Y440489D03*
X1192957Y435158D03*
X1193000Y444841D03*
X1192686Y449961D03*
X1196403Y458572D03*
X1192431Y868620D03*
X1192152Y884399D03*
X1192367Y903785D03*
X1190210Y900909D03*
X1191151Y936296D03*
X1193219Y940703D03*
X1197173Y940645D03*
X1196352Y951033D03*
X1191219Y967757D03*
X1191928Y987314D03*
X1198644Y985289D03*
X1195757Y988131D03*
X1203419Y1011161D03*
X1200008D03*
X1196300Y998600D03*
X1202028Y998349D03*
X1199700Y1013661D03*
X1201800Y1019431D03*
X1219783Y55513D03*
X1216008Y68581D03*
X1222383Y60513D03*
X1216021Y80581D03*
X1208103Y72615D03*
Y76587D03*
X1222511Y85731D03*
X1220151Y88801D03*
X1218204Y103621D03*
X1209542Y100625D03*
X1213915Y112083D03*
X1210121Y141247D03*
X1214608Y143518D03*
X1213708Y152373D03*
X1216858Y152562D03*
X1222353Y157370D03*
X1217550Y183834D03*
X1212265Y171523D03*
X1217723Y172665D03*
X1217660Y178560D03*
X1218536Y186629D03*
X1211795Y192490D03*
X1210268Y198671D03*
X1217840Y200864D03*
X1217070Y190185D03*
X1207753Y192300D03*
X1208250Y206767D03*
X1210750D03*
X1217863Y207037D03*
X1217929Y212455D03*
X1215230Y221642D03*
X1206995Y228221D03*
X1208380Y221708D03*
X1210880D03*
X1206995Y231021D03*
X1222110Y219379D03*
X1222738Y228631D03*
X1207546Y236189D03*
X1210046D03*
X1212546D03*
X1207487Y248765D03*
X1209987D03*
X1212487D03*
X1219144Y265897D03*
X1216644D03*
X1212984Y268195D03*
X1210184D03*
X1207684D03*
X1212984Y270695D03*
X1207684D03*
X1210184D03*
X1220723Y324466D03*
X1211892Y339559D03*
X1215776Y331072D03*
X1213173Y377912D03*
X1217177Y369925D03*
X1206693Y384410D03*
X1213173Y386500D03*
X1209872Y382047D03*
X1212173Y391496D03*
X1213261Y397912D03*
X1210173Y403500D03*
X1212173Y409000D03*
X1209426Y433069D03*
Y430469D03*
Y435669D03*
Y440869D03*
Y438269D03*
X1206626Y433069D03*
Y430469D03*
Y435669D03*
Y440869D03*
Y438269D03*
X1209980Y451677D03*
X1207480Y454177D03*
X1209980D03*
X1207480Y451677D03*
X1209184Y463618D03*
Y460218D03*
X1225243Y60438D03*
X1230924Y86012D03*
Y94374D03*
X1226065Y86046D03*
X1227017Y94279D03*
X1223068Y94351D03*
X1238230Y116594D03*
X1226261D03*
X1232204Y110784D03*
X1237204D03*
X1238230Y119594D03*
X1226261D03*
X1236783Y124663D03*
X1226695Y124283D03*
X1231761Y124879D03*
X1238127Y138838D03*
X1225102Y161306D03*
X1226437Y176665D03*
Y168665D03*
Y192665D03*
X1226550Y186778D03*
X1226469Y204864D03*
Y208864D03*
X1231518Y218085D03*
X1234318D03*
X1238118Y216385D03*
X1239465Y244571D03*
X1236845Y249108D03*
X1228226Y248371D03*
X1229252Y314890D03*
X1229028Y311740D03*
X1226436Y324518D03*
X1229922Y324550D03*
X1234904Y316942D03*
X1232197Y316964D03*
X1238293Y317296D03*
X1229438Y332584D03*
X1235589Y348015D03*
X1229942Y347937D03*
X1231506Y353470D03*
X1223431Y377912D03*
X1225755Y369391D03*
X1229122Y369355D03*
X1222601Y369251D03*
X1223431Y381912D03*
Y397912D03*
X1232833Y539315D03*
X1232149Y550137D03*
X1234941D03*
X1235930Y626229D03*
X1235292Y622912D03*
X1237500Y632405D03*
X1238034Y629961D03*
X1238695Y627313D03*
X1256307Y103411D03*
X1247847Y97667D03*
X1256701D03*
X1252097Y95111D03*
X1243503Y102495D03*
X1241764Y125107D03*
X1243237Y142862D03*
X1250378Y143762D03*
X1244278Y148717D03*
X1251826Y195176D03*
X1254326D03*
X1253844Y199248D03*
X1249326Y195176D03*
X1250844Y199248D03*
X1246826Y195176D03*
X1249407Y210509D03*
X1253844Y202048D03*
X1250844Y201748D03*
X1251180Y206806D03*
X1248680D03*
X1246907Y210509D03*
X1240831Y221970D03*
X1240897Y226320D03*
X1240831Y219470D03*
Y216970D03*
X1248599Y230556D03*
X1252854Y227824D03*
X1243858Y228646D03*
X1253460Y238714D03*
X1247584Y242078D03*
X1252941Y246874D03*
X1242815Y232971D03*
X1246808Y256394D03*
X1241205Y303962D03*
X1253245Y416888D03*
Y419488D03*
Y422088D03*
X1253087Y553101D03*
X1241629Y550065D03*
X1248106Y1004700D03*
X1245400Y1003700D03*
X1246000Y1014800D03*
X1252148Y1026223D03*
X1252500Y1014288D03*
X1246300Y1027800D03*
X1253424Y1138130D03*
X1250928Y1142828D03*
X1254200Y1146600D03*
X1249363Y1173065D03*
X1256218Y1175987D03*
X1249363Y1166065D03*
X1255439Y1172008D03*
X1255628Y1188345D03*
X1253056Y1194917D03*
X1254275Y1531334D03*
X1249894Y1527805D03*
X1253904Y1519645D03*
X1254275Y1539334D03*
X1250434Y1535334D03*
X1267497Y90650D03*
X1267247Y95236D03*
X1256466Y106561D03*
X1257444Y230117D03*
X1255161Y244297D03*
X1266962Y302167D03*
X1262665Y302730D03*
X1263328Y309003D03*
X1262075Y324075D03*
X1261659Y318258D03*
X1264088Y320382D03*
X1266616Y322456D03*
X1257000Y333500D03*
X1264215Y333215D03*
X1262500Y330655D03*
X1256000Y338000D03*
X1259991Y340691D03*
X1256000Y340500D03*
X1263500Y336000D03*
X1264659Y377173D03*
X1267944Y371767D03*
X1261764Y391533D03*
X1263484Y385644D03*
X1268659Y385123D03*
X1268067Y406060D03*
X1261231Y399918D03*
X1264336Y412106D03*
X1268328Y421489D03*
Y418889D03*
Y416289D03*
X1270397Y447081D03*
X1259223Y454334D03*
X1267540Y459330D03*
X1267493Y454214D03*
X1267836Y449045D03*
X1267843Y473571D03*
Y481071D03*
Y478571D03*
Y476071D03*
X1269629Y848124D03*
X1270892Y856343D03*
X1271121Y892513D03*
X1270276Y897062D03*
X1269221Y894760D03*
X1270586Y905324D03*
X1272661Y929858D03*
X1260539Y1134729D03*
X1267921D03*
X1266718Y1142666D03*
X1263921Y1134729D03*
X1268593Y1157544D03*
X1267104Y1167768D03*
X1272123D03*
X1271246Y1178240D03*
X1271256Y1185205D03*
X1262605Y1187215D03*
X1262298Y1180175D03*
X1260800Y1191096D03*
X1268571Y1201043D03*
X1264575D03*
X1261538Y1199814D03*
X1255296Y1196056D03*
X1263449Y1217228D03*
X1266113Y1219895D03*
X1269388Y1223170D03*
X1267333Y1531334D03*
X1262891Y1527334D03*
X1267183Y1539334D03*
X1262891Y1535334D03*
X1286044Y85539D03*
Y82939D03*
Y75139D03*
Y80339D03*
Y77739D03*
X1286088Y92874D03*
X1272809Y90615D03*
X1277130Y99961D03*
X1277180Y95236D03*
X1285137Y162368D03*
X1275992Y215478D03*
Y212978D03*
Y210478D03*
Y207978D03*
X1286448Y213213D03*
Y210713D03*
Y208213D03*
Y215713D03*
X1281821Y264180D03*
X1279321D03*
X1279246Y258880D03*
X1271571Y281185D03*
X1289345Y330655D03*
X1284419Y359377D03*
X1287437Y379429D03*
X1280699Y377173D03*
X1284659D03*
X1274436Y377350D03*
X1276659Y385123D03*
X1273659D03*
X1280659D03*
X1284333Y391569D03*
X1282760Y401066D03*
X1272421Y403300D03*
X1271828Y405889D03*
Y408489D03*
Y413689D03*
Y411089D03*
Y416289D03*
Y421489D03*
Y418889D03*
Y424089D03*
X1272215Y432718D03*
Y435518D03*
X1282092Y442118D03*
Y439318D03*
X1271828Y426689D03*
X1272927Y450091D03*
X1275927D03*
X1273397Y447081D03*
X1281737Y461034D03*
Y456034D03*
X1272927Y462060D03*
X1275927D03*
X1286005Y485580D03*
X1280631Y480194D03*
Y477694D03*
X1277897Y478876D03*
Y476376D03*
X1274415Y477053D03*
X1271915D03*
X1284900Y678800D03*
X1283400Y715500D03*
X1278255Y722241D03*
X1283400Y719700D03*
X1282539Y746076D03*
X1279539Y748576D03*
X1282539Y751076D03*
X1279539Y763576D03*
X1282539Y766076D03*
X1279539Y758576D03*
X1282539Y756076D03*
Y761076D03*
X1279539Y753576D03*
Y768576D03*
Y780576D03*
Y784576D03*
X1285092Y819500D03*
X1285500Y827500D03*
X1281388Y827388D03*
X1281777Y823500D03*
X1285500Y843500D03*
X1281331Y843331D03*
X1281269Y835492D03*
X1285500Y835500D03*
X1283025Y848305D03*
X1271438Y861846D03*
X1285500Y863500D03*
Y859500D03*
Y855500D03*
Y851500D03*
X1279460Y854487D03*
Y859487D03*
Y864487D03*
X1274396Y866896D03*
X1285500Y867500D03*
X1279460Y874487D03*
Y869487D03*
Y879487D03*
X1285302Y877283D03*
X1282285Y865602D03*
X1274264Y898591D03*
X1279460Y884487D03*
X1285302Y885783D03*
X1279299Y898813D03*
X1279460Y889487D03*
X1285302Y881783D03*
X1281075Y911075D03*
X1282184Y898854D03*
X1274400Y914123D03*
X1283494Y907176D03*
X1275493Y929858D03*
X1279493D03*
X1283493D03*
X1279693Y919800D03*
X1274670Y919808D03*
X1281400Y940256D03*
X1289547Y941000D03*
X1281733Y949475D03*
X1275788Y1124088D03*
X1282421Y1137129D03*
X1271921Y1134729D03*
X1275794D03*
X1282830Y1150087D03*
X1275050Y1157404D03*
X1280306Y1170767D03*
X1275965Y1187232D03*
X1280602Y1185238D03*
X1280395Y1180235D03*
X1272541Y1201043D03*
X1276575Y1201039D03*
X1280575Y1200969D03*
X1280694Y1208993D03*
X1274446Y1228226D03*
X1272235Y1226016D03*
X1297687Y-40256D03*
Y-43656D03*
X1297785Y33768D03*
X1302139Y26325D03*
X1302785Y31168D03*
X1294369Y98551D03*
X1304923Y97475D03*
X1297919Y103783D03*
X1288115Y104249D03*
Y107649D03*
X1294837Y162793D03*
X1287737Y162368D03*
X1294837Y165393D03*
Y167993D03*
Y170493D03*
X1301761Y177616D03*
X1302342Y172190D03*
X1299840Y181009D03*
X1293834Y181426D03*
X1297045Y181366D03*
X1294042Y184221D03*
X1296659Y184012D03*
X1301781Y213132D03*
X1298078Y211359D03*
Y213859D03*
X1290520Y211695D03*
X1293020D03*
X1290520Y208695D03*
X1293320D03*
X1301781Y215632D03*
X1302025Y256303D03*
X1296697Y265701D03*
X1301784Y265896D03*
X1293515Y270026D03*
X1291015D03*
X1288215D03*
Y267526D03*
X1293515D03*
X1291015D03*
X1304273Y281982D03*
X1298332Y281716D03*
X1294000Y324000D03*
X1303000Y326692D03*
X1293000Y338500D03*
X1303000Y331000D03*
X1302896Y343797D03*
Y340397D03*
X1292500Y335000D03*
X1299959Y356954D03*
X1294080Y349820D03*
X1291410Y371060D03*
X1295410Y371076D03*
X1293048Y379088D03*
X1298346Y379028D03*
X1293100Y409539D03*
X1296100D03*
X1293100Y406739D03*
X1296100Y407039D03*
X1295764Y401981D03*
X1298264D03*
X1300037Y398278D03*
X1297537D03*
X1292618Y413611D03*
X1295118D03*
X1300118D03*
X1297618D03*
X1292383Y424067D03*
X1294883D03*
X1299883D03*
X1297383D03*
X1299757Y438293D03*
Y441093D03*
X1290092Y442118D03*
Y439318D03*
X1299757Y443893D03*
X1287719Y470001D03*
X1290219D03*
X1299867Y477318D03*
X1299466Y466409D03*
X1299807Y472020D03*
X1288144Y489036D03*
X1291005Y485580D03*
X1288505D03*
X1301314Y484882D03*
X1299304Y487382D03*
X1290380Y495636D03*
Y492836D03*
X1300817Y568635D03*
X1301194Y565518D03*
X1305836Y660009D03*
X1298963Y659609D03*
X1289811Y677612D03*
X1289317Y706932D03*
X1291604Y781576D03*
Y776576D03*
Y771435D03*
X1295491Y798821D03*
X1298720Y798975D03*
X1289730Y806845D03*
X1302140Y812625D03*
X1302501Y824747D03*
X1297667Y832150D03*
X1293500Y827500D03*
X1296770Y828775D03*
X1293500Y843500D03*
Y835500D03*
X1296687Y839500D03*
X1293500Y851500D03*
X1294000Y863500D03*
X1293500Y879800D03*
Y871800D03*
Y875800D03*
X1288164Y892354D03*
X1296866Y894993D03*
X1305250Y889250D03*
X1293272Y887800D03*
X1293500Y883800D03*
X1291129Y892267D03*
X1294264Y905595D03*
X1301657Y899129D03*
X1288500Y901254D03*
X1298966Y899610D03*
X1296466D03*
X1298000Y917000D03*
X1294075D03*
X1304949Y928546D03*
X1292500Y928000D03*
X1295453Y928047D03*
X1291059Y917000D03*
X1302000D03*
X1302500Y939500D03*
X1300882Y937144D03*
X1296500Y961500D03*
X1289500Y949500D03*
X1300500Y960000D03*
X1290792Y961363D03*
X1300500Y970187D03*
X1297558Y970216D03*
X1292836Y975244D03*
X1292631Y979845D03*
X1299717Y1024136D03*
X1297852Y1014475D03*
X1295815Y1124943D03*
X1295893Y1122182D03*
X1310853Y37543D03*
X1314887Y45448D03*
X1318859D03*
X1311904Y100625D03*
X1320566Y103621D03*
X1304854Y106186D03*
X1316277Y112083D03*
X1305015Y168697D03*
X1319912Y183834D03*
X1314627Y171523D03*
X1320085Y172665D03*
X1320022Y178560D03*
X1306103Y191941D03*
X1319432Y190185D03*
X1314157Y192490D03*
X1320202Y200864D03*
X1310115Y192300D03*
X1308112Y206767D03*
X1313112D03*
X1310612D03*
X1320225Y207037D03*
X1320291Y212455D03*
X1313242Y221708D03*
X1310742D03*
X1309357Y231021D03*
Y228221D03*
X1317592Y221642D03*
X1308242Y221708D03*
X1307657Y224421D03*
X1309908Y236189D03*
X1314908D03*
X1312408D03*
X1312349Y248765D03*
X1309849D03*
X1314849D03*
X1306800Y266114D03*
X1310046Y268195D03*
X1312546D03*
X1315346D03*
X1319006Y265897D03*
X1312546Y270695D03*
X1310046D03*
X1315346D03*
X1318362Y310562D03*
X1305928Y318250D03*
X1308428D03*
X1315256Y336510D03*
X1313103Y339606D03*
X1312240Y334681D03*
X1315397Y333709D03*
X1308012Y348109D03*
X1305910Y377581D03*
X1310172Y367956D03*
X1308410Y379591D03*
X1311283Y370801D03*
X1308826Y389402D03*
X1306113Y383817D03*
X1312626Y387702D03*
X1315426D03*
X1306113Y386317D03*
Y388817D03*
X1309750Y438293D03*
Y441093D03*
Y443893D03*
X1311488Y471560D03*
X1307819Y474382D03*
X1307835Y470382D03*
X1319474Y467560D03*
X1319974Y475560D03*
X1311488D03*
X1318160Y520053D03*
X1317945Y523058D03*
X1319000Y562500D03*
Y558500D03*
Y586500D03*
Y574500D03*
Y578500D03*
Y605000D03*
Y590500D03*
X1319323Y598454D03*
X1319000Y621000D03*
Y609000D03*
Y633000D03*
Y625000D03*
Y637000D03*
Y653500D03*
Y649500D03*
Y641000D03*
Y669500D03*
Y665500D03*
Y681500D03*
Y677500D03*
X1313979Y677726D03*
X1319000Y685500D03*
Y696500D03*
Y700500D03*
Y712500D03*
Y716500D03*
Y724500D03*
Y728500D03*
Y732500D03*
X1321000Y796000D03*
X1313000D03*
X1317000Y799000D03*
Y788000D03*
X1313000D03*
X1315000Y811620D03*
X1319000D03*
X1317000Y804000D03*
X1313000D03*
X1321000D03*
X1310715Y820491D03*
Y822991D03*
Y817991D03*
X1310687Y830206D03*
Y832706D03*
Y827706D03*
X1310971Y842319D03*
X1305786Y867704D03*
X1310994Y866859D03*
X1309753Y877589D03*
X1305740Y877534D03*
X1310535Y870775D03*
X1308220Y889253D03*
X1311061Y889361D03*
X1314500Y911500D03*
X1319500Y901500D03*
X1314500Y905000D03*
X1305356Y902597D03*
X1319500Y905000D03*
X1309103Y917000D03*
X1313867Y925605D03*
X1311325Y928918D03*
X1319554Y925585D03*
X1309103Y936559D03*
X1306500Y936500D03*
X1315779Y943743D03*
X1313152Y936605D03*
X1312575Y943974D03*
X1321256Y943815D03*
X1311000Y961500D03*
X1307000Y960500D03*
X1315441Y960000D03*
X1307000Y970000D03*
X1311000Y970124D03*
X1307707Y979870D03*
X1317254Y990777D03*
X1317053Y988111D03*
X1319874Y989856D03*
X1307561Y986951D03*
X1315606Y1042825D03*
X1315756Y1039344D03*
X1312873Y1036543D03*
X1306385Y1036646D03*
X1319221Y1058097D03*
Y1060697D03*
X1316869Y1107997D03*
X1319069Y1112397D03*
X1318969Y1109397D03*
X1316869Y1113797D03*
Y1110897D03*
X1317437Y1160834D03*
X1318178Y1192621D03*
Y1190121D03*
X1319237Y1221428D03*
X1311237D03*
X1315237D03*
X1311237Y1233428D03*
Y1229428D03*
Y1225428D03*
X1315237Y1237428D03*
Y1233428D03*
Y1229428D03*
Y1225428D03*
X1319237Y1237428D03*
Y1233428D03*
Y1229428D03*
Y1225428D03*
X1315237Y1241428D03*
X1319237D03*
X1308107Y1283395D03*
X1310773Y1282411D03*
X1303900Y1288000D03*
X1318287Y1295381D03*
Y1291381D03*
X1324120Y22742D03*
X1331073Y33400D03*
X1328003Y32403D03*
X1328318Y27333D03*
X1336623Y30483D03*
X1322853Y37530D03*
X1328799Y168665D03*
Y176665D03*
X1320898Y186629D03*
X1328799Y192665D03*
Y196665D03*
X1328912Y186778D03*
X1328831Y204864D03*
Y208864D03*
X1324472Y219379D03*
X1325100Y228631D03*
X1321506Y265897D03*
X1334110Y310562D03*
X1321762D03*
X1329636Y307562D03*
X1326236D03*
X1332563Y326356D03*
X1325573Y326719D03*
X1332359Y322685D03*
X1326489Y356945D03*
X1331005Y356670D03*
X1331922Y359836D03*
X1325007Y370951D03*
X1334109Y373401D03*
X1334285Y386567D03*
X1331606D03*
X1328896D03*
X1320594Y387151D03*
Y382151D03*
Y384651D03*
X1329097Y435321D03*
Y438121D03*
X1326297Y435321D03*
Y438121D03*
X1329097Y440921D03*
X1326297D03*
X1329097Y443721D03*
X1326297D03*
X1335440Y452799D03*
X1329083Y448931D03*
X1329606Y459170D03*
X1332974Y474513D03*
X1321450Y520268D03*
X1321164Y523130D03*
X1326993Y556788D03*
X1331096Y549931D03*
X1327043Y573346D03*
X1327000Y562500D03*
X1326946Y567906D03*
X1338000Y562500D03*
X1327000Y578500D03*
Y583826D03*
X1335000Y594500D03*
X1327000Y605000D03*
Y594500D03*
Y609000D03*
X1333224Y615484D03*
X1327000Y613000D03*
Y621000D03*
X1335532Y622260D03*
X1338000Y609000D03*
X1327000Y629000D03*
X1327003Y623940D03*
X1335000Y641000D03*
X1338000Y653500D03*
X1327000Y641000D03*
X1327011Y646064D03*
X1327000Y657500D03*
X1335000Y685500D03*
X1327000D03*
Y695500D03*
Y700500D03*
X1338000D03*
X1327000Y711500D03*
Y716500D03*
X1335000Y732500D03*
X1327000D03*
X1330295Y746328D03*
X1326970Y736464D03*
X1336661Y753675D03*
Y745675D03*
Y737675D03*
X1330295Y751328D03*
X1330086Y763758D03*
X1330324Y779030D03*
X1336746Y781675D03*
X1329000Y796000D03*
X1325000Y799000D03*
X1337000Y796000D03*
X1333000Y799000D03*
Y788000D03*
X1329000D03*
X1321000D03*
X1325000D03*
X1331000Y811620D03*
X1327000D03*
X1329000Y804000D03*
X1325000D03*
X1333000D03*
X1323000Y811620D03*
X1335000D03*
X1335803Y826500D03*
X1331056Y904557D03*
X1336096Y905042D03*
X1336000Y900500D03*
X1324000Y901000D03*
X1331078Y900500D03*
X1330500Y925500D03*
X1334500D03*
X1326500D03*
X1333425Y930925D03*
X1324000D03*
X1333132Y933781D03*
X1336000Y943500D03*
X1329199Y933825D03*
X1323000Y934075D03*
X1326500Y943500D03*
X1335343Y961727D03*
X1321028Y961749D03*
X1332500Y961500D03*
X1325550Y960445D03*
X1332000Y969500D03*
X1327000D03*
X1329503Y991088D03*
X1334909Y990340D03*
X1332404Y988215D03*
X1329834Y988132D03*
X1324735Y989966D03*
X1327267Y988271D03*
X1322427Y988221D03*
X1333974Y1033483D03*
X1320549Y1037876D03*
X1322773Y1040599D03*
X1329221Y1058097D03*
X1321721D03*
X1324221D03*
X1326721D03*
Y1060697D03*
X1329221D03*
X1321721D03*
X1324221D03*
X1326163Y1082501D03*
X1326189Y1085205D03*
X1329163Y1082501D03*
X1329189Y1085205D03*
X1326189Y1088205D03*
X1326471Y1091227D03*
X1329189Y1088205D03*
X1323189Y1085205D03*
Y1087705D03*
X1323163Y1082501D03*
X1323021Y1090956D03*
X1337514Y1104335D03*
X1334956Y1105552D03*
X1321069Y1107997D03*
X1323021Y1093956D03*
X1331162Y1104792D03*
X1332669Y1106867D03*
X1321169Y1110597D03*
X1321954Y1113648D03*
X1326254D03*
X1328754D03*
X1323405Y1118801D03*
Y1116101D03*
X1325635Y1172384D03*
Y1162384D03*
Y1164884D03*
Y1167384D03*
Y1169884D03*
X1323135Y1172384D03*
Y1162384D03*
Y1164884D03*
Y1167384D03*
Y1169884D03*
X1334793Y1179421D03*
Y1181921D03*
Y1184421D03*
Y1186921D03*
X1320493Y1186709D03*
Y1184209D03*
Y1181709D03*
Y1179209D03*
X1325635Y1174884D03*
X1323135D03*
X1331643Y1192621D03*
Y1190121D03*
X1327237Y1221428D03*
X1331237D03*
X1335237D03*
X1323237D03*
X1327237Y1237428D03*
Y1233428D03*
Y1229428D03*
Y1225428D03*
X1331237Y1237428D03*
Y1233428D03*
Y1229428D03*
Y1225428D03*
X1335237Y1237428D03*
Y1233428D03*
Y1229428D03*
Y1225428D03*
X1323237Y1237428D03*
Y1233428D03*
Y1229428D03*
Y1225428D03*
X1335237Y1241428D03*
X1323237Y1245428D03*
Y1241428D03*
X1327237Y1245428D03*
Y1241428D03*
X1331237Y1245428D03*
Y1241428D03*
X1335237Y1245428D03*
X1333876Y1257160D03*
Y1260160D03*
X1337687Y-79306D03*
Y-82706D03*
X1336646Y22627D03*
X1336551Y26534D03*
X1340320Y147540D03*
X1344092Y141247D03*
X1351559Y143740D03*
X1348939Y148277D03*
X1348419Y265222D03*
X1340104Y279117D03*
X1344007Y279054D03*
X1337510Y310562D03*
X1347990Y322539D03*
X1341169Y325926D03*
X1346009Y336080D03*
X1346093Y340805D03*
X1349636Y340862D03*
X1346065Y347106D03*
X1338471Y356959D03*
X1337509Y373401D03*
X1349763Y371908D03*
X1342810Y408104D03*
X1345610D03*
X1348410D03*
X1336388Y424939D03*
X1342527Y420375D03*
X1345327D03*
X1348127D03*
X1336388Y427439D03*
X1346443Y431112D03*
X1352008Y435101D03*
X1352271Y442114D03*
X1346613Y440101D03*
X1352251Y447121D03*
X1346248Y452718D03*
X1340820Y452987D03*
X1352259Y452601D03*
X1347846Y461607D03*
X1339846D03*
X1339049Y471334D03*
X1343846Y461607D03*
X1346738Y564492D03*
X1339289Y568461D03*
X1342053Y579339D03*
X1346533Y576780D03*
X1340522Y586133D03*
X1343000Y590458D03*
X1346533Y581898D03*
X1344129Y606914D03*
X1344433Y601201D03*
X1339289Y614961D03*
X1344680Y619085D03*
X1346738Y611192D03*
X1346533Y628398D03*
X1346378Y623734D03*
X1342053Y625839D03*
X1340522Y632633D03*
X1343000Y636958D03*
X1346738Y655492D03*
X1339289Y659461D03*
X1346533Y667780D03*
X1342053Y670339D03*
X1346533Y672898D03*
X1340522Y677133D03*
X1343000Y681458D03*
X1350929Y687043D03*
X1340299Y686243D03*
X1346738Y702492D03*
X1346533Y719898D03*
X1339289Y706461D03*
X1342053Y717339D03*
X1346533Y714780D03*
X1340522Y724133D03*
X1343000Y728458D03*
X1344768Y737675D03*
Y741675D03*
Y745675D03*
Y749675D03*
Y753675D03*
Y761675D03*
Y757675D03*
X1336450Y765675D03*
X1344768Y773675D03*
Y781350D03*
X1345226Y777675D03*
X1341000Y799000D03*
X1345000Y796000D03*
X1341000Y788000D03*
X1345000D03*
X1337000D03*
X1348917Y796000D03*
Y788000D03*
X1352817Y796000D03*
X1349000Y804000D03*
X1351000Y811620D03*
X1347000D03*
X1343000D03*
X1337000Y804000D03*
X1345000D03*
X1341000D03*
X1349976Y829000D03*
X1350000Y825500D03*
X1340000Y900000D03*
X1351500Y903000D03*
Y906500D03*
X1340000Y906000D03*
Y903000D03*
X1351511Y900000D03*
X1350500Y925500D03*
X1338500D03*
X1342500D03*
X1346500D03*
X1353948Y943603D03*
X1345948D03*
X1349848Y936755D03*
X1338500Y930500D03*
X1350500D03*
X1342500D03*
X1346500D03*
X1337514Y988259D03*
X1343465Y1026123D03*
X1340665D03*
X1343465Y1028923D03*
X1340665D03*
X1347552Y1091816D03*
Y1089316D03*
X1345052Y1081816D03*
Y1084316D03*
Y1086816D03*
X1347552D03*
Y1084316D03*
X1350418Y1090288D03*
X1347552Y1081816D03*
X1344241Y1106298D03*
X1348997Y1107997D03*
X1350418Y1093088D03*
X1339234Y1101917D03*
X1339169Y1106897D03*
X1341984Y1110092D03*
X1345650Y1115896D03*
X1348997Y1113797D03*
Y1110897D03*
X1351197Y1112397D03*
X1351097Y1109397D03*
X1345650Y1118396D03*
X1347300Y1128332D03*
X1343725Y1128738D03*
X1343905Y1162384D03*
Y1164884D03*
Y1167384D03*
Y1169884D03*
Y1172384D03*
X1341405D03*
Y1169884D03*
Y1167384D03*
Y1164884D03*
Y1162384D03*
X1350963Y1172384D03*
Y1169884D03*
Y1167384D03*
Y1164884D03*
Y1162384D03*
X1351149Y1158200D03*
X1347423Y1186709D03*
Y1184209D03*
Y1181709D03*
Y1179209D03*
X1343905Y1174884D03*
X1341405D03*
X1350963D03*
X1337108Y1192621D03*
Y1190121D03*
X1345108D03*
Y1192621D03*
X1347237Y1221428D03*
X1343237D03*
X1339237D03*
X1347237Y1237428D03*
Y1233428D03*
Y1229428D03*
X1343237D03*
Y1233428D03*
Y1237428D03*
X1339237D03*
Y1233428D03*
Y1229428D03*
Y1225428D03*
X1347237Y1245428D03*
Y1241428D03*
X1343237D03*
Y1245428D03*
X1339237D03*
Y1241428D03*
X1339876Y1257160D03*
X1342876D03*
X1345876Y1260160D03*
Y1257160D03*
X1348876Y1260160D03*
Y1257160D03*
X1351876Y1260160D03*
Y1257160D03*
X1336876Y1260160D03*
Y1257160D03*
X1342876Y1260160D03*
X1339876D03*
X1360122Y141247D03*
X1364609Y143518D03*
X1363709Y152373D03*
X1366859Y152562D03*
X1363535Y327877D03*
X1366535Y335751D03*
Y339151D03*
X1363535Y331277D03*
Y343625D03*
X1366535Y354899D03*
Y351499D03*
X1363535Y347025D03*
X1360719Y424601D03*
X1352817Y788000D03*
X1367000Y811620D03*
X1365000Y804000D03*
X1355000Y811620D03*
X1363000D03*
X1353000Y804000D03*
X1359000Y811620D03*
X1357000Y804000D03*
X1361000D03*
X1354185Y906498D03*
X1367000Y904500D03*
X1363000Y900500D03*
X1367000D03*
X1354500Y925500D03*
X1366500D03*
X1358500D03*
X1362500D03*
X1365948Y939475D03*
X1357948Y938842D03*
X1361948Y943603D03*
X1369948D03*
X1362500Y930500D03*
X1366500D03*
X1354500D03*
X1358500D03*
X1364765Y1004766D03*
X1367444Y1003763D03*
X1357765Y1019766D03*
X1361265D03*
X1365049Y1028416D03*
X1365314Y1021793D03*
X1357265Y1026266D03*
Y1034266D03*
X1366265Y1039880D03*
X1369642Y1104335D03*
X1367084Y1105552D03*
X1353197Y1107997D03*
X1363290Y1104792D03*
X1364797Y1106867D03*
X1353297Y1110597D03*
X1354082Y1113648D03*
X1355533Y1116101D03*
Y1118801D03*
X1360882Y1113648D03*
X1358382D03*
X1353463Y1172384D03*
Y1169884D03*
Y1167384D03*
Y1164884D03*
Y1162384D03*
X1361723Y1179421D03*
Y1181921D03*
Y1184421D03*
Y1186921D03*
X1353463Y1174884D03*
X1364038Y1190121D03*
Y1192621D03*
X1363876Y1260160D03*
Y1257160D03*
X1354876Y1260160D03*
X1357876D03*
X1360876D03*
Y1257160D03*
X1357876D03*
X1354876D03*
X1366876Y1260160D03*
Y1257160D03*
X1376262Y116594D03*
X1382205Y110784D03*
X1387205D03*
X1376262Y119594D03*
X1386784Y124663D03*
X1376696Y124283D03*
X1381762Y124879D03*
X1375103Y161306D03*
X1372354Y157370D03*
X1384319Y218085D03*
X1381519D03*
X1386846Y249108D03*
X1378227Y248371D03*
X1384265Y320871D03*
Y325371D03*
X1383551Y337808D03*
X1384265Y329871D03*
X1383634Y342766D03*
X1384265Y334371D03*
X1375073Y356871D03*
Y361371D03*
X1383505Y349437D03*
X1384265Y352371D03*
X1372232Y361298D03*
X1383963Y366675D03*
X1377024Y397713D03*
X1375108Y420838D03*
X1375171Y424741D03*
X1375400Y435192D03*
X1375360Y432234D03*
X1383343Y508228D03*
X1383907Y516591D03*
X1383556Y554388D03*
X1378415Y558795D03*
X1383608Y571927D03*
X1378415Y563984D03*
Y569776D03*
X1378957Y584457D03*
X1383000Y584500D03*
X1382997Y581317D03*
X1383425Y590425D03*
X1378415Y605295D03*
X1383608Y618427D03*
X1378415Y610484D03*
Y616276D03*
X1383425Y636925D03*
X1378957Y630957D03*
X1384657Y631620D03*
X1378957Y627988D03*
X1378415Y649795D03*
Y654984D03*
Y660776D03*
X1386289Y672488D03*
X1383425Y681425D03*
X1378957Y675457D03*
X1383000Y675500D03*
X1378415Y696795D03*
Y701984D03*
X1378957Y719488D03*
X1378415Y707776D03*
X1383425Y728425D03*
X1378957Y722457D03*
X1385290Y722400D03*
X1371000Y811620D03*
X1381000Y804000D03*
X1373000D03*
X1369000D03*
X1385360Y811757D03*
X1381428Y812287D03*
X1375193Y811724D03*
X1376708Y901000D03*
X1378500Y925500D03*
X1374369Y925499D03*
X1370500Y925500D03*
X1382500D03*
X1382775Y930281D03*
X1373948Y940103D03*
X1374500Y930500D03*
X1370500D03*
X1378500D03*
X1381519Y996280D03*
X1383162Y991829D03*
X1373534Y1012325D03*
Y1004680D03*
X1378938Y1000586D03*
X1374034Y1015825D03*
X1374059Y1018860D03*
X1376359Y1016825D03*
X1378559Y1038534D03*
X1384784Y1033783D03*
X1385929Y1038665D03*
X1373874Y1032266D03*
Y1035716D03*
X1385152Y1046591D03*
X1377087Y1106365D03*
X1371362Y1101917D03*
X1371297Y1106897D03*
X1382456Y1107997D03*
X1374112Y1110092D03*
X1377778Y1115896D03*
X1384656Y1112397D03*
X1382456Y1110897D03*
Y1113797D03*
X1384556Y1109397D03*
X1377778Y1118396D03*
X1369233Y1169884D03*
Y1172384D03*
X1371733D03*
Y1169884D03*
Y1167384D03*
Y1164884D03*
Y1162384D03*
X1369233D03*
Y1164884D03*
Y1167384D03*
X1376861Y1160834D03*
X1383024D03*
X1369233Y1174884D03*
X1371733D03*
X1375459Y1197471D03*
Y1193471D03*
X1379959Y1197471D03*
Y1193471D03*
X1397848Y97667D03*
X1388231Y116594D03*
X1393504Y102495D03*
X1388231Y119594D03*
X1391765Y125107D03*
X1393238Y142862D03*
X1400379Y143762D03*
X1394279Y148717D03*
X1388128Y138838D03*
X1399327Y195176D03*
X1396827D03*
X1400845Y199248D03*
Y201748D03*
X1398681Y206806D03*
X1401181D03*
X1399408Y210509D03*
X1396908D03*
X1390832Y216970D03*
Y219470D03*
X1390898Y226320D03*
X1390832Y221970D03*
X1388119Y216385D03*
X1402855Y227824D03*
X1398600Y230556D03*
X1393859Y228646D03*
X1397585Y242078D03*
X1392816Y232971D03*
X1389466Y244571D03*
X1396809Y256394D03*
X1395726Y320529D03*
X1395568Y325529D03*
X1395726Y330529D03*
X1395736Y335529D03*
X1395726Y340529D03*
Y345529D03*
Y360529D03*
Y350529D03*
Y355529D03*
X1391896Y365529D03*
X1399884Y367165D03*
X1387847Y366710D03*
X1400231Y390256D03*
X1396528Y397454D03*
X1399571Y397418D03*
X1393575Y397310D03*
X1390553Y397436D03*
X1391623Y409900D03*
X1387125Y417312D03*
X1393177Y424804D03*
X1389557Y424678D03*
X1389431Y421593D03*
X1390271Y417578D03*
X1393208Y428109D03*
X1393336Y431100D03*
X1403085Y460565D03*
X1393944Y507856D03*
X1394044Y510990D03*
X1397079Y527726D03*
Y548726D03*
Y544726D03*
X1395605Y556217D03*
X1390741Y561000D03*
Y569000D03*
Y565000D03*
X1391087Y581317D03*
X1398946Y621311D03*
X1390741Y611500D03*
Y607500D03*
Y615500D03*
X1391586Y623692D03*
X1398946Y629311D03*
Y625311D03*
X1397000Y652000D03*
Y656000D03*
Y660000D03*
Y699000D03*
Y707000D03*
Y703000D03*
X1391040Y812027D03*
X1386335Y803704D03*
X1390537Y803679D03*
X1394537Y803653D03*
X1398530Y811717D03*
X1402417Y811692D03*
X1400069Y827515D03*
X1401300Y820485D03*
X1395955Y832697D03*
X1402000Y840000D03*
Y848000D03*
X1399872Y845109D03*
X1402000Y864000D03*
X1391316Y857849D03*
X1388488Y857822D03*
X1402000Y876000D03*
X1390182Y873460D03*
X1387582Y873487D03*
X1402000Y884000D03*
Y892000D03*
X1388479Y892923D03*
X1385979D03*
X1390979D03*
X1402000Y900000D03*
X1387520Y905307D03*
X1387753Y912629D03*
X1394891Y914783D03*
X1402187Y908270D03*
X1387504Y899931D03*
X1390541Y900086D03*
X1388980Y921075D03*
X1401000Y925789D03*
X1396869Y958707D03*
X1402064Y965913D03*
X1389192Y992568D03*
X1398854Y987277D03*
X1394885Y999941D03*
X1392031Y1004375D03*
X1385732Y1029482D03*
X1389762Y1043055D03*
X1387813Y1030952D03*
X1399807Y1036155D03*
X1399852Y1039779D03*
X1388523Y1090090D03*
X1392691Y1089224D03*
X1392086Y1092743D03*
X1392691Y1086724D03*
Y1084224D03*
Y1081724D03*
X1390191D03*
Y1084224D03*
Y1086724D03*
X1403101Y1104335D03*
X1400543Y1105552D03*
X1396749Y1104792D03*
X1388451Y1093048D03*
X1386656Y1107997D03*
X1398256Y1106867D03*
X1386756Y1110597D03*
X1394341Y1113648D03*
X1388992Y1118801D03*
Y1116101D03*
X1387541Y1113648D03*
X1391841D03*
X1388722Y1162384D03*
Y1164884D03*
Y1167384D03*
Y1169884D03*
Y1172384D03*
X1391222Y1162384D03*
Y1164884D03*
Y1167384D03*
Y1169884D03*
Y1172384D03*
X1388722Y1174884D03*
X1391222D03*
X1393695Y1186709D03*
Y1184209D03*
Y1181709D03*
Y1179209D03*
X1391380Y1190121D03*
Y1192621D03*
X1385821Y1260160D03*
X1391821Y1257160D03*
X1394821D03*
X1385821D03*
X1388821D03*
X1397821Y1260160D03*
Y1257160D03*
X1400821Y1260160D03*
Y1257160D03*
X1388821Y1260160D03*
X1394821D03*
X1391821D03*
X1385052Y1303139D03*
X1389052D03*
X1406308Y103411D03*
X1406702Y97667D03*
X1417498Y90650D03*
X1417248Y95236D03*
X1402098Y95111D03*
X1406467Y106561D03*
X1403845Y199248D03*
X1401827Y195176D03*
X1404327D03*
X1403845Y202048D03*
X1407445Y230117D03*
X1403461Y238714D03*
X1402942Y246874D03*
X1405162Y244297D03*
X1402921Y322403D03*
X1409830Y347649D03*
X1404690Y362209D03*
X1416912Y386903D03*
X1408854Y381207D03*
X1416470Y381397D03*
X1402968Y390177D03*
X1414369Y398056D03*
X1408254Y398041D03*
X1407844Y411033D03*
X1415610Y417644D03*
X1415674Y421278D03*
X1417856Y448419D03*
X1414903Y469905D03*
X1410903Y470419D03*
Y461919D03*
X1418903Y461419D03*
X1411269Y481467D03*
X1415623Y492268D03*
X1415823Y482165D03*
X1416061Y504825D03*
X1413561D03*
X1411061D03*
X1415064Y500202D03*
X1406910Y495982D03*
X1416413Y495649D03*
X1406910Y491982D03*
X1416002Y517401D03*
X1413502D03*
X1411002D03*
X1416553Y522569D03*
Y525369D03*
X1415168Y531882D03*
X1412668D03*
X1409618Y531948D03*
X1401438Y534211D03*
X1405992Y534909D03*
X1405619Y541135D03*
X1405685Y546553D03*
X1405708Y552726D03*
X1415103Y555194D03*
Y563194D03*
Y571194D03*
X1416660Y581222D03*
Y591215D03*
X1401383Y611071D03*
X1416832Y610562D03*
Y607762D03*
X1411622Y610548D03*
X1407566Y622285D03*
X1407754Y616905D03*
X1418439Y633736D03*
X1407952Y633724D03*
X1413432Y633716D03*
X1407835Y627713D03*
X1405229Y652028D03*
X1405000Y660000D03*
X1410000Y685000D03*
Y681000D03*
X1404500Y675000D03*
X1410000Y701000D03*
Y697000D03*
X1418000Y696000D03*
Y701000D03*
X1410000Y709000D03*
Y713000D03*
X1405000Y707000D03*
Y703000D03*
X1418000Y717000D03*
X1410000D03*
X1404500Y722000D03*
X1410000Y729000D03*
Y725000D03*
X1418000Y724000D03*
Y729000D03*
X1404249Y735858D03*
X1410000Y745000D03*
Y741000D03*
X1418000Y740000D03*
Y745000D03*
X1407482Y750853D03*
X1410000Y757000D03*
Y753000D03*
Y761000D03*
X1418000D03*
X1406867Y783273D03*
X1409115Y773520D03*
X1414597Y792375D03*
X1406483Y811717D03*
X1413500Y832000D03*
Y828000D03*
X1413449Y823934D03*
X1405402Y819917D03*
X1405500Y844000D03*
Y836000D03*
X1413500Y848000D03*
Y840000D03*
Y836000D03*
Y844000D03*
X1405500Y860000D03*
X1413500Y864000D03*
Y860000D03*
Y856000D03*
Y852000D03*
X1405500Y880000D03*
Y868000D03*
X1413500Y876000D03*
X1417797Y879501D03*
X1413500Y872000D03*
Y868000D03*
X1405500Y888000D03*
Y896000D03*
X1417081D03*
X1413500Y892000D03*
Y884000D03*
Y888000D03*
X1413733Y911137D03*
X1412376Y907848D03*
X1414876D03*
X1417376D03*
X1409876D03*
X1405500Y904000D03*
X1404760Y915186D03*
X1413500Y904000D03*
Y900000D03*
X1417284Y911009D03*
X1416802Y936845D03*
X1416244Y942285D03*
X1419337D03*
X1405214Y965074D03*
X1419446Y977192D03*
X1416618Y992307D03*
X1401265Y989465D03*
X1407265D03*
X1414143Y985486D03*
X1412698Y997590D03*
X1412609Y1008766D03*
X1412759Y1016266D03*
X1402215Y1020440D03*
X1414851Y1058097D03*
X1412351D03*
X1407351D03*
X1409851D03*
X1417351D03*
X1414851Y1060697D03*
X1412351D03*
X1407351D03*
X1409851D03*
X1417351D03*
X1405677Y1086796D03*
X1408177D03*
X1410677D03*
X1413177D03*
X1415677D03*
Y1084296D03*
X1413177D03*
X1410677D03*
X1408177D03*
X1405677D03*
X1416005Y1090288D03*
X1410546Y1106298D03*
X1404821Y1101917D03*
X1404756Y1106897D03*
X1416005Y1093088D03*
X1414584Y1107997D03*
X1411237Y1115896D03*
X1407571Y1110092D03*
X1414584Y1113797D03*
X1416784Y1112397D03*
X1414584Y1110897D03*
X1416684Y1109397D03*
X1411237Y1118396D03*
X1409425Y1129238D03*
X1413177Y1128894D03*
X1409492Y1167384D03*
Y1169884D03*
Y1172384D03*
X1406992D03*
Y1169884D03*
X1416550Y1162384D03*
Y1164884D03*
Y1167384D03*
Y1169884D03*
Y1172384D03*
X1406992Y1167384D03*
Y1164884D03*
Y1162384D03*
X1409492D03*
Y1164884D03*
X1416736Y1158200D03*
X1416550Y1174884D03*
X1409492D03*
X1406992D03*
X1407995Y1179421D03*
Y1181921D03*
Y1184421D03*
Y1186921D03*
X1410310Y1192621D03*
Y1190121D03*
X1404845D03*
Y1192621D03*
X1408736Y1222194D03*
X1412736D03*
X1416736D03*
X1408736Y1238194D03*
Y1234194D03*
Y1230194D03*
Y1226194D03*
X1412736Y1238194D03*
Y1234194D03*
Y1230194D03*
Y1226194D03*
X1416736Y1238194D03*
Y1234194D03*
Y1230194D03*
Y1226194D03*
X1412736Y1246194D03*
Y1242194D03*
X1416736Y1246194D03*
Y1242194D03*
X1408736D03*
Y1246194D03*
X1409821Y1260160D03*
X1412821D03*
Y1257160D03*
X1409821D03*
X1406821D03*
X1403821D03*
X1415821Y1260160D03*
Y1257160D03*
X1403821Y1260160D03*
X1406821D03*
X1417711Y1301729D03*
X1410817Y1305417D03*
X1407825Y1426975D03*
X1408536Y1536570D03*
X1407747Y1549054D03*
X1408044Y1559306D03*
X1407255Y1571732D03*
X1422810Y90615D03*
X1427131Y99961D03*
X1427181Y95236D03*
X1425993Y212978D03*
Y207978D03*
Y210478D03*
Y215478D03*
X1429322Y264180D03*
X1431822D03*
X1429247Y258880D03*
X1434166Y325361D03*
X1434164Y339232D03*
X1434038Y334114D03*
X1435818Y352361D03*
X1421005Y407616D03*
X1417903Y439919D03*
X1434997Y442603D03*
X1427117Y443071D03*
X1423427Y456839D03*
X1425927D03*
X1423427Y454339D03*
X1425927D03*
X1432414Y459371D03*
X1423427Y459339D03*
X1425927D03*
X1418903Y469905D03*
X1431484Y470045D03*
X1427484Y462004D03*
X1422499Y485138D03*
X1419650Y485128D03*
X1426384Y478625D03*
X1428084Y482425D03*
X1427499Y485138D03*
X1424999D03*
X1426384Y476125D03*
X1418253Y529169D03*
X1417668Y531882D03*
X1424129Y537658D03*
X1427832Y539731D03*
X1424129Y540458D03*
X1432590Y544895D03*
X1435390D03*
X1427832Y542231D03*
X1432890Y541895D03*
X1417903Y555194D03*
Y563194D03*
Y571194D03*
X1422260Y581222D03*
X1419460D03*
X1435119Y590801D03*
X1422260Y591215D03*
X1419460D03*
X1431000Y591000D03*
X1434944Y597130D03*
X1433114Y620653D03*
Y617853D03*
X1419632Y607762D03*
X1422432D03*
X1425232Y610562D03*
Y607762D03*
X1422432Y610562D03*
X1419632D03*
X1430944Y605443D03*
X1420452Y628078D03*
X1430175Y627852D03*
X1425452Y633473D03*
X1430481Y658153D03*
X1433529Y660564D03*
X1426615Y674112D03*
X1429000Y685000D03*
X1418000D03*
Y681000D03*
X1425909Y691120D03*
X1433464Y692658D03*
X1418000Y689000D03*
X1433053Y701839D03*
X1426000Y717000D03*
X1418000Y705000D03*
X1431522Y708633D03*
X1434000Y712958D03*
X1430289Y734961D03*
X1418000Y733000D03*
X1417969Y720894D03*
X1429000Y729000D03*
X1434000Y751958D03*
X1433153Y745839D03*
X1427000Y766500D03*
X1426000Y761000D03*
X1435000Y765500D03*
X1434000Y756958D03*
X1418023Y765343D03*
X1427000Y781834D03*
Y770500D03*
X1435000D03*
X1427000Y794500D03*
X1435000Y802500D03*
X1427000Y810500D03*
Y814500D03*
X1435000D03*
Y809500D03*
X1427000Y802500D03*
Y830500D03*
Y826500D03*
X1434975Y830500D03*
X1435000Y825500D03*
X1427000Y842500D03*
Y838500D03*
X1435000Y846500D03*
X1427000D03*
X1435043Y874694D03*
X1435082Y869475D03*
X1423190Y905295D03*
X1429059Y908579D03*
X1426085Y910281D03*
X1429907Y936998D03*
X1424897Y936777D03*
X1435516Y936000D03*
X1420699Y958452D03*
X1430839Y965546D03*
X1420740Y1008766D03*
X1428740Y1000766D03*
X1420740Y996766D03*
X1428864D03*
X1420740Y1012266D03*
X1428740Y1016266D03*
X1428823Y1020266D03*
X1435229Y1104335D03*
X1432671Y1105552D03*
X1428877Y1104792D03*
X1418784Y1107997D03*
X1430384Y1106867D03*
X1418884Y1110597D03*
X1421120Y1116101D03*
Y1118801D03*
X1426469Y1113648D03*
X1423969D03*
X1419669D03*
X1419050Y1162384D03*
Y1164884D03*
Y1167384D03*
Y1169884D03*
Y1172384D03*
Y1174884D03*
X1420625Y1186709D03*
Y1184209D03*
Y1181709D03*
Y1179209D03*
X1418310Y1192621D03*
Y1190121D03*
X1420736Y1222194D03*
X1424736D03*
X1428736D03*
X1432736D03*
X1420736Y1238194D03*
Y1234194D03*
Y1230194D03*
Y1226194D03*
X1424736Y1238194D03*
Y1234194D03*
Y1230194D03*
Y1226194D03*
X1428736Y1238194D03*
Y1234194D03*
Y1230194D03*
Y1226194D03*
X1432736Y1234194D03*
Y1230194D03*
Y1226194D03*
X1420736Y1246194D03*
Y1242194D03*
X1424736Y1246194D03*
Y1242194D03*
X1428736Y1246194D03*
Y1242194D03*
X1421821Y1257160D03*
X1418821D03*
Y1260160D03*
X1421821D03*
X1431080Y1301702D03*
X1421238Y1301712D03*
X1428009Y1301760D03*
X1424732Y1301603D03*
X1432258Y1414600D03*
X1430374Y1492474D03*
X1420877Y1494706D03*
X1421964Y1502813D03*
X1423930Y1520364D03*
X1429587Y1527450D03*
X1433405Y1546001D03*
X1432913Y1568679D03*
X1449685Y34228D03*
X1436045Y77393D03*
Y74793D03*
Y85193D03*
Y82593D03*
Y79993D03*
X1444370Y98551D03*
X1436089Y92874D03*
X1447920Y103783D03*
X1438116Y107649D03*
Y104249D03*
X1442682Y147540D03*
X1446454Y141247D03*
X1451301Y148277D03*
X1435138Y162368D03*
X1437738D03*
X1444838Y162793D03*
Y165393D03*
Y170493D03*
Y167993D03*
X1451762Y177616D03*
X1449841Y181009D03*
X1447046Y181366D03*
X1443835Y181426D03*
X1444043Y184221D03*
X1446660Y184012D03*
X1448079Y211359D03*
Y213859D03*
X1436449Y213213D03*
Y210713D03*
X1440521Y211695D03*
X1443021D03*
X1440521Y208695D03*
X1443321D03*
X1436449Y208213D03*
Y215713D03*
X1451785Y265896D03*
X1446698Y265701D03*
X1441016Y267526D03*
Y270026D03*
X1443516D03*
X1438216D03*
X1443516Y267526D03*
X1438216D03*
X1448333Y281716D03*
X1449060Y329861D03*
X1448948Y326448D03*
X1449060Y320861D03*
X1438829Y329861D03*
X1437064Y320861D03*
X1448822Y345324D03*
X1448734Y332910D03*
X1448500Y340575D03*
X1439712Y336673D03*
X1440420Y346833D03*
X1449060Y356861D03*
X1441180Y354909D03*
X1448572Y349441D03*
X1449060Y352361D03*
X1447502Y360785D03*
X1434697Y347125D03*
X1439719Y350387D03*
X1443041Y363648D03*
X1434608Y362584D03*
X1438768Y371655D03*
X1442633Y371502D03*
X1445906Y366030D03*
X1440523Y382747D03*
X1435424Y430361D03*
X1440390Y456652D03*
X1442890D03*
Y459152D03*
Y461652D03*
X1440390Y459152D03*
Y461652D03*
X1436930Y461818D03*
X1433960Y491214D03*
X1449293Y491133D03*
X1442721Y495151D03*
X1437663Y492987D03*
X1442421Y498151D03*
X1433960Y493714D03*
X1437663Y495487D03*
X1445221Y498151D03*
X1449293Y493633D03*
Y496133D03*
Y498633D03*
X1445221Y495151D03*
X1439462Y537877D03*
X1449393Y553297D03*
Y555897D03*
X1446988Y548418D03*
X1439462Y540377D03*
X1435390Y541895D03*
X1444488Y548418D03*
X1439488D03*
X1441988D03*
X1439462Y542877D03*
Y545377D03*
X1449393Y558497D03*
Y566797D03*
Y563697D03*
Y561097D03*
X1443388Y570686D03*
X1446183Y570478D03*
X1435668Y582747D03*
X1446600Y576484D03*
X1446243Y573689D03*
X1443597Y573303D03*
X1449993Y578405D03*
X1438944Y597232D03*
X1443775Y596089D03*
X1448994Y596782D03*
X1440930Y613913D03*
Y616713D03*
Y619513D03*
X1434944Y605443D03*
X1438944Y605637D03*
X1437790Y625013D03*
X1435952Y642184D03*
X1446323Y673183D03*
X1437738Y686992D03*
X1448991Y694392D03*
X1451976Y693844D03*
X1437533Y704398D03*
Y699280D03*
X1438930Y716363D03*
X1446860Y730735D03*
X1446538Y719548D03*
X1437738Y730992D03*
X1446717Y735536D03*
X1437533Y743280D03*
Y748398D03*
X1447289Y776461D03*
X1446000Y770500D03*
X1451000Y793458D03*
Y798458D03*
X1450253Y787339D03*
X1443000Y802500D03*
X1447000Y810500D03*
Y818500D03*
X1435000D03*
X1448000Y834500D03*
X1443000Y846500D03*
X1435000Y834500D03*
X1449000Y844500D03*
X1435212Y854042D03*
X1448726Y864400D03*
X1439891Y873821D03*
X1445367Y891888D03*
X1441223Y891957D03*
X1435745Y901500D03*
X1443231Y899006D03*
X1439103Y898564D03*
X1447261Y898571D03*
X1446022Y927000D03*
X1448137Y949440D03*
X1439031Y957683D03*
X1441088Y976409D03*
X1433996Y981437D03*
X1440700Y981763D03*
X1435669Y1005366D03*
X1440869Y1010256D03*
X1435197Y1028372D03*
X1442674Y1106365D03*
X1436949Y1101917D03*
X1436884Y1106897D03*
X1439699Y1110092D03*
X1443365Y1115896D03*
Y1118396D03*
X1442448Y1160834D03*
X1434820Y1162384D03*
Y1164884D03*
Y1167384D03*
Y1169884D03*
Y1172384D03*
X1437320D03*
Y1169884D03*
Y1167384D03*
Y1164884D03*
Y1162384D03*
X1434925Y1179421D03*
Y1181921D03*
Y1184421D03*
Y1186921D03*
X1434820Y1174884D03*
X1437320D03*
X1437240Y1192621D03*
Y1190121D03*
X1436736Y1222194D03*
Y1226194D03*
X1443660Y1310698D03*
X1440260D03*
X1446817Y1335846D03*
X1441200Y1338700D03*
X1435900Y1340800D03*
X1439258Y1414600D03*
X1446135Y1530876D03*
X1443103Y1527201D03*
X1441145Y1540415D03*
X1440153Y1563093D03*
X1443769Y1562173D03*
X1452717Y34052D03*
X1457347Y31518D03*
X1457829Y26425D03*
X1455013Y43128D03*
X1460466Y76587D03*
Y72615D03*
X1461905Y100625D03*
X1454924Y97475D03*
X1454855Y106186D03*
X1462484Y141247D03*
X1466971Y143518D03*
X1453921Y143740D03*
X1466071Y152373D03*
X1455016Y168697D03*
X1452343Y172190D03*
X1464628Y171523D03*
X1456104Y191941D03*
X1464158Y192490D03*
X1458113Y206767D03*
X1463113D03*
X1460613D03*
X1451782Y213132D03*
X1463243Y221708D03*
X1460743D03*
X1458243D03*
X1457658Y224421D03*
X1459358Y231021D03*
Y228221D03*
X1451782Y215632D03*
X1459909Y236189D03*
X1464909D03*
X1462409D03*
X1459850Y248765D03*
X1464850D03*
X1462350D03*
X1452026Y256303D03*
X1456801Y266114D03*
X1460047Y270695D03*
Y268195D03*
X1462547Y270695D03*
Y268195D03*
X1465347Y270695D03*
Y268195D03*
X1454274Y281982D03*
X1459060Y320861D03*
Y325361D03*
Y329861D03*
Y338861D03*
Y343361D03*
Y334361D03*
Y347861D03*
Y352361D03*
X1459873Y391705D03*
X1463145Y391579D03*
X1458214Y406231D03*
X1464536Y433114D03*
X1458912Y581659D03*
X1455419Y578986D03*
X1454944Y596729D03*
X1453000Y614158D03*
Y616958D03*
Y619758D03*
X1450944Y605443D03*
X1458944D03*
X1461474Y655807D03*
X1455761Y683448D03*
X1468372Y673812D03*
X1460111Y683536D03*
X1451428Y673252D03*
X1460816Y727964D03*
X1455291Y759656D03*
X1455159Y763714D03*
X1454504Y777575D03*
X1454533Y784780D03*
X1454738Y772492D03*
X1454533Y789898D03*
X1453102Y821102D03*
X1454541Y831339D03*
X1453102Y826500D03*
X1452619Y836457D03*
X1461113Y871389D03*
X1457218Y888764D03*
X1452641Y888033D03*
X1451286Y898549D03*
X1462500Y905295D03*
X1461888Y936055D03*
X1462000Y957000D03*
X1458202Y960288D03*
X1457937Y966712D03*
X1457352Y976277D03*
X1459519Y989432D03*
X1467096Y988813D03*
X1456966Y998507D03*
X1458892Y1007522D03*
X1465658Y1006648D03*
X1465846Y1023900D03*
X1463025Y1018307D03*
X1459267Y1013678D03*
X1456280Y1023405D03*
X1459683Y1028377D03*
X1481905Y-79278D03*
Y-82678D03*
X1479972Y40780D03*
X1472146Y55513D03*
X1468371Y68581D03*
X1474746Y60513D03*
X1477606Y60438D03*
X1468384Y80581D03*
X1474874Y85731D03*
X1483287Y86012D03*
X1472514Y88801D03*
X1478428Y86046D03*
X1475431Y94351D03*
X1479380Y94279D03*
X1470567Y103621D03*
X1478624Y116594D03*
X1466278Y112083D03*
X1484567Y110784D03*
X1478624Y119594D03*
X1479058Y124283D03*
X1484124Y124879D03*
X1477465Y161306D03*
X1469221Y152562D03*
X1474716Y157370D03*
X1478800Y168665D03*
Y176665D03*
X1469913Y183834D03*
X1470023Y178560D03*
X1470086Y172665D03*
X1470899Y186629D03*
X1469433Y190185D03*
X1478800Y192665D03*
Y196665D03*
X1470203Y200864D03*
X1478913Y186778D03*
X1478832Y204864D03*
X1470292Y212455D03*
X1470226Y207037D03*
X1478832Y208864D03*
X1467593Y221642D03*
X1474473Y219379D03*
X1475101Y228631D03*
X1480589Y248371D03*
X1471507Y265897D03*
X1469007D03*
X1477549Y327200D03*
Y322700D03*
Y345200D03*
Y340700D03*
Y331700D03*
Y358700D03*
Y349700D03*
Y354200D03*
X1480702Y368516D03*
X1468309Y408861D03*
X1475236Y412482D03*
X1466231Y423671D03*
X1469538Y416795D03*
X1466653Y428582D03*
X1471375Y433115D03*
X1477597Y682997D03*
X1475264Y680933D03*
X1474713Y685247D03*
X1479297Y693630D03*
X1476794Y691447D03*
X1476716Y704398D03*
X1479500Y689630D03*
Y697630D03*
X1474425Y712925D03*
X1479759Y720885D03*
X1469957Y706957D03*
X1474000Y707000D03*
X1479794Y709388D03*
X1472000Y727500D03*
X1469116Y719055D03*
X1480000Y731500D03*
X1479759Y743500D03*
X1479657Y735500D03*
X1469957Y750957D03*
X1476716Y748398D03*
X1480000Y739500D03*
X1471006Y744818D03*
X1470801Y739280D03*
X1474425Y756925D03*
X1479665Y754555D03*
X1474000Y753093D03*
X1476677Y827626D03*
X1473489Y861354D03*
X1474060Y877196D03*
X1473468Y874267D03*
X1482387Y872940D03*
X1474883Y868206D03*
X1473433Y891043D03*
X1473387Y897425D03*
X1482195Y885807D03*
X1470925Y920575D03*
X1480343Y914776D03*
X1480109Y943496D03*
X1480144Y946880D03*
X1479441Y961941D03*
X1480414Y952214D03*
X1476500Y974000D03*
X1482237Y966028D03*
X1479196Y970000D03*
X1480414Y975064D03*
X1475096Y980330D03*
X1471096D03*
X1479096Y988813D03*
X1471296D03*
X1475096D03*
X1483096D03*
X1475062Y1008300D03*
Y1002453D03*
X1482535Y1024254D03*
X1468869Y1018469D03*
X1476230Y1030672D03*
X1473230D03*
X1471374Y1118654D03*
X1474384Y1109564D03*
X1480231D03*
X1474384Y1122164D03*
X1480231D03*
X1474384Y1134764D03*
X1480231D03*
X1474384Y1147364D03*
X1480231D03*
X1474384Y1172564D03*
X1480231D03*
X1474384Y1159964D03*
X1480231D03*
X1474384Y1185164D03*
X1480231D03*
X1483308Y1214372D03*
X1479063Y1218169D03*
X1498621Y19043D03*
X1489556Y17645D03*
X1498621Y31043D03*
Y23043D03*
X1489829Y29424D03*
X1490563Y23043D03*
X1500210Y97667D03*
X1483287Y94374D03*
X1490593Y116594D03*
X1495866Y102495D03*
X1489567Y110784D03*
X1490593Y119594D03*
X1494127Y125107D03*
X1489146Y124663D03*
X1495600Y142862D03*
X1496641Y148717D03*
X1490490Y138838D03*
X1493260Y226320D03*
X1493194Y221970D03*
X1490481Y216385D03*
X1493194Y216970D03*
Y219470D03*
X1486681Y218085D03*
X1483881D03*
X1496221Y228646D03*
X1495178Y232971D03*
X1491828Y244571D03*
X1489208Y249108D03*
X1499171Y256394D03*
X1497446Y295877D03*
X1486860Y327200D03*
X1500659Y330024D03*
X1495605Y322700D03*
X1487318Y318200D03*
X1486360Y322700D03*
Y345200D03*
X1500386Y344642D03*
X1486913Y340327D03*
X1487152Y331272D03*
X1495689Y332534D03*
X1495521Y340700D03*
X1486360Y349700D03*
X1495521Y349681D03*
X1495925Y358700D03*
X1499839Y354001D03*
X1486890Y368576D03*
X1494286Y372699D03*
X1488000Y731500D03*
X1495500Y750500D03*
X1488731Y739500D03*
X1496629Y765000D03*
X1496763Y777000D03*
X1493301Y776911D03*
X1496814Y773000D03*
X1497000Y781000D03*
X1496756Y785000D03*
X1491425Y798425D03*
X1499633Y787794D03*
X1493716Y789898D03*
X1486957Y792457D03*
X1495170Y796670D03*
X1487050Y809413D03*
X1496845Y809000D03*
X1496806Y817000D03*
X1496621Y829000D03*
X1496447Y821000D03*
X1486386Y825296D03*
X1493092Y820444D03*
X1493038Y833898D03*
X1495240Y825000D03*
X1491425Y842425D03*
X1486957Y836457D03*
X1492625Y837324D03*
X1488138Y878339D03*
Y872839D03*
X1482566Y882154D03*
X1494954Y895264D03*
X1484824Y927324D03*
X1487240Y924453D03*
X1497063Y934000D03*
X1496072Y940201D03*
X1483324Y939324D03*
X1482921Y931324D03*
X1485500Y932500D03*
X1497075Y961000D03*
X1487240Y952012D03*
X1496072Y953981D03*
X1495500Y972500D03*
X1489500D03*
X1487096Y988813D03*
X1491096D03*
X1495096D03*
X1499096D03*
X1490235Y1004816D03*
X1487266Y1002046D03*
X1486030Y1016827D03*
X1491877D03*
X1486030Y1029427D03*
X1491877D03*
X1496140Y1105091D03*
X1496185Y1102091D03*
X1496140Y1117691D03*
X1496185Y1114691D03*
Y1127291D03*
X1496140Y1130291D03*
X1496185Y1139891D03*
X1496140Y1155491D03*
Y1142891D03*
X1496185Y1152491D03*
X1496140Y1168091D03*
X1496185Y1165091D03*
X1496140Y1180691D03*
X1496185Y1177691D03*
X1482705Y1200001D03*
X1489793Y1207737D03*
X1497693Y1230407D03*
X1508670Y103411D03*
X1509064Y97667D03*
X1504460Y95111D03*
X1508829Y106561D03*
X1502741Y143762D03*
X1506689Y195176D03*
X1506207Y199248D03*
X1501689Y195176D03*
X1503207Y199248D03*
X1499189Y195176D03*
X1504189D03*
X1506207Y202048D03*
X1503207Y201748D03*
X1499270Y210509D03*
X1501043Y206806D03*
X1501770Y210509D03*
X1503543Y206806D03*
X1509807Y230117D03*
X1500962Y230556D03*
X1505217Y227824D03*
X1505823Y238714D03*
X1499947Y242078D03*
X1505304Y246874D03*
X1507524Y244297D03*
X1503884Y295549D03*
X1501500Y321000D03*
X1501000Y317500D03*
X1501684Y336561D03*
X1516838Y347422D03*
X1515909Y354601D03*
X1516636Y458711D03*
X1513284Y552466D03*
X1504495Y796844D03*
X1510527Y833500D03*
X1504938Y859711D03*
X1500353Y859855D03*
X1500638Y873839D03*
X1512712Y867418D03*
X1502158Y899479D03*
X1510527Y908951D03*
X1513927D03*
X1504208Y909740D03*
X1509274Y921226D03*
X1505337Y921240D03*
X1509500Y937000D03*
Y944138D03*
X1516500Y947500D03*
X1501812Y938397D03*
X1512161Y957541D03*
X1509500Y950500D03*
X1498973Y975443D03*
X1511000Y970500D03*
X1511096Y988813D03*
X1507096D03*
X1503096D03*
X1515096D03*
X1513286Y1012354D03*
X1507831Y1009354D03*
X1507786Y1012354D03*
Y1024954D03*
X1513286D03*
X1507831Y1021954D03*
X1503572Y1034538D03*
X1501640Y1105091D03*
Y1117691D03*
Y1130291D03*
Y1142891D03*
Y1155491D03*
Y1168091D03*
Y1180691D03*
X1508356Y1220068D03*
X1500675Y1227300D03*
X1506807Y1234921D03*
X1507692Y1224472D03*
X1507058Y1229402D03*
X1517261Y-40358D03*
Y-43758D03*
X1525172Y90615D03*
X1519860Y90650D03*
X1529493Y99961D03*
X1529543Y95236D03*
X1519610D03*
X1528355Y210478D03*
Y215478D03*
Y212978D03*
Y207978D03*
X1519321Y378600D03*
Y382600D03*
X1519436Y458711D03*
X1521963Y453682D03*
X1520200Y455921D03*
X1518780Y463600D03*
X1519185Y603600D03*
Y619600D03*
Y623600D03*
X1520729Y634190D03*
X1524200Y646098D03*
X1518517Y878898D03*
X1518452Y873780D03*
X1525022Y909558D03*
X1522881Y901034D03*
X1522954Y897951D03*
X1521085Y921094D03*
X1515179D03*
X1527267Y932647D03*
X1522209Y937846D03*
X1521500Y947500D03*
X1528500Y947612D03*
X1529128Y952978D03*
X1521085Y957340D03*
X1525583Y968500D03*
X1530767Y972981D03*
X1519863Y977637D03*
X1525005Y974323D03*
X1530594Y979952D03*
X1531096Y988813D03*
X1523096D03*
X1519096D03*
X1527096Y997860D03*
X1526810Y1025090D03*
X1522904Y1021256D03*
X1521939Y1040818D03*
X1522099Y1035521D03*
X1531993Y1056453D03*
X1531961Y1050849D03*
X1524953Y1051037D03*
X1517855Y1053457D03*
X1538407Y85539D03*
Y82939D03*
Y75139D03*
Y80339D03*
Y77739D03*
X1546732Y98551D03*
X1538451Y92874D03*
X1540478Y107649D03*
Y104249D03*
X1545044Y147540D03*
X1540100Y162368D03*
X1537500D03*
X1547200Y162793D03*
Y165393D03*
Y167993D03*
Y170493D03*
X1546197Y181426D03*
X1546405Y184221D03*
X1538811Y213213D03*
Y210713D03*
X1542883Y211695D03*
X1545383D03*
X1542883Y208695D03*
X1545683D03*
X1538811Y208213D03*
Y215713D03*
X1534184Y264180D03*
X1531684D03*
X1531609Y258880D03*
X1549060Y265701D03*
X1545878Y270026D03*
X1543378D03*
X1540578D03*
X1543378Y267526D03*
X1540578D03*
X1545878D03*
X1544736Y305156D03*
X1545583Y316363D03*
X1539140Y320863D03*
X1545636Y325363D03*
X1542797Y329863D03*
X1545846Y334363D03*
X1544951Y343363D03*
X1538133Y354553D03*
X1545434Y352363D03*
X1546183Y541863D03*
Y545263D03*
X1544375Y553407D03*
X1546875D03*
X1544375Y550907D03*
X1546875D03*
X1542704Y572162D03*
X1543946Y569928D03*
X1546293Y570962D03*
X1546036Y568475D03*
X1548080Y910757D03*
X1547644Y903060D03*
X1532067Y1041832D03*
X1531947Y1046212D03*
X1531546Y1062769D03*
X1536909Y1151870D03*
Y1159350D03*
X1540649Y1155610D03*
X1562828Y72615D03*
Y76587D03*
X1564267Y100625D03*
X1557286Y97475D03*
X1557217Y106186D03*
X1550282Y103783D03*
X1548816Y141247D03*
X1564846D03*
X1556283Y143740D03*
X1553663Y148277D03*
X1552203Y181009D03*
X1549408Y181366D03*
X1557378Y168697D03*
X1554705Y172190D03*
X1554124Y177616D03*
X1558466Y191941D03*
X1549022Y184012D03*
X1560475Y206767D03*
X1562975D03*
X1554144Y213132D03*
X1550441Y211359D03*
Y213859D03*
X1560605Y221708D03*
X1560020Y224421D03*
X1563105Y221708D03*
X1561720Y231021D03*
Y228221D03*
X1554144Y215632D03*
X1562271Y236189D03*
X1562212Y248765D03*
X1554388Y256303D03*
X1559163Y266114D03*
X1554147Y265896D03*
X1562409Y268195D03*
Y270695D03*
X1556636Y281982D03*
X1550695Y281716D03*
X1550931Y305158D03*
X1554403Y316363D03*
X1553534Y327337D03*
X1553910Y331798D03*
X1553597Y336601D03*
X1553862Y344867D03*
X1551175Y347283D03*
X1556588Y545528D03*
X1548359Y569426D03*
X1548645Y566929D03*
X1562385Y610400D03*
X1564670Y650122D03*
X1565132Y668153D03*
X1561552Y665455D03*
X1548629Y927836D03*
X1548504Y915689D03*
X1548616Y931602D03*
X1551163Y952888D03*
X1552000Y969850D03*
X1571895Y58013D03*
X1570733Y68581D03*
X1577108Y60513D03*
X1570746Y80581D03*
X1577236Y85731D03*
X1574876Y88801D03*
X1581742Y94279D03*
X1577793Y94351D03*
X1572929Y103621D03*
X1568640Y112083D03*
X1581420Y124283D03*
X1569333Y143518D03*
X1568433Y152373D03*
X1579827Y161306D03*
X1571583Y152562D03*
X1577078Y157370D03*
X1572275Y183834D03*
X1566990Y171523D03*
X1572385Y178560D03*
X1572448Y172665D03*
X1573261Y186629D03*
X1571795Y190185D03*
X1566520Y192490D03*
X1572565Y200864D03*
X1565475Y206767D03*
X1572654Y212455D03*
X1572588Y207037D03*
X1581194Y208864D03*
X1565605Y221708D03*
X1569955Y221642D03*
X1576835Y219379D03*
X1577463Y228631D03*
X1564771Y236189D03*
X1567271D03*
X1564712Y248765D03*
X1567212D03*
X1567709Y270695D03*
X1573869Y265897D03*
X1571369D03*
X1567709Y268195D03*
X1564909Y270695D03*
Y268195D03*
X1563877Y325363D03*
Y316363D03*
X1571625Y344131D03*
X1574775Y333549D03*
X1563877Y329863D03*
Y343363D03*
Y334363D03*
X1578587Y341787D03*
X1578420Y338309D03*
X1574775Y344127D03*
X1563877Y352363D03*
X1575935Y382109D03*
X1577862Y554121D03*
X1575934Y561420D03*
Y558917D03*
X1565323Y577716D03*
X1571755Y577937D03*
X1579760Y595500D03*
X1574760Y606929D03*
X1579260Y604567D03*
X1574720Y618400D03*
X1575001Y612592D03*
X1580418Y610072D03*
X1580354Y616317D03*
X1576297Y627600D03*
X1577077Y631712D03*
X1574880Y645891D03*
X1571888Y649380D03*
X1572141Y662981D03*
X1578000Y678776D03*
X1569434Y677111D03*
X1568872Y686971D03*
X1575192Y707592D03*
X1579968Y60438D03*
X1585649Y86012D03*
Y94374D03*
X1580790Y86046D03*
X1592955Y116594D03*
X1580986D03*
X1586929Y110784D03*
X1591929D03*
X1592955Y119594D03*
X1580986D03*
X1596489Y125107D03*
X1586486Y124879D03*
X1591508Y124663D03*
X1592852Y138838D03*
X1581162Y168665D03*
Y176665D03*
Y192665D03*
Y196665D03*
X1581275Y186778D03*
X1581194Y204864D03*
X1586243Y218085D03*
X1595622Y226320D03*
X1592843Y216385D03*
X1595556Y216970D03*
Y219470D03*
Y221970D03*
X1589043Y218085D03*
X1594190Y244571D03*
X1591570Y249108D03*
X1582951Y248371D03*
X1595069Y337361D03*
X1595109Y342663D03*
X1594466Y350984D03*
X1592635Y455911D03*
X1591443Y465332D03*
X1595460Y549800D03*
X1595260Y547075D03*
X1594760Y568000D03*
X1595364Y562800D03*
X1595300Y558800D03*
X1596790Y1442557D03*
X1592643Y1460707D03*
X1593019Y1457557D03*
X1591775Y1473090D03*
X1596038Y1492000D03*
X1591925Y1512075D03*
X1591333Y1501980D03*
X1590748Y1523377D03*
X1602572Y97667D03*
X1611032Y103411D03*
X1611426Y97667D03*
X1606822Y95111D03*
X1598228Y102495D03*
X1611191Y106561D03*
X1597962Y142862D03*
X1605103Y143762D03*
X1599003Y148717D03*
X1604051Y195176D03*
X1605569Y199248D03*
X1601551Y195176D03*
X1606551D03*
X1609051D03*
X1608569Y199248D03*
X1603405Y206806D03*
X1605905D03*
X1601632Y210509D03*
X1604132D03*
X1608569Y202048D03*
X1605569Y201748D03*
X1603324Y230556D03*
X1607579Y227824D03*
X1612169Y230117D03*
X1598583Y228646D03*
X1608185Y238714D03*
X1602309Y242078D03*
X1607666Y246874D03*
X1597540Y232971D03*
X1609886Y244297D03*
X1604677Y253198D03*
X1596691Y287397D03*
X1596197Y293477D03*
X1607947Y332326D03*
X1605966Y343794D03*
X1602138Y351047D03*
X1596253Y375633D03*
X1596534Y379760D03*
X1599527Y396718D03*
X1596760Y530000D03*
X1596260Y540500D03*
X1611316Y685800D03*
X1611027Y722427D03*
X1611327Y735973D03*
X1611627Y780327D03*
X1609500Y776100D03*
X1611873Y795127D03*
X1606190Y803774D03*
X1606709Y819165D03*
X1600333Y1440504D03*
X1596836Y1446488D03*
X1600333Y1449068D03*
X1601968Y1453442D03*
X1597457Y1460662D03*
X1605430Y1468023D03*
X1597039Y1475100D03*
X1599726Y1474990D03*
X1600008Y1488492D03*
X1601500Y1514500D03*
X1608500Y1506000D03*
Y1515000D03*
X1613790Y1531334D03*
X1609348Y1527334D03*
X1613790Y1523334D03*
X1604000Y1519000D03*
X1600732Y1539334D03*
X1609348Y1535334D03*
X1598574Y1543373D03*
X1622222Y90650D03*
X1627534Y90615D03*
X1621972Y95236D03*
X1626147Y351033D03*
X1628636Y422088D03*
X1623955Y442956D03*
X1625772Y438323D03*
X1621596Y456386D03*
X1625938Y445873D03*
X1620385Y465874D03*
X1616622Y546712D03*
Y542712D03*
X1618538Y618288D03*
X1614538D03*
X1627224Y643252D03*
X1613362Y656321D03*
X1621362D03*
X1617362D03*
X1616260Y678462D03*
X1619950Y678519D03*
X1615913Y692245D03*
X1628200Y711417D03*
X1612800Y705900D03*
X1620600D03*
X1620500Y723200D03*
X1628343Y747288D03*
X1616683Y744517D03*
X1620100Y738300D03*
X1624000Y760900D03*
X1612573Y761427D03*
X1628027Y801427D03*
X1613117Y828117D03*
X1640769Y85539D03*
Y82939D03*
Y75139D03*
Y80339D03*
Y77739D03*
X1640813Y92874D03*
X1631905Y95236D03*
X1631855Y99961D03*
X1642840Y104249D03*
Y107649D03*
X1639862Y162368D03*
X1642462D03*
X1641173Y213213D03*
Y210713D03*
Y208213D03*
X1630717Y210478D03*
Y215478D03*
Y212978D03*
Y207978D03*
X1641173Y215713D03*
X1634046Y264180D03*
X1636546D03*
X1633971Y258880D03*
X1642940Y267526D03*
Y270026D03*
X1629553Y329067D03*
X1629302Y334402D03*
X1640030Y335550D03*
X1636561Y343072D03*
X1629514Y331727D03*
X1630691Y347432D03*
X1640197Y374690D03*
X1638340Y379536D03*
X1641615Y379600D03*
X1635170Y442856D03*
X1632439Y452265D03*
X1633225Y458455D03*
X1636271Y453881D03*
X1635185Y446595D03*
X1635283Y728117D03*
X1630327Y774627D03*
X1629927Y787327D03*
X1644552Y871353D03*
X1635176Y886761D03*
X1644718Y909263D03*
X1635000Y919263D03*
X1644325Y942120D03*
X1637771Y952120D03*
X1640581Y1551907D03*
X1649094Y98551D03*
X1659648Y97475D03*
X1652644Y103783D03*
X1659579Y106186D03*
X1647406Y147540D03*
X1651178Y141247D03*
X1658645Y143740D03*
X1656025Y148277D03*
X1649562Y162793D03*
Y165393D03*
Y167993D03*
Y170493D03*
X1656486Y177616D03*
X1654565Y181009D03*
X1648559Y181426D03*
X1651770Y181366D03*
X1659740Y168697D03*
X1657067Y172190D03*
X1660828Y191941D03*
X1651384Y184012D03*
X1648767Y184221D03*
X1647745Y211695D03*
X1645245Y208695D03*
X1648045D03*
X1656506Y213132D03*
X1652803Y211359D03*
Y213859D03*
X1645245Y211695D03*
X1656506Y215632D03*
X1656750Y256303D03*
X1656509Y265896D03*
X1661525Y266114D03*
X1651422Y265701D03*
X1648240Y267526D03*
X1645740D03*
Y270026D03*
X1648240D03*
X1653057Y281716D03*
X1658998Y281982D03*
X1658200Y315039D03*
X1654771Y352088D03*
X1645685Y381500D03*
X1648835Y390500D03*
X1650044Y435158D03*
X1649789Y440489D03*
X1646209Y442606D03*
X1650087Y444841D03*
X1649773Y449961D03*
X1653490Y458572D03*
X1645826Y446606D03*
X1647133Y463479D03*
X1647604Y467367D03*
X1656112Y768669D03*
X1657042Y773604D03*
X1647402Y881460D03*
X1648375Y886766D03*
X1650205Y925911D03*
X1647763Y919268D03*
X1648387Y945554D03*
X1647470Y952125D03*
X1651443Y981515D03*
X1647565Y981432D03*
X1652944Y993796D03*
X1653414Y990590D03*
X1676870Y55513D03*
X1673095Y68581D03*
X1679470Y60513D03*
X1673108Y80581D03*
X1665190Y76587D03*
Y72615D03*
X1679598Y85731D03*
X1677238Y88801D03*
X1675291Y103621D03*
X1666629Y100625D03*
X1671002Y112083D03*
X1667208Y141247D03*
X1671695Y143518D03*
X1670795Y152373D03*
X1673945Y152562D03*
X1674637Y183834D03*
X1669352Y171523D03*
X1674810Y172665D03*
X1674747Y178560D03*
X1675623Y186629D03*
X1674157Y190185D03*
X1668882Y192490D03*
X1667318Y198828D03*
X1674927Y200864D03*
X1664840Y192300D03*
X1662837Y206767D03*
X1667837D03*
X1665337D03*
X1674950Y207037D03*
X1675016Y212455D03*
X1667967Y221708D03*
X1665467D03*
X1664082Y231021D03*
Y228221D03*
X1672317Y221642D03*
X1662967Y221708D03*
X1662382Y224421D03*
X1669633Y236189D03*
X1667133D03*
X1664633D03*
X1667074Y248765D03*
X1664574D03*
X1669574D03*
X1676231Y265897D03*
X1673731D03*
X1670071Y268195D03*
Y270695D03*
X1667271Y268195D03*
X1664771D03*
Y270695D03*
X1667271D03*
X1673203Y328867D03*
X1668979Y339559D03*
X1666860Y353661D03*
X1663650Y353283D03*
X1673723Y353881D03*
X1670323Y353534D03*
X1670260Y377912D03*
X1669260Y391496D03*
X1663618Y393858D03*
X1663780Y384410D03*
X1666959Y382047D03*
X1670260Y386500D03*
X1669260Y409000D03*
X1665260Y398583D03*
X1670348Y397912D03*
X1667260Y403500D03*
X1663713Y440869D03*
Y438269D03*
X1666513Y433069D03*
Y430469D03*
Y435669D03*
Y440869D03*
Y438269D03*
X1663713Y433069D03*
Y430469D03*
Y435669D03*
X1664567Y451677D03*
X1667067D03*
X1664567Y454177D03*
X1667067D03*
X1666271Y460218D03*
Y463618D03*
X1682330Y60438D03*
X1688011Y86012D03*
Y94374D03*
X1683152Y86046D03*
X1680155Y94351D03*
X1684104Y94279D03*
X1683348Y116594D03*
X1694291Y110784D03*
X1689291D03*
X1683348Y119594D03*
X1683782Y124283D03*
X1693870Y124663D03*
X1688848Y124879D03*
X1695214Y138838D03*
X1682189Y161306D03*
X1679440Y157370D03*
X1683524Y168665D03*
Y176665D03*
Y192665D03*
X1683637Y186778D03*
X1683556Y204864D03*
Y208864D03*
X1688605Y218085D03*
X1691405D03*
X1679197Y219379D03*
X1679825Y228631D03*
X1693932Y249108D03*
X1685313Y248371D03*
X1686339Y314890D03*
X1686115Y311740D03*
X1683523Y324518D03*
X1677810Y324466D03*
X1686408Y332584D03*
X1687424Y347937D03*
X1692676Y348015D03*
X1688593Y353470D03*
X1691182Y357016D03*
X1680518Y377912D03*
Y381912D03*
Y397912D03*
X1689920Y539315D03*
X1689236Y550137D03*
X1692028D03*
X1693000Y626912D03*
X1692379Y622912D03*
X1704934Y97667D03*
X1709184Y95111D03*
X1695317Y116594D03*
X1700590Y102495D03*
X1695317Y119594D03*
X1698851Y125107D03*
X1700324Y142862D03*
X1707465Y143762D03*
X1701365Y148717D03*
X1708913Y195176D03*
X1710931Y199248D03*
X1706413Y195176D03*
X1703913D03*
X1707931Y199248D03*
Y201748D03*
X1706494Y210509D03*
X1703994D03*
X1705767Y206806D03*
X1708267D03*
X1697984Y226320D03*
X1695205Y216385D03*
X1697918Y216970D03*
Y219470D03*
Y221970D03*
X1705686Y230556D03*
X1709941Y228747D03*
X1700945Y228646D03*
X1704671Y242078D03*
X1699902Y232971D03*
X1696552Y244571D03*
X1703895Y256394D03*
X1700223Y292141D03*
X1703609Y287320D03*
X1698292Y303962D03*
X1698716Y550065D03*
X1708015Y1142700D03*
X1711333Y1146609D03*
X1706450Y1173065D03*
X1703400Y1174400D03*
X1713394Y103411D03*
X1713788Y97667D03*
X1724584Y90650D03*
X1724334Y95236D03*
X1713553Y106561D03*
X1711413Y195176D03*
X1710931Y202048D03*
X1714531Y230117D03*
X1710547Y238714D03*
X1710028Y246874D03*
X1712248Y244297D03*
X1716755Y326179D03*
X1712226Y344028D03*
X1715930Y340969D03*
X1715590Y331719D03*
X1721746Y377173D03*
X1715228Y387966D03*
X1718851Y391533D03*
X1720571Y385644D03*
X1725746Y385123D03*
X1718318Y399918D03*
X1725154Y406060D03*
X1725415Y416289D03*
Y418889D03*
Y421489D03*
X1721423Y412106D03*
X1716310Y454334D03*
X1724627Y459330D03*
X1724580Y454214D03*
X1724923Y449045D03*
X1724930Y473571D03*
Y476071D03*
Y478571D03*
Y481071D03*
X1710174Y553101D03*
X1717626Y1134729D03*
X1710511Y1138130D03*
X1721008Y1134729D03*
X1723805Y1142666D03*
X1725008Y1134636D03*
X1725680Y1157544D03*
X1724191Y1167768D03*
X1713239Y1176038D03*
X1712526Y1171950D03*
X1728343Y1185205D03*
X1719692Y1187215D03*
X1719385Y1180175D03*
X1712715Y1188500D03*
X1721662Y1201043D03*
X1725658D03*
X1718625Y1199814D03*
X1712542Y1196600D03*
X1720536Y1217228D03*
X1723200Y1219895D03*
X1710825Y1231688D03*
X1712966Y1229841D03*
X1743175Y92874D03*
X1729896Y90615D03*
X1734267Y95236D03*
X1734217Y99961D03*
X1742224Y162368D03*
X1733079Y207978D03*
Y210478D03*
Y215478D03*
Y212978D03*
X1736408Y264180D03*
X1738908D03*
X1736333Y258880D03*
X1744524Y379429D03*
X1741746Y377173D03*
X1737786D03*
X1729751D03*
X1733746Y385123D03*
X1730746D03*
X1737746D03*
X1741420Y391569D03*
X1739847Y401066D03*
X1729508Y403300D03*
X1728915Y405889D03*
Y408489D03*
Y413689D03*
Y411089D03*
Y416289D03*
Y421489D03*
Y418889D03*
Y424089D03*
X1729302Y432718D03*
Y435518D03*
X1739179Y439318D03*
X1728915Y426689D03*
X1739179Y442118D03*
X1733014Y450091D03*
X1730014D03*
X1727404Y447209D03*
X1730404D03*
X1738824Y456034D03*
Y461034D03*
X1733014Y462060D03*
X1730014D03*
X1734952Y479217D03*
X1737646Y477213D03*
Y479713D03*
X1729002Y477053D03*
X1731502D03*
X1734952Y476717D03*
X1741800Y917900D03*
X1742029Y1116251D03*
X1739508Y1137129D03*
X1729008Y1134729D03*
X1732881D03*
X1739917Y1150087D03*
X1732137Y1157404D03*
X1737393Y1170767D03*
X1729210Y1167768D03*
X1728333Y1178240D03*
X1733052Y1187310D03*
X1737689Y1185238D03*
X1737482Y1180235D03*
X1733662Y1201039D03*
X1729628Y1201043D03*
X1737662Y1200969D03*
X1737781Y1208993D03*
X1726475Y1223170D03*
X1731533Y1228226D03*
X1729322Y1226016D03*
X1743131Y85539D03*
Y82939D03*
Y75139D03*
Y80339D03*
Y77739D03*
X1751456Y98551D03*
X1755006Y103783D03*
X1745202Y104249D03*
Y107649D03*
X1744824Y162368D03*
X1751924Y162793D03*
Y165393D03*
Y167993D03*
Y170493D03*
X1758848Y177616D03*
X1759429Y172190D03*
X1756927Y181009D03*
X1750921Y181426D03*
X1754132Y181366D03*
X1751129Y184221D03*
X1753746Y184012D03*
X1747607Y211695D03*
X1755165Y211359D03*
Y213859D03*
X1750107Y211695D03*
X1747607Y208695D03*
X1750407D03*
X1743535Y208213D03*
Y213213D03*
Y210713D03*
Y215713D03*
X1753784Y265701D03*
X1758871Y265896D03*
X1750602Y267526D03*
X1745302D03*
X1748102D03*
X1745302Y270026D03*
X1748102D03*
X1750602D03*
X1755419Y281716D03*
X1748497Y371060D03*
X1752497Y371076D03*
X1750135Y379088D03*
X1755433Y379028D03*
X1744180Y383966D03*
X1750187Y409539D03*
X1753187D03*
X1750187Y406739D03*
X1753187Y407039D03*
X1752851Y401981D03*
X1755351D03*
X1757124Y398278D03*
X1754624D03*
X1749470Y424067D03*
X1751970D03*
X1756970D03*
X1754470D03*
X1749705Y413611D03*
X1752205D03*
X1757205D03*
X1754705D03*
X1756844Y438293D03*
X1747179Y439318D03*
X1756844Y441093D03*
X1747179Y442118D03*
X1756844Y443893D03*
X1747306Y470001D03*
X1744806D03*
X1756894Y472020D03*
X1756553Y466409D03*
X1756954Y477318D03*
X1745231Y489036D03*
X1743092Y485580D03*
X1745592D03*
X1748092D03*
X1758401Y484882D03*
X1756391Y487382D03*
X1747467Y492836D03*
Y495636D03*
X1756089Y542952D03*
X1750879Y541940D03*
X1754906Y824333D03*
Y820737D03*
X1746897Y879199D03*
X1746884Y884649D03*
X1747900Y900160D03*
X1744900D03*
X1750915Y902055D03*
X1749267Y918413D03*
X1751200Y931100D03*
X1746600Y935100D03*
X1751854Y991297D03*
X1749314Y987904D03*
X1745824Y987058D03*
X1748677Y993986D03*
X1753860Y997271D03*
X1759569Y1021944D03*
X1744529Y1116251D03*
X1758390Y1577905D03*
X1759947Y1599029D03*
X1750685Y1621654D03*
X1767552Y76587D03*
Y72615D03*
X1762010Y97475D03*
X1768991Y100625D03*
X1761941Y106186D03*
X1773364Y112083D03*
X1771714Y171523D03*
X1776999Y183834D03*
X1762102Y168697D03*
X1763190Y191941D03*
X1771244Y192490D03*
X1776519Y190185D03*
X1767202Y192300D03*
X1765199Y206767D03*
X1770199D03*
X1767699D03*
X1758868Y213132D03*
X1765329Y221708D03*
X1770329D03*
X1767829D03*
X1764744Y224421D03*
X1766444Y231021D03*
Y228221D03*
X1774679Y221642D03*
X1758868Y215632D03*
X1771995Y236189D03*
X1769495D03*
X1766995D03*
X1771936Y248765D03*
X1769436D03*
X1766936D03*
X1759112Y256303D03*
X1763887Y266114D03*
X1767133Y270695D03*
X1769633D03*
X1772433Y268195D03*
Y270695D03*
X1769633Y268195D03*
X1767133D03*
X1761360Y281982D03*
X1762997Y377581D03*
X1765497Y379591D03*
X1772513Y387702D03*
X1769713D03*
X1765913Y389402D03*
X1763200Y388817D03*
Y383817D03*
Y386317D03*
X1766837Y438293D03*
Y441093D03*
Y443893D03*
X1768586Y467560D03*
X1764903Y470382D03*
X1764906Y474382D03*
X1776561Y467560D03*
X1777061Y475560D03*
X1768575D03*
X1770135Y490711D03*
X1758957Y543036D03*
X1773789Y927663D03*
X1765664Y923724D03*
X1769064D03*
X1773789Y930663D03*
X1774476Y995049D03*
X1773810Y990821D03*
X1762486Y990260D03*
X1760201Y992475D03*
X1758881Y995633D03*
X1769004Y1019395D03*
X1768844Y1023694D03*
Y1027248D03*
X1771773Y1028829D03*
X1772188Y1428369D03*
X1766313Y1580198D03*
X1761072Y1590719D03*
X1765040Y1599511D03*
X1760422Y1640303D03*
X1768422D03*
X1772422D03*
X1762041Y1631511D03*
X1768422Y1632245D03*
X1773820Y1631238D03*
X1779232Y55513D03*
X1775457Y68581D03*
X1785246Y60660D03*
X1781832Y60513D03*
X1775470Y80581D03*
X1781960Y85731D03*
X1790712Y81713D03*
X1790664Y71908D03*
X1779600Y88801D03*
X1790373Y94663D03*
X1786466Y85923D03*
Y94279D03*
X1782517Y94351D03*
X1777653Y103621D03*
X1785886Y168665D03*
Y176665D03*
X1777172Y172665D03*
X1777109Y178560D03*
X1777985Y186629D03*
X1785779Y192665D03*
X1785886Y196665D03*
X1777289Y200864D03*
X1785999Y186778D03*
X1785918Y204864D03*
X1777378Y212455D03*
X1777312Y207037D03*
X1785918Y208864D03*
X1781559Y219379D03*
X1782187Y228631D03*
X1778593Y265897D03*
X1776093D03*
X1787674Y303130D03*
X1777681Y387151D03*
Y382151D03*
Y384651D03*
X1786184Y435321D03*
Y438121D03*
X1783384Y435321D03*
Y438121D03*
X1786184Y440921D03*
X1783384D03*
X1786184Y443721D03*
X1783384D03*
X1786170Y448931D03*
X1792527Y452799D03*
X1786693Y459170D03*
X1790061Y474513D03*
X1779404Y826570D03*
X1791041Y818795D03*
X1780016Y874400D03*
X1775904Y924546D03*
X1778047Y916120D03*
X1789537Y930498D03*
X1780158Y953295D03*
X1785758Y956095D03*
Y953295D03*
X1782958D03*
Y956095D03*
X1780158D03*
X1789363Y969160D03*
X1782563Y979660D03*
X1785663D03*
X1779363D03*
X1786863Y985060D03*
X1779143Y995203D03*
X1779033Y1023432D03*
X1786740Y1019237D03*
X1780802Y1019474D03*
X1774863Y1019237D03*
X1774844Y1023694D03*
X1783844D03*
X1786844Y1027248D03*
X1780844D03*
X1774844D03*
X1789844Y1023694D03*
X1775998Y1074707D03*
Y1072207D03*
X1781198Y1074707D03*
X1778598D03*
X1783798D03*
Y1072207D03*
X1778598D03*
X1781198D03*
X1790736Y1072090D03*
Y1074590D03*
X1780326Y1089851D03*
X1777726D03*
X1782926D03*
Y1092351D03*
X1777726D03*
X1780326D03*
X1775126Y1089851D03*
Y1092351D03*
X1790639Y1082585D03*
X1790572Y1085152D03*
X1780662Y1108413D03*
X1783262D03*
X1778062D03*
X1775462D03*
X1785321Y1121122D03*
X1787921D03*
X1790521D03*
X1780566Y1111038D03*
X1783166D03*
X1777966D03*
X1775366D03*
X1790521Y1130822D03*
X1781874Y1139822D03*
X1787921Y1130822D03*
X1785321D03*
X1784374Y1139822D03*
X1781802Y1147822D03*
X1784302D03*
X1783278Y1208140D03*
X1778227Y1438099D03*
X1786091Y1443715D03*
X1787745Y1437765D03*
X1783178Y1437550D03*
X1778104Y1470289D03*
X1791088Y77296D03*
X1804758Y294429D03*
X1793524Y303343D03*
X1805196Y300952D03*
X1799897Y408104D03*
X1802697D03*
X1805497D03*
X1793475Y424939D03*
X1799614Y420375D03*
X1802414D03*
X1805214D03*
X1793475Y427439D03*
X1809095Y435101D03*
X1803700Y440101D03*
X1803530Y431112D03*
X1809358Y442114D03*
X1803335Y452718D03*
X1809346Y452601D03*
X1797907Y452987D03*
X1809338Y447121D03*
X1804933Y461607D03*
X1796933D03*
X1796136Y471334D03*
X1800933Y461607D03*
X1802000Y892447D03*
X1797365Y930761D03*
X1793474Y930374D03*
X1805463Y969260D03*
X1801963Y969160D03*
X1802363Y989660D03*
X1803351Y1027471D03*
X1805188Y1019078D03*
X1799646Y1018999D03*
X1793470Y1018762D03*
X1801844Y1023694D03*
X1795844D03*
X1798844Y1027248D03*
X1792844D03*
X1795936Y1072090D03*
X1793336D03*
X1798536D03*
Y1074590D03*
X1793336D03*
X1795936D03*
X1801961Y1081717D03*
X1795819Y1088553D03*
X1800813Y1103246D03*
X1806206Y1114589D03*
X1803506D03*
X1800906D03*
X1798306D03*
X1798702Y1124328D03*
X1801302D03*
X1803902D03*
X1806602D03*
X1793221Y1121122D03*
Y1130822D03*
X1804532Y1133356D03*
X1807232D03*
X1807035Y1136912D03*
Y1144912D03*
X1806835Y1214668D03*
X1800489Y1220598D03*
X1807243Y1219955D03*
X1802670Y1210905D03*
X1805126Y1225745D03*
X1799845Y1261044D03*
X1794845D03*
X1797345D03*
X1799845Y1263544D03*
X1797345D03*
X1794845D03*
X1803885Y1435046D03*
X1806428Y1444543D03*
X1795374D03*
X1802813Y1464015D03*
X1803762Y1467236D03*
X1819900Y906900D03*
X1807663Y966660D03*
Y963860D03*
X1808014Y984832D03*
X1812538Y1026859D03*
X1811468Y1021084D03*
X1807844Y1023694D03*
Y1027248D03*
X1810349Y1031264D03*
X1816756Y1089145D03*
Y1094145D03*
X1816235Y1083970D03*
X1810346Y1082250D03*
X1816756Y1097145D03*
Y1101145D03*
X1810310Y1104819D03*
X1809535Y1136912D03*
Y1144912D03*
X1812130Y1205349D03*
X1822594Y1211054D03*
Y1215324D03*
X1814741Y1217093D03*
X1811482Y1226423D03*
X1810018Y1295944D03*
X1812818D03*
X1815618Y1298744D03*
Y1295944D03*
X1812818Y1298744D03*
X1810018D03*
X1812202Y1432624D03*
X1809342Y1476733D03*
X1824706Y1085145D03*
X1824949Y1077145D03*
X1824706Y1100185D03*
Y1106145D03*
X1828272Y1095968D03*
X1824706Y1093150D03*
X1830915Y1109146D03*
X1834665Y1213239D03*
G54D23*
X51750Y617861D03*
X48207D03*
X44664D03*
X51750Y620661D03*
X48207D03*
X44664D03*
X55294Y617861D03*
Y620661D03*
X146948Y1088287D03*
X143208D03*
X146948Y1099507D03*
X143208D03*
X146948Y1106988D03*
X143208D03*
X146948Y1114468D03*
Y1121948D03*
X143208Y1114468D03*
Y1121948D03*
X146948Y1129429D03*
X143208D03*
X146948Y1136909D03*
X143208D03*
X146948Y1148129D03*
X143208D03*
X146947Y1170570D03*
X143207D03*
X146947Y1178051D03*
X143207D03*
X165649Y1073326D03*
X158169D03*
X150689D03*
X165649Y1092027D03*
X158169D03*
X150689D03*
X165649Y1077066D03*
X161909Y1084547D03*
X158169Y1077066D03*
X154429Y1084547D03*
X161909Y1080807D03*
X154429D03*
X165649Y1095767D03*
X161909Y1103247D03*
X158169Y1095767D03*
X154429Y1103247D03*
X150689Y1095767D03*
X161909Y1099507D03*
X154429D03*
X161909Y1118208D03*
Y1121948D03*
X165649Y1110728D03*
X161909D03*
X154429D03*
Y1118208D03*
X150689Y1110728D03*
Y1118208D03*
X154429Y1125688D03*
X150689D03*
Y1133169D03*
X165649D03*
X161909D03*
X154429D03*
X165649Y1148129D03*
Y1144389D03*
Y1155610D03*
X160039Y1176180D03*
X156299D03*
X169389Y1084547D03*
Y1080807D03*
Y1103247D03*
X173129Y1136909D03*
X169389D03*
X176870Y1151870D03*
Y1148129D03*
Y1144389D03*
X169389Y1151870D03*
Y1148129D03*
X176870Y1166830D03*
Y1159350D03*
X169389D03*
X176870Y1174310D03*
Y1178051D03*
Y1181791D03*
X188090Y1114468D03*
X184350D03*
X191830D03*
X195570D03*
X191830Y1140649D03*
Y1136909D03*
X195570Y1140649D03*
X184350Y1136909D03*
X191830Y1133169D03*
Y1129429D03*
Y1144389D03*
Y1151869D03*
X195570Y1148129D03*
Y1155610D03*
X184350Y1144389D03*
X188090Y1155610D03*
X184350Y1151870D03*
X188090Y1148129D03*
X191830Y1159350D03*
Y1170570D03*
X195570Y1166830D03*
X184350Y1159350D03*
Y1170570D03*
X188090Y1166830D03*
X191830Y1185531D03*
Y1178051D03*
X195570Y1181791D03*
Y1174310D03*
X184350Y1185531D03*
X188090Y1181791D03*
Y1174310D03*
X184350Y1178051D03*
X191830Y1193011D03*
X195570Y1215452D03*
X197440Y1217322D03*
X186220D03*
X189960D03*
Y1213582D03*
X203051Y1114468D03*
X199311D03*
X206791D03*
X210531D03*
X206791Y1136909D03*
X203051D03*
X199311D03*
X214271D03*
X210531D03*
X199311Y1129429D03*
X206791D03*
X214271D03*
X210531D03*
X203051D03*
X210531Y1155610D03*
X203051D03*
X206791Y1144389D03*
X203051D03*
X199311D03*
X214271D03*
X210531D03*
X214271Y1151870D03*
X210531D03*
X206791D03*
X203051D03*
X199311D03*
X214271Y1170570D03*
X210531Y1166830D03*
X214271Y1159350D03*
X206791Y1170570D03*
X203051Y1166830D03*
X199311Y1170570D03*
X206791Y1159350D03*
X199311D03*
X203051Y1174310D03*
X210531D03*
X203051Y1185531D03*
X199311D03*
X206791D03*
X214271D03*
X210531D03*
X206791Y1178051D03*
X203051D03*
X199311D03*
X214271D03*
X210531D03*
X214271Y1193011D03*
X210531D03*
X199311D03*
X203051D03*
X206791D03*
X214271Y1200491D03*
X210531D03*
X199311D03*
X206791D03*
X203051D03*
X201181Y1213582D03*
X214271Y1211712D03*
X208661Y1213582D03*
X203051Y1215452D03*
X214271D03*
X201181Y1217322D03*
X208661D03*
X210531Y1215452D03*
X204921Y1213582D03*
X225492Y1114468D03*
X221752D03*
X218011D03*
X225492Y1136909D03*
X221751D03*
X218011D03*
X229232D03*
Y1129429D03*
X218011D03*
X221751D03*
X225492D03*
X218011Y1155610D03*
X225492D03*
Y1144389D03*
X221751D03*
X218011D03*
X229232D03*
Y1151870D03*
X221752D03*
X218011D03*
X225492D03*
Y1166830D03*
X221751Y1170570D03*
X218011Y1166830D03*
X221751Y1159350D03*
X229232Y1170570D03*
Y1159350D03*
X225492Y1174310D03*
X218011D03*
X225492Y1185531D03*
X218011D03*
X221751D03*
X229232D03*
X225492Y1178051D03*
X221751D03*
X218011D03*
X229232D03*
X218011Y1193011D03*
X221751D03*
X225492D03*
X229232D03*
X218011Y1200491D03*
X221751D03*
X225492D03*
X229232D03*
X218011Y1215452D03*
X229232Y1211712D03*
Y1215452D03*
X225492Y1211712D03*
X221752D03*
Y1215452D03*
X240452Y1114468D03*
X244192D03*
X236712Y1118208D03*
X244192D03*
X236712Y1114468D03*
X240452Y1118208D03*
Y1136909D03*
X236712D03*
X244192D03*
Y1129429D03*
X240452D03*
X236712D03*
Y1155610D03*
X244192D03*
X240452Y1151869D03*
X236712D03*
X244192D03*
X240452Y1144389D03*
X236712D03*
X244192D03*
X236712Y1166830D03*
X240452Y1170570D03*
Y1159350D03*
X244192Y1166830D03*
X236712Y1174310D03*
X244192D03*
X240452Y1185531D03*
X236712D03*
X244192D03*
X240452Y1178051D03*
X236712D03*
X244192D03*
X240452Y1193011D03*
X236712D03*
X244192D03*
X236712Y1200491D03*
X244192D03*
X240452D03*
X244192Y1215452D03*
X240452D03*
X242322Y1217322D03*
X236712Y1211712D03*
Y1215452D03*
X238582Y1217322D03*
X262893Y1118208D03*
X259153Y1114468D03*
X262893D03*
X255413Y1118208D03*
Y1114468D03*
X247933D03*
X259153Y1118208D03*
X251673Y1114468D03*
X247933Y1118208D03*
X251673D03*
X255413Y1136909D03*
X251673D03*
X247933D03*
X259153D03*
X262893D03*
X247933Y1129429D03*
X259153D03*
X262893D03*
X255413D03*
X251673D03*
Y1155610D03*
X259153D03*
X251673Y1144389D03*
X247933D03*
X255413D03*
X259153Y1151869D03*
X262893D03*
X247933D03*
X255413D03*
X251673D03*
X262893Y1144389D03*
X259153D03*
X251673Y1166830D03*
X255413Y1170570D03*
X247933D03*
X255413Y1159350D03*
X247933D03*
X259153Y1166830D03*
X262893Y1170570D03*
Y1159350D03*
X251673Y1174310D03*
X259153D03*
X247933Y1185531D03*
X255413D03*
X251673D03*
X259153D03*
X262893D03*
X251673Y1178051D03*
X247933D03*
X255413D03*
X259153D03*
X262893D03*
X251673Y1193011D03*
X255413D03*
X247933D03*
X262893D03*
X259153D03*
Y1200491D03*
X262893D03*
X251673D03*
X247933D03*
X255413D03*
Y1215452D03*
X262893D03*
X247932Y1215451D03*
X259153Y1215452D03*
X251673D03*
X247932Y1211711D03*
X251673D03*
X270373Y1114468D03*
X274114D03*
X277854D03*
X266633Y1136909D03*
Y1129429D03*
X274114D03*
Y1140649D03*
Y1136909D03*
X266633Y1155610D03*
X277854D03*
X266633Y1151869D03*
Y1144389D03*
X274114D03*
X277854Y1159350D03*
Y1166830D03*
Y1170570D03*
X266633D03*
X270373D03*
X266633Y1159350D03*
X270373D03*
Y1166830D03*
X266633D03*
Y1174310D03*
X277854D03*
X266633Y1185531D03*
Y1178051D03*
X270373Y1181791D03*
X274114Y1185531D03*
Y1189271D03*
Y1178051D03*
X266633Y1193011D03*
Y1200491D03*
X274114D03*
Y1193011D03*
X277854Y1204232D03*
Y1196751D03*
Y1200491D03*
X274114Y1215452D03*
X277854D03*
X266633D03*
X274114Y1211712D03*
X277854Y1207972D03*
X285334Y1118208D03*
X281594D03*
X285334Y1114468D03*
X281594D03*
X289074Y1140649D03*
X285334D03*
Y1136909D03*
X292815Y1140649D03*
X285334Y1155610D03*
X281594Y1144389D03*
X285334Y1148129D03*
Y1144389D03*
X289074Y1148129D03*
X292815D03*
Y1155610D03*
X285334Y1170570D03*
Y1166830D03*
Y1159350D03*
X292815Y1170570D03*
X285334Y1174310D03*
X289074Y1189271D03*
X285334D03*
X281594Y1181791D03*
X285334Y1178051D03*
X289074Y1181791D03*
X285334Y1196751D03*
Y1204232D03*
X281594Y1200491D03*
X285334D03*
Y1207972D03*
Y1215452D03*
Y1211712D03*
X281594Y1215452D03*
Y1207972D03*
X311515Y1140649D03*
X304035Y1144389D03*
Y1151869D03*
X307775Y1144389D03*
Y1151869D03*
X296555Y1155610D03*
X311515Y1148129D03*
Y1155610D03*
X304035Y1166830D03*
Y1159350D03*
X307775Y1166830D03*
X296555Y1170570D03*
X311515D03*
X304035Y1174310D03*
Y1181791D03*
Y1189271D03*
X307775Y1174310D03*
Y1181791D03*
Y1189271D03*
X311515Y1178051D03*
Y1185531D03*
Y1193011D03*
X322736Y1136909D03*
X326476D03*
X315255Y1140649D03*
X322736Y1144389D03*
Y1151870D03*
X326476Y1144389D03*
X315255Y1148129D03*
X326476Y1151870D03*
X315255Y1155610D03*
X322736Y1159350D03*
X326476D03*
X315255Y1170570D03*
X322736Y1174310D03*
Y1181791D03*
Y1189271D03*
X326476Y1174310D03*
X315255Y1178051D03*
X326476Y1181791D03*
X315255Y1185531D03*
X326476Y1189271D03*
X315255Y1193011D03*
X425023Y441086D03*
Y433999D03*
Y437543D03*
X422223Y441086D03*
Y433999D03*
Y437543D03*
X425023Y444629D03*
X422223D03*
X501750Y620661D03*
X505293D03*
X501750Y617861D03*
X505293D03*
X512380D03*
X508836Y620661D03*
Y617861D03*
X512380Y620661D03*
X600295Y1088287D03*
X604035D03*
X600295Y1099507D03*
X604035D03*
X600295Y1106988D03*
X604035D03*
Y1121948D03*
X600295D03*
Y1114468D03*
X604035D03*
X600295Y1136909D03*
X604035D03*
X600295Y1129429D03*
X604035D03*
Y1148129D03*
X600295D03*
X604034Y1170570D03*
X600294D03*
X604034Y1178051D03*
X600294D03*
X615256Y1073326D03*
X607776D03*
X618996Y1084547D03*
Y1080807D03*
X615256Y1077066D03*
X611516Y1080807D03*
Y1084547D03*
X607776Y1092027D03*
X615256D03*
X607776Y1095767D03*
X615256D03*
X618996Y1103247D03*
X611516D03*
X618996Y1099507D03*
X611516D03*
X618996Y1118208D03*
Y1121948D03*
X611516Y1118208D03*
X607776D03*
X611516Y1110728D03*
X618996D03*
X607776D03*
X611516Y1125688D03*
X607776D03*
Y1133169D03*
X615256Y1178051D03*
X611516D03*
X622736Y1073326D03*
Y1077066D03*
X626476Y1084547D03*
X622736Y1092027D03*
X626476Y1080807D03*
X622736Y1095767D03*
X626476Y1103247D03*
X622736Y1118208D03*
X626476Y1114468D03*
X622736Y1110728D03*
X630216Y1114468D03*
X633957Y1151870D03*
Y1148129D03*
Y1144389D03*
X626476Y1148129D03*
X622736Y1144389D03*
Y1148129D03*
X626476Y1151870D03*
X622736Y1155610D03*
X633957Y1166830D03*
Y1159350D03*
X626476D03*
X633957Y1174310D03*
Y1178051D03*
Y1181791D03*
X645177Y1114468D03*
X641437D03*
X648917D03*
X652657D03*
X648917Y1140649D03*
Y1136909D03*
X652657Y1140649D03*
X641437Y1136909D03*
X648917Y1129429D03*
Y1133169D03*
X652657Y1148129D03*
Y1155610D03*
X648917Y1144389D03*
Y1151869D03*
X641437Y1144389D03*
Y1151870D03*
X645177Y1155610D03*
Y1148129D03*
X648917Y1159350D03*
Y1170570D03*
X652657Y1166830D03*
X641437Y1170570D03*
X645177Y1166830D03*
X641437Y1159350D03*
X648917Y1185531D03*
Y1178051D03*
X652657Y1181791D03*
Y1174310D03*
X641437Y1185531D03*
Y1178051D03*
X645177Y1181791D03*
Y1174310D03*
X648917Y1193011D03*
X652657Y1215452D03*
Y1219192D03*
X641437Y1215452D03*
X648917D03*
X645177D03*
X660138Y1114468D03*
X656398D03*
X663878D03*
X667618D03*
Y1129429D03*
X660138D03*
X656398D03*
X663878D03*
Y1136909D03*
X660138D03*
X656398D03*
X667618D03*
X660138Y1155610D03*
X667618D03*
Y1144389D03*
X663878D03*
X660138D03*
X656398D03*
X667618Y1151870D03*
X663878D03*
X660138D03*
X656398D03*
X663878Y1170570D03*
X660138Y1166830D03*
X656398Y1170570D03*
X663878Y1159350D03*
X656398D03*
X667618Y1166830D03*
Y1174310D03*
X660138D03*
X667618Y1185531D03*
X660138D03*
X656398D03*
X663878D03*
X667618Y1178051D03*
X663878D03*
X660138D03*
X656398D03*
X667618Y1200491D03*
X656398D03*
X663878D03*
X660138D03*
X663878Y1193011D03*
X660138D03*
X656398D03*
X667618D03*
X663878Y1211712D03*
X656398D03*
X660138Y1215452D03*
X656398D03*
X663878D03*
X667618D03*
X660138Y1211712D03*
X682579Y1114468D03*
X678839D03*
X675098D03*
Y1129429D03*
X671358D03*
X678838D03*
X682579D03*
Y1136909D03*
X678838D03*
X675098D03*
X671358D03*
X682579Y1155610D03*
X675098D03*
X678839Y1151870D03*
X675098D03*
X671358D03*
X682579D03*
Y1144389D03*
X671358D03*
X678838D03*
X675098D03*
X682579Y1166830D03*
X678838Y1170570D03*
X671358D03*
X675098Y1166830D03*
X671358Y1159350D03*
X678838D03*
X682579Y1174310D03*
X675098D03*
X682579Y1185531D03*
X675098D03*
X671358D03*
X678838D03*
X682579Y1178051D03*
X678838D03*
X675098D03*
X671358D03*
X675098Y1200491D03*
X671358D03*
X678838D03*
X682579D03*
Y1193011D03*
X678838D03*
X675098D03*
X671358D03*
X682579Y1211712D03*
X678839D03*
Y1215452D03*
X671358Y1211712D03*
Y1215452D03*
X675098D03*
X693799Y1114468D03*
Y1118208D03*
X701279Y1114468D03*
X697539Y1118208D03*
Y1114468D03*
X701279Y1118208D03*
Y1129429D03*
X697539D03*
X693799D03*
X686319D03*
X697539Y1136909D03*
X693799D03*
X701279D03*
X686319D03*
X701279Y1155610D03*
X693799D03*
X701279Y1151869D03*
X697539D03*
X693799D03*
X701279Y1144389D03*
X697539D03*
X693799D03*
X686319D03*
Y1151870D03*
X693799Y1166830D03*
X697539Y1170570D03*
Y1159350D03*
X701279Y1166830D03*
X686319Y1170570D03*
Y1159350D03*
X701279Y1174310D03*
X693799D03*
X701279Y1185531D03*
X697539D03*
X693799D03*
X701279Y1178051D03*
X697539D03*
X693799D03*
X686319Y1185531D03*
Y1178051D03*
X701279Y1200491D03*
X697539D03*
X693799D03*
X686319D03*
X701279Y1193011D03*
X697539D03*
X693799D03*
X686319D03*
Y1211712D03*
Y1215452D03*
X699409Y1217322D03*
X697539Y1215452D03*
X693799D03*
Y1211712D03*
X701279Y1215452D03*
X695669Y1217322D03*
X708760Y1114468D03*
X716240Y1118208D03*
X705020Y1114468D03*
X712500D03*
X716240D03*
X705020Y1118208D03*
X712500D03*
X708760D03*
X705020Y1129429D03*
X708760D03*
X712500D03*
X716240D03*
Y1136909D03*
X705020D03*
X708760D03*
X712500D03*
X708760Y1155610D03*
X716240D03*
Y1151869D03*
X708760D03*
X712500D03*
X705020D03*
X712500Y1144389D03*
X705020D03*
X708760D03*
X716240D03*
Y1166830D03*
X705020Y1159350D03*
X712500D03*
X705020Y1170570D03*
X712500D03*
X708760Y1166830D03*
X716240Y1174310D03*
X708760D03*
X716240Y1185531D03*
X708760D03*
X712500D03*
X705020D03*
X716240Y1178051D03*
X712500D03*
X705020D03*
X708760D03*
X712500Y1200491D03*
X705020D03*
X708760D03*
X716240D03*
X708760Y1193011D03*
X712500D03*
X705020D03*
X716240D03*
Y1215452D03*
X708760D03*
X712500D03*
X705019Y1215451D03*
Y1211711D03*
X708760D03*
X731201Y1114468D03*
X734941D03*
X727460D03*
X719980Y1118208D03*
Y1114468D03*
Y1129429D03*
X723720D03*
X731201D03*
X719980Y1136909D03*
X723720D03*
X731201D03*
Y1140649D03*
X723720Y1155610D03*
X719980Y1151869D03*
X723720D03*
Y1144389D03*
X719980D03*
X734941Y1155610D03*
X731201Y1144389D03*
X719980Y1159350D03*
X727460D03*
X723720D03*
Y1166830D03*
X727460D03*
X719980Y1170570D03*
X727460D03*
X723720D03*
X734941Y1159350D03*
Y1166830D03*
Y1170570D03*
X723720Y1174310D03*
X727460Y1181791D03*
X719980Y1185531D03*
Y1178051D03*
X723720D03*
Y1185531D03*
X734941Y1174310D03*
X731201Y1189271D03*
Y1185531D03*
Y1178051D03*
X719980Y1200491D03*
X723720D03*
X731201D03*
X719980Y1193011D03*
X723720D03*
X731201D03*
X734941Y1196751D03*
Y1204232D03*
Y1200491D03*
X731201Y1215452D03*
X734941D03*
X723720D03*
X719980D03*
X731201Y1211712D03*
X734941Y1207972D03*
X727461Y1215452D03*
X738681Y1118208D03*
X742421D03*
X738681Y1114468D03*
X742421D03*
Y1140649D03*
Y1136909D03*
X746161Y1140649D03*
X749902D03*
X742421Y1155610D03*
X746161Y1148129D03*
X738681Y1144389D03*
X742421Y1148129D03*
Y1144389D03*
X749902Y1155610D03*
Y1148129D03*
X742421Y1159350D03*
Y1166830D03*
Y1170570D03*
X749902D03*
X742421Y1189271D03*
X746161D03*
X742421Y1174310D03*
X738681Y1181791D03*
X746161D03*
X742421Y1178051D03*
Y1196751D03*
X738681Y1200491D03*
X742421Y1204232D03*
Y1200491D03*
Y1211712D03*
Y1215452D03*
Y1207972D03*
X738681Y1215452D03*
Y1207972D03*
Y1211712D03*
X761122Y1144389D03*
Y1151869D03*
X753642Y1155610D03*
X764862Y1151869D03*
Y1144389D03*
Y1166830D03*
X761122D03*
Y1159350D03*
X753642Y1170570D03*
X764862Y1174310D03*
X761122Y1181791D03*
X764862D03*
X761122Y1174310D03*
X768602Y1140649D03*
X772342D03*
Y1148129D03*
Y1155610D03*
X783563Y1151870D03*
X779823D03*
Y1144389D03*
X783563D03*
X768602Y1155610D03*
Y1148129D03*
X779823Y1159350D03*
X772342Y1170570D03*
X768602D03*
X783563Y1159350D03*
Y1189271D03*
X768602Y1185531D03*
X772342Y1178051D03*
X779823Y1189271D03*
X772342Y1185531D03*
X783563Y1174310D03*
X779823D03*
X783563Y1181791D03*
X768602Y1178051D03*
X779823Y1181791D03*
X768602Y1193011D03*
X772342D03*
X920349Y450340D03*
X917549D03*
X920349Y453884D03*
Y457427D03*
X917549Y453884D03*
Y457427D03*
X920349Y460970D03*
X917549D03*
X962380Y617861D03*
X958837D03*
X962380Y620661D03*
X958837D03*
X969467D03*
X965923Y617861D03*
Y620661D03*
X969467Y617861D03*
X1057381Y1088287D03*
Y1106988D03*
Y1099507D03*
Y1114468D03*
Y1121948D03*
Y1129429D03*
Y1136909D03*
Y1148129D03*
X1057380Y1170570D03*
Y1178051D03*
X1072342Y1073326D03*
X1064862D03*
Y1092027D03*
X1072342Y1077066D03*
X1068602Y1084547D03*
Y1080807D03*
X1061121Y1088287D03*
X1072342Y1092027D03*
X1068602Y1099507D03*
X1072342Y1095767D03*
X1061121Y1106988D03*
X1068602Y1103247D03*
X1064862Y1095767D03*
X1061121Y1099507D03*
Y1114468D03*
X1068602Y1110728D03*
Y1118208D03*
X1064862Y1110728D03*
Y1118208D03*
X1061121Y1121948D03*
X1064862Y1125688D03*
X1068602D03*
X1061121Y1129429D03*
X1064862Y1133169D03*
X1061121Y1136909D03*
Y1148129D03*
X1061120Y1170570D03*
X1072342Y1178051D03*
X1068602D03*
X1061120D03*
X1079822Y1073326D03*
Y1092027D03*
X1083562Y1084547D03*
X1079822Y1077066D03*
X1076082Y1084547D03*
Y1080807D03*
X1083562D03*
X1076082Y1103247D03*
X1079822Y1095767D03*
X1076082Y1099507D03*
X1083562Y1103247D03*
X1079822Y1118208D03*
X1076082Y1121948D03*
Y1118208D03*
X1079822Y1110728D03*
X1083562Y1114468D03*
X1087302D03*
X1076082Y1110728D03*
X1091043Y1151870D03*
Y1148129D03*
Y1144389D03*
X1083562Y1148129D03*
X1079822Y1144389D03*
Y1148129D03*
X1083562Y1151870D03*
X1079822Y1155610D03*
X1091043Y1166830D03*
Y1159350D03*
X1083562D03*
X1091043Y1181791D03*
Y1178051D03*
Y1174310D03*
X1102263Y1114468D03*
X1098523D03*
X1106003D03*
Y1140649D03*
Y1136909D03*
X1098523D03*
X1106003Y1129429D03*
Y1133169D03*
Y1151869D03*
Y1144389D03*
X1098523D03*
Y1151870D03*
X1102263Y1148129D03*
Y1155610D03*
X1106003Y1170570D03*
Y1159350D03*
X1102263Y1166830D03*
X1098523Y1159350D03*
Y1170570D03*
X1106003Y1178051D03*
Y1185531D03*
X1098523D03*
X1102263Y1174310D03*
X1098523Y1178051D03*
X1102263Y1181791D03*
X1106003Y1193011D03*
Y1215452D03*
X1098523D03*
X1102263D03*
X1117224Y1114468D03*
X1113484D03*
X1120964D03*
X1124704D03*
X1109743D03*
X1120964Y1129429D03*
X1113484D03*
X1117224D03*
X1124704D03*
Y1136909D03*
X1113484D03*
X1117224D03*
X1120964D03*
X1109743Y1140649D03*
X1124704Y1144389D03*
X1113484D03*
X1117224D03*
X1120964D03*
X1113484Y1151870D03*
X1117224D03*
X1120964D03*
X1124704D03*
Y1155610D03*
X1109743D03*
Y1148129D03*
X1117224Y1155610D03*
X1113484Y1159350D03*
X1120964D03*
X1109743Y1166830D03*
X1113484Y1170570D03*
X1117224Y1166830D03*
X1120964Y1170570D03*
X1124704Y1166830D03*
X1113484Y1178051D03*
X1117224D03*
X1120964D03*
X1124704D03*
X1120964Y1185531D03*
X1113484D03*
X1117224D03*
X1124704D03*
X1109743Y1174310D03*
Y1181791D03*
X1117224Y1174310D03*
X1124704D03*
X1117224Y1200491D03*
X1120964D03*
X1113484D03*
X1124704D03*
X1120964Y1193011D03*
X1117224D03*
X1113484D03*
X1124704D03*
Y1215452D03*
X1120964D03*
Y1211712D03*
X1117224Y1215452D03*
X1109743D03*
X1113484Y1211712D03*
X1111613Y1217322D03*
X1115354D03*
X1117224Y1211712D03*
X1139665Y1114468D03*
X1135925D03*
X1132184D03*
Y1129429D03*
X1128444D03*
X1135924D03*
X1139665D03*
Y1136909D03*
X1135924D03*
X1132184D03*
X1128444D03*
Y1144389D03*
X1135924D03*
X1132184D03*
X1139665D03*
X1135925Y1151870D03*
X1132184D03*
X1128444D03*
X1139665D03*
Y1155610D03*
X1132184D03*
X1139665Y1166830D03*
X1135924Y1170570D03*
X1128444D03*
X1132184Y1166830D03*
X1128444Y1159350D03*
X1135924D03*
X1139665Y1178051D03*
X1135924D03*
X1132184D03*
X1128444D03*
X1139665Y1185531D03*
X1132184D03*
X1128444D03*
X1135924D03*
X1139665Y1174310D03*
X1132184D03*
Y1200491D03*
X1128444D03*
X1135924D03*
X1139665D03*
X1128444Y1193011D03*
X1132184D03*
X1135924D03*
X1139665D03*
Y1211712D03*
X1135925D03*
Y1215452D03*
X1128444D03*
X1132184D03*
X1128444Y1211712D03*
X1154625Y1118208D03*
X1150885D03*
X1154625Y1114468D03*
X1150885D03*
X1154625Y1129429D03*
X1150885D03*
X1143405D03*
Y1136909D03*
X1154625D03*
X1150885D03*
X1143405Y1144389D03*
X1150885Y1151869D03*
X1154625D03*
Y1144389D03*
X1150885D03*
X1143405Y1151870D03*
X1150885Y1155610D03*
X1143405Y1170570D03*
X1154625Y1159350D03*
X1143405D03*
X1150885Y1166830D03*
X1154625Y1170570D03*
X1143405Y1178051D03*
Y1185531D03*
X1154625D03*
X1150885D03*
X1154625Y1178051D03*
X1150885D03*
Y1174310D03*
X1143405Y1200491D03*
X1154625D03*
X1150885D03*
Y1193011D03*
X1154625D03*
X1143405D03*
Y1211712D03*
Y1215452D03*
X1150885Y1211712D03*
Y1215452D03*
X1154625D03*
X1156495Y1217322D03*
X1152755D03*
X1162106Y1114468D03*
X1169586D03*
X1162106Y1118208D03*
X1173326Y1114468D03*
X1158365Y1118208D03*
X1173326D03*
X1165846Y1114468D03*
X1158365D03*
X1169586Y1118208D03*
X1165846D03*
X1169586Y1129429D03*
X1165846D03*
X1162106D03*
X1158365D03*
X1173326D03*
Y1136909D03*
X1169586D03*
X1165846D03*
X1158365D03*
X1162106D03*
X1173326Y1151869D03*
X1158365D03*
X1162106D03*
X1169586D03*
X1165846D03*
X1173326Y1144389D03*
X1165846D03*
X1158365D03*
X1162106D03*
X1169586D03*
X1173326Y1155610D03*
X1165846D03*
X1158365D03*
X1173326Y1166830D03*
X1165846D03*
X1169586Y1170570D03*
X1158365Y1166830D03*
X1162106Y1170570D03*
X1169586Y1159350D03*
X1162106D03*
X1158365Y1185531D03*
X1162106D03*
X1169586D03*
X1165846D03*
X1173326D03*
X1165846Y1178051D03*
X1158365D03*
X1162106D03*
X1169586D03*
X1173326D03*
X1165846Y1174310D03*
X1158365D03*
X1173326D03*
Y1200491D03*
X1165846D03*
X1162106D03*
X1158365D03*
X1169586D03*
X1165846Y1193011D03*
X1169586D03*
X1158365D03*
X1162106D03*
X1173326D03*
Y1215452D03*
X1165846D03*
X1169586D03*
X1162105Y1215451D03*
X1158365Y1215452D03*
X1162105Y1211711D03*
X1165846D03*
X1188287Y1114468D03*
X1177066D03*
Y1118208D03*
X1184546Y1114468D03*
X1180806Y1129429D03*
X1177066D03*
X1188287D03*
X1180806Y1136909D03*
X1177066D03*
X1188287D03*
Y1140649D03*
X1180806Y1151869D03*
X1177066D03*
Y1144389D03*
X1180806D03*
Y1155610D03*
X1188287Y1144389D03*
X1180806Y1170570D03*
X1184546D03*
X1177066D03*
X1184546Y1166830D03*
X1180806D03*
X1177066Y1159350D03*
X1180806D03*
X1184546D03*
X1177066Y1185531D03*
Y1178051D03*
X1180806Y1185531D03*
Y1178051D03*
Y1174310D03*
X1184546Y1181791D03*
X1188287Y1185531D03*
Y1189271D03*
Y1178051D03*
X1180806Y1200491D03*
X1177066D03*
X1188287D03*
X1177066Y1193011D03*
X1180806D03*
X1188287D03*
Y1215452D03*
X1180806D03*
X1177066D03*
X1188287Y1211712D03*
X1199507Y1118208D03*
X1195767D03*
Y1114468D03*
X1192027D03*
X1199507D03*
Y1140649D03*
Y1136909D03*
X1203247Y1140649D03*
X1199507Y1155610D03*
X1192027D03*
X1203247Y1148129D03*
X1195767Y1144389D03*
X1199507Y1148129D03*
Y1144389D03*
Y1170570D03*
Y1166830D03*
Y1159350D03*
X1192027Y1166830D03*
Y1170570D03*
Y1159350D03*
X1203247Y1189271D03*
X1199507D03*
Y1174310D03*
X1195767Y1181791D03*
X1192027Y1174310D03*
X1199507Y1178051D03*
X1203247Y1181791D03*
X1199507Y1196751D03*
Y1204232D03*
X1195767Y1200491D03*
X1192027Y1196751D03*
Y1200491D03*
Y1204232D03*
X1199507Y1200491D03*
X1192027Y1215452D03*
X1199507Y1211712D03*
Y1215452D03*
Y1207972D03*
X1195767Y1215452D03*
X1192027Y1207972D03*
X1195767D03*
Y1211712D03*
X1206988Y1140649D03*
X1218208Y1144389D03*
Y1151869D03*
X1206988Y1155610D03*
Y1148129D03*
X1210728Y1155610D03*
X1221948Y1151869D03*
Y1144389D03*
X1218208Y1166830D03*
Y1159350D03*
X1221948Y1166830D03*
X1210728Y1170570D03*
X1206988D03*
X1218208Y1189271D03*
Y1174310D03*
X1221948Y1181791D03*
Y1174310D03*
X1218208Y1181791D03*
X1221948Y1189271D03*
X1236909Y1136909D03*
X1225688Y1140649D03*
X1229428D03*
X1236909Y1151870D03*
X1225688Y1148129D03*
X1229428D03*
X1225688Y1155610D03*
X1236909Y1144389D03*
X1229428Y1155610D03*
Y1170570D03*
X1225688D03*
X1236909Y1159350D03*
Y1181791D03*
X1225688Y1185531D03*
X1236909Y1189271D03*
X1229428Y1178051D03*
Y1185531D03*
X1236909Y1174310D03*
X1225688Y1178051D03*
Y1193011D03*
X1229428D03*
X1240649Y1136909D03*
Y1151870D03*
Y1144389D03*
Y1159350D03*
Y1174310D03*
Y1181791D03*
Y1189271D03*
X1339196Y441086D03*
Y433999D03*
Y437543D03*
X1336396Y441086D03*
Y433999D03*
Y437543D03*
X1339196Y444629D03*
X1336396D03*
X1415924Y620661D03*
Y617861D03*
X1423010Y620661D03*
X1419467Y617861D03*
X1423010D03*
X1426554Y620661D03*
Y617861D03*
X1419467Y620661D03*
X1514468Y1088287D03*
Y1099507D03*
Y1106988D03*
Y1121948D03*
Y1114468D03*
Y1129429D03*
Y1136909D03*
Y1148129D03*
Y1155610D03*
X1514467Y1170570D03*
Y1178051D03*
X1521949Y1073326D03*
X1529429D03*
Y1077066D03*
X1525689Y1084547D03*
X1529429Y1092027D03*
X1521949D03*
X1518208Y1088287D03*
X1525689Y1080807D03*
X1518208Y1099507D03*
X1525689D03*
X1529429Y1095767D03*
X1525689Y1103247D03*
X1518208Y1106988D03*
X1521949Y1095767D03*
Y1110728D03*
X1518208Y1114468D03*
X1525689Y1110728D03*
X1518208Y1121948D03*
X1521949Y1118208D03*
X1525689D03*
Y1125688D03*
X1518208Y1129429D03*
X1521949Y1125688D03*
X1518208Y1136909D03*
X1521949Y1133169D03*
X1518208Y1148129D03*
Y1155610D03*
X1518207Y1170570D03*
X1527559Y1176180D03*
X1518207Y1178051D03*
X1536909Y1073326D03*
X1533169Y1080807D03*
Y1084547D03*
X1540649Y1080807D03*
X1536909Y1077066D03*
X1540649Y1084547D03*
X1536909Y1092027D03*
Y1095767D03*
X1533169Y1099507D03*
X1540649Y1103247D03*
X1533169D03*
X1536909Y1118208D03*
X1533169D03*
Y1121948D03*
X1544389Y1114468D03*
X1536909Y1110728D03*
X1533169D03*
X1540649Y1114468D03*
X1536909Y1148129D03*
X1540649Y1151870D03*
Y1148129D03*
X1536909Y1144389D03*
Y1155610D03*
X1540649Y1159350D03*
Y1170570D03*
Y1174310D03*
Y1178050D03*
X1531299Y1176180D03*
X1559350Y1114468D03*
X1555610D03*
X1563090D03*
Y1140649D03*
Y1136909D03*
X1555610D03*
X1563090Y1129429D03*
Y1133169D03*
Y1144389D03*
Y1151869D03*
X1555610Y1144389D03*
X1548130Y1151870D03*
Y1148129D03*
Y1144389D03*
X1559350Y1155610D03*
X1555610Y1151870D03*
X1559350Y1148129D03*
X1563090Y1159350D03*
Y1170570D03*
X1548130Y1166830D03*
Y1159350D03*
X1555610Y1170570D03*
X1559350Y1166830D03*
X1555610Y1159350D03*
X1548130Y1174310D03*
Y1178051D03*
Y1181791D03*
X1563090Y1185531D03*
Y1178051D03*
X1555610Y1185531D03*
X1559350Y1174310D03*
Y1181791D03*
X1555610Y1178051D03*
X1563090Y1193011D03*
X1555610Y1215452D03*
X1563090D03*
X1559350D03*
X1574311Y1114468D03*
X1570571D03*
X1578051D03*
X1566830D03*
X1578051Y1136909D03*
X1574311D03*
X1570571D03*
X1574311Y1129429D03*
X1570571D03*
X1578051D03*
X1566830Y1140649D03*
X1578051Y1144389D03*
X1574311D03*
X1570571D03*
X1578051Y1151870D03*
X1574311D03*
X1570571D03*
X1574311Y1155610D03*
X1566830Y1148129D03*
Y1155610D03*
X1578051Y1170570D03*
X1574311Y1166830D03*
X1570571Y1170570D03*
X1566830Y1166830D03*
X1578051Y1159350D03*
X1570571D03*
X1574311Y1185531D03*
X1570571D03*
X1578051D03*
Y1178051D03*
X1574311D03*
X1570571D03*
X1574311Y1174310D03*
X1566830Y1181791D03*
Y1174310D03*
X1570571Y1193011D03*
X1574311D03*
X1578051D03*
X1570571Y1200491D03*
X1578051D03*
X1574311D03*
X1578051Y1215452D03*
X1566830D03*
X1570571Y1211712D03*
X1566830Y1219192D03*
X1574311Y1215452D03*
X1570571D03*
X1578051Y1211712D03*
X1574311D03*
X1593012Y1114468D03*
X1589271D03*
X1581791D03*
X1593011Y1136909D03*
X1589271D03*
X1585531D03*
X1581791D03*
X1589271Y1129429D03*
X1585531D03*
X1581791D03*
X1593011D03*
X1585531Y1144389D03*
X1581791D03*
X1593011D03*
X1589271D03*
X1593012Y1151870D03*
X1589271D03*
X1585531D03*
X1581791D03*
Y1155610D03*
X1589271D03*
X1593011Y1170570D03*
X1585531D03*
X1589271Y1166830D03*
X1581791D03*
X1585531Y1159350D03*
X1593011D03*
X1589271Y1185531D03*
X1585531D03*
X1581791D03*
X1593011D03*
X1581791Y1178051D03*
X1593011D03*
X1589271D03*
X1585531D03*
X1589271Y1174310D03*
X1581791D03*
X1585531Y1193011D03*
X1589271D03*
X1593011D03*
X1581791D03*
X1589271Y1200491D03*
X1585531D03*
X1581791D03*
X1593011D03*
X1593012Y1211712D03*
Y1215452D03*
X1581791D03*
X1589271D03*
X1585531D03*
Y1211712D03*
X1596752Y1114468D03*
X1607972D03*
X1611712Y1118208D03*
X1607972D03*
X1611712Y1114468D03*
X1600492Y1136909D03*
X1596752D03*
X1611712D03*
X1607972D03*
X1611712Y1129429D03*
X1607972D03*
X1600492D03*
X1596752D03*
X1600492Y1144389D03*
X1596752D03*
X1611712Y1151869D03*
X1607972D03*
X1611712Y1144389D03*
X1607972D03*
X1600492Y1151870D03*
X1596752D03*
Y1155610D03*
X1607972D03*
Y1166830D03*
X1611712Y1170570D03*
X1600492D03*
X1596752Y1166830D03*
X1611712Y1159350D03*
X1600492D03*
Y1185531D03*
X1596752D03*
X1600492Y1178051D03*
X1596752D03*
X1611712Y1185531D03*
X1607972D03*
X1611712Y1178051D03*
X1607972D03*
Y1174310D03*
X1596752D03*
X1607972Y1193011D03*
X1611712D03*
X1600492D03*
X1596752D03*
X1600492Y1200491D03*
X1596752D03*
X1611712D03*
X1607972D03*
X1600492Y1211712D03*
Y1215452D03*
X1596752Y1211712D03*
X1611712Y1215452D03*
X1607972D03*
Y1211712D03*
X1609842Y1217322D03*
X1615452Y1118208D03*
X1619193D03*
X1615452Y1114468D03*
X1619193D03*
X1622933D03*
X1626673D03*
Y1118208D03*
X1622933D03*
X1626673Y1136909D03*
X1622933D03*
X1615452D03*
X1619193D03*
X1626673Y1129429D03*
X1622933D03*
X1619193D03*
X1615452D03*
Y1151869D03*
X1619193D03*
X1626673D03*
X1622933D03*
Y1144389D03*
X1615452D03*
X1619193D03*
X1626673D03*
X1622933Y1155610D03*
X1615452D03*
Y1166830D03*
X1619193Y1170570D03*
X1626673Y1159350D03*
X1619193D03*
X1622933Y1166830D03*
X1626673Y1170570D03*
X1619193Y1185531D03*
X1626673D03*
X1622933D03*
Y1178051D03*
X1615452D03*
X1619193D03*
X1626673D03*
X1615452Y1185531D03*
X1622933Y1174310D03*
X1615452D03*
X1622933Y1193011D03*
X1626673D03*
X1615452D03*
X1619193D03*
X1622933Y1200491D03*
X1619193D03*
X1615452D03*
X1626673D03*
X1622933Y1215452D03*
X1619192Y1215451D03*
X1626673Y1215452D03*
X1615452D03*
X1613582Y1217322D03*
X1619192Y1211711D03*
X1622933D03*
X1637893Y1118208D03*
Y1114468D03*
X1634153D03*
X1630413D03*
X1641633D03*
X1634153Y1118208D03*
X1630413D03*
Y1136909D03*
X1637893D03*
X1634153D03*
X1630413Y1129429D03*
X1637893D03*
X1634153D03*
X1630413Y1151869D03*
X1637893D03*
X1634153D03*
Y1144389D03*
X1630413D03*
X1637893D03*
Y1155610D03*
X1630413D03*
X1637893Y1170570D03*
X1641633D03*
X1634153D03*
X1641633Y1166830D03*
X1637893D03*
Y1159350D03*
X1641633D03*
X1634153D03*
X1630413Y1166830D03*
X1641633Y1181791D03*
X1630413Y1185531D03*
X1634153D03*
X1630413Y1178051D03*
X1634153D03*
X1637893Y1185531D03*
Y1178051D03*
Y1174310D03*
X1630413D03*
X1634153Y1193011D03*
X1637893D03*
X1630413D03*
Y1200491D03*
X1637893D03*
X1634153D03*
X1630413Y1215452D03*
X1637893D03*
X1634153D03*
X1656594Y1118208D03*
X1652854D03*
Y1114468D03*
X1645374D03*
X1649114D03*
X1656594D03*
X1645374Y1129429D03*
Y1136909D03*
Y1140649D03*
X1656594Y1133169D03*
Y1140649D03*
Y1136909D03*
X1660334Y1140649D03*
X1649114Y1155610D03*
X1656594D03*
X1645374Y1144389D03*
X1660334Y1148129D03*
X1652854Y1144389D03*
X1656594Y1148129D03*
Y1144389D03*
X1649114Y1159350D03*
Y1170570D03*
Y1166830D03*
X1656594Y1170570D03*
Y1166830D03*
Y1159350D03*
Y1189271D03*
X1649114Y1174310D03*
X1656594D03*
X1652854Y1181791D03*
X1660334Y1189271D03*
X1645374Y1185531D03*
Y1189271D03*
X1660334Y1181791D03*
X1656594Y1178051D03*
X1645374D03*
Y1200491D03*
Y1193011D03*
X1656594Y1196751D03*
Y1204232D03*
X1652854Y1200491D03*
X1649114Y1204232D03*
Y1196751D03*
Y1200491D03*
X1656594D03*
X1645374Y1215452D03*
X1649114D03*
X1652854D03*
X1656594Y1211712D03*
X1645374D03*
X1656594Y1215452D03*
Y1207972D03*
X1649114D03*
X1652854D03*
Y1211712D03*
X1664075Y1140649D03*
X1667815Y1155610D03*
X1664075Y1148129D03*
Y1155610D03*
X1675295Y1144389D03*
Y1151869D03*
Y1166830D03*
Y1159350D03*
X1664075Y1170570D03*
X1667815D03*
X1675295Y1189271D03*
Y1174310D03*
Y1181791D03*
X1686515Y1140649D03*
X1682775D03*
X1679035Y1151869D03*
Y1144389D03*
X1682775Y1148129D03*
X1686515Y1155610D03*
Y1148129D03*
X1682775Y1155610D03*
X1679035Y1166830D03*
X1686515Y1170570D03*
X1682775D03*
X1679035Y1181791D03*
Y1189271D03*
Y1174310D03*
X1686515Y1185531D03*
X1682775Y1178051D03*
X1686515D03*
X1682775Y1185531D03*
X1686515Y1193011D03*
X1682775D03*
Y1222932D03*
X1693996Y1136909D03*
X1697736D03*
X1693996Y1151870D03*
X1697736D03*
X1693996Y1144389D03*
X1697736D03*
Y1159350D03*
X1693996D03*
X1697736Y1174310D03*
X1693996Y1189271D03*
X1697736D03*
Y1181791D03*
X1693996D03*
Y1174310D03*
X1796283Y441086D03*
Y433999D03*
Y437543D03*
X1793483Y441086D03*
Y433999D03*
Y437543D03*
X1796283Y444629D03*
X1793483D03*
G54D53*
X970071Y1365652D03*
Y1409152D03*
G54D33*
X109882Y1489331D03*
Y1494449D03*
Y1591693D03*
Y1596811D03*
Y1622402D03*
X118543Y1452717D03*
X127205Y1489331D03*
Y1494449D03*
X118543Y1493662D03*
Y1498780D03*
X127205Y1591693D03*
X118543Y1596024D03*
X127205Y1596811D03*
X118543Y1601142D03*
X127205Y1622402D03*
X135866Y1452717D03*
X144528Y1489331D03*
Y1494449D03*
X135866Y1493662D03*
Y1498780D03*
X144528Y1591693D03*
X135866Y1596024D03*
X144528Y1596811D03*
X135866Y1601142D03*
X144528Y1622402D03*
X153189Y1452717D03*
X161850Y1489331D03*
Y1494449D03*
X153189Y1493662D03*
Y1498780D03*
X161850Y1591693D03*
X153189Y1596024D03*
X161850Y1596811D03*
X153189Y1601142D03*
X161850Y1622402D03*
X179173Y1458622D03*
Y1463741D03*
X170512Y1452717D03*
X179173Y1473977D03*
Y1479095D03*
Y1489331D03*
Y1494449D03*
X170512Y1493662D03*
Y1498780D03*
X179173Y1504685D03*
Y1509804D03*
Y1560985D03*
Y1566103D03*
Y1576339D03*
Y1581457D03*
Y1591693D03*
X170512Y1596024D03*
X179173Y1596811D03*
Y1607048D03*
Y1612166D03*
X170512Y1601142D03*
X179173Y1622402D03*
X187835Y1452717D03*
Y1462953D03*
Y1468071D03*
Y1478308D03*
Y1483426D03*
Y1493662D03*
Y1498780D03*
Y1509016D03*
Y1514134D03*
Y1565315D03*
Y1570434D03*
Y1580670D03*
Y1585788D03*
X291771Y1452717D03*
X283110Y1504685D03*
X291771Y1509016D03*
X283110Y1509804D03*
X291771Y1514134D03*
X283110Y1607048D03*
X291771Y1611378D03*
X283110Y1612166D03*
X291771Y1616496D03*
X283110Y1622402D03*
X309094Y1452717D03*
X300433Y1504685D03*
X309094Y1509016D03*
X300433Y1509804D03*
X309094Y1514134D03*
X300433Y1607048D03*
X309094Y1611378D03*
X300433Y1612166D03*
X309094Y1616496D03*
X300433Y1622402D03*
X326417Y1452717D03*
X317756Y1504685D03*
X326417Y1509016D03*
X317756Y1509804D03*
X326417Y1514134D03*
X317756Y1607048D03*
X326417Y1611378D03*
X317756Y1612166D03*
X326417Y1616496D03*
X317756Y1622402D03*
X343740Y1452717D03*
X335078Y1504685D03*
X343740Y1509016D03*
X335078Y1509804D03*
X343740Y1514134D03*
X335078Y1607048D03*
X343740Y1611378D03*
X335078Y1612166D03*
X343740Y1616496D03*
X335078Y1622402D03*
X361063Y1452717D03*
X352401Y1458622D03*
Y1463741D03*
X361063Y1462953D03*
Y1468071D03*
X352401Y1473977D03*
Y1479095D03*
X361063Y1478308D03*
Y1483426D03*
X352401Y1489331D03*
Y1494449D03*
X361063Y1493662D03*
Y1498780D03*
X352401Y1504685D03*
Y1509804D03*
X361063Y1509016D03*
Y1514134D03*
X352401Y1560985D03*
Y1566103D03*
X361063Y1565315D03*
Y1570434D03*
X352401Y1576339D03*
Y1581457D03*
X361063Y1580670D03*
Y1585788D03*
X352401Y1591693D03*
Y1596811D03*
Y1607048D03*
Y1612166D03*
Y1622402D03*
X456339Y1458622D03*
Y1463741D03*
Y1489331D03*
Y1494449D03*
Y1576339D03*
Y1581457D03*
Y1607048D03*
Y1612166D03*
Y1622402D03*
X473662Y1458622D03*
Y1463741D03*
X465000Y1452717D03*
Y1462953D03*
Y1468071D03*
X473662Y1489331D03*
Y1494449D03*
X465000Y1493662D03*
Y1498780D03*
X473662Y1576339D03*
Y1581457D03*
X465000Y1580670D03*
Y1585788D03*
X473662Y1607048D03*
Y1612166D03*
X465000Y1611378D03*
X473662Y1622402D03*
X465000Y1616496D03*
X490985Y1458622D03*
Y1463741D03*
X482323Y1452717D03*
Y1462953D03*
Y1468071D03*
X490985Y1489331D03*
Y1494449D03*
X482323Y1493662D03*
Y1498780D03*
X490985Y1576339D03*
Y1581457D03*
X482323Y1580670D03*
Y1585788D03*
X490985Y1607048D03*
Y1612166D03*
X482323Y1611378D03*
X490985Y1622402D03*
X482323Y1616496D03*
X499646Y1452717D03*
Y1462953D03*
Y1468071D03*
Y1493662D03*
Y1498780D03*
Y1580670D03*
Y1585788D03*
Y1611378D03*
Y1616496D03*
X516969Y1452717D03*
X508307Y1458622D03*
X516969Y1462953D03*
X508307Y1463741D03*
X516969Y1468071D03*
X508307Y1489331D03*
X516969Y1493662D03*
X508307Y1494449D03*
X516969Y1498780D03*
X508307Y1576339D03*
X516969Y1580670D03*
X508307Y1581457D03*
X516969Y1585788D03*
X508307Y1607048D03*
X516969Y1611378D03*
X508307Y1612166D03*
X516969Y1616496D03*
X508307Y1622402D03*
X534292Y1452717D03*
X525630Y1458622D03*
Y1463741D03*
X534292Y1462953D03*
Y1468071D03*
X525630Y1473977D03*
Y1479095D03*
X534292Y1478308D03*
Y1483426D03*
X525630Y1489331D03*
Y1494449D03*
X534292Y1493662D03*
Y1498780D03*
X525630Y1504685D03*
Y1509804D03*
X534292Y1509016D03*
Y1514134D03*
X525630Y1560985D03*
Y1566103D03*
X534292Y1565315D03*
Y1570434D03*
X525630Y1576339D03*
Y1581457D03*
X534292Y1580670D03*
Y1585788D03*
X525630Y1591693D03*
X534292Y1596024D03*
X525630Y1596811D03*
X534292Y1601142D03*
X525630Y1607048D03*
Y1612166D03*
X534292Y1611378D03*
Y1616496D03*
X525630Y1622402D03*
X629567D03*
X638228Y1452717D03*
X646890Y1622402D03*
X655551Y1452717D03*
X664213Y1622402D03*
X672874Y1452717D03*
X681535Y1622402D03*
X698858Y1458622D03*
Y1463741D03*
X690197Y1452717D03*
X698858Y1473977D03*
Y1479095D03*
Y1489331D03*
Y1494449D03*
Y1504685D03*
Y1509804D03*
Y1560985D03*
Y1566103D03*
Y1576339D03*
Y1581457D03*
Y1591693D03*
Y1596811D03*
Y1607048D03*
Y1612166D03*
Y1622402D03*
X707520Y1452717D03*
Y1462953D03*
Y1468071D03*
Y1478308D03*
Y1483426D03*
Y1493662D03*
Y1498780D03*
Y1509016D03*
Y1514134D03*
Y1565315D03*
Y1570434D03*
Y1580670D03*
Y1585788D03*
Y1596024D03*
Y1601142D03*
Y1611378D03*
Y1616496D03*
X1140511Y1452717D03*
X1131850Y1489331D03*
X1140511Y1493662D03*
X1131850Y1494449D03*
X1140511Y1498780D03*
X1131850Y1591693D03*
X1140511Y1596024D03*
X1131850Y1596811D03*
X1140511Y1601142D03*
X1131850Y1622402D03*
X1149173Y1489331D03*
Y1494449D03*
Y1591693D03*
Y1596811D03*
Y1622402D03*
X1157834Y1452717D03*
X1166496Y1489331D03*
Y1494449D03*
X1157834Y1493662D03*
Y1498780D03*
X1166496Y1591693D03*
X1157834Y1596024D03*
X1166496Y1596811D03*
X1157834Y1601142D03*
X1166496Y1622402D03*
X1175157Y1452717D03*
X1183818Y1489331D03*
Y1494449D03*
X1175157Y1493662D03*
Y1498780D03*
X1183818Y1591693D03*
X1175157Y1596024D03*
X1183818Y1596811D03*
X1175157Y1601142D03*
X1183818Y1622402D03*
X1201141Y1458622D03*
Y1463741D03*
X1192480Y1452717D03*
X1201141Y1473977D03*
Y1479095D03*
Y1489331D03*
Y1494449D03*
X1192480Y1493662D03*
Y1498780D03*
X1201141Y1504685D03*
Y1509804D03*
Y1560985D03*
Y1566103D03*
Y1576339D03*
Y1581457D03*
Y1591693D03*
X1192480Y1596024D03*
X1201141Y1596811D03*
Y1607048D03*
Y1612166D03*
X1192480Y1601142D03*
X1201141Y1622402D03*
X1209803Y1452717D03*
Y1462953D03*
Y1468071D03*
Y1478308D03*
Y1483426D03*
Y1493662D03*
Y1498780D03*
Y1509016D03*
Y1514134D03*
Y1565315D03*
Y1570434D03*
Y1580670D03*
Y1585788D03*
Y1596024D03*
Y1601142D03*
Y1611378D03*
Y1616496D03*
X1313740Y1452717D03*
X1305079Y1504685D03*
X1313740Y1509016D03*
X1305079Y1509804D03*
X1313740Y1514134D03*
X1305079Y1607048D03*
X1313740Y1611378D03*
X1305079Y1612166D03*
X1313740Y1616496D03*
X1305079Y1622402D03*
X1331063Y1452717D03*
X1322402Y1504685D03*
X1331063Y1509016D03*
X1322402Y1509804D03*
X1331063Y1514134D03*
X1322402Y1607048D03*
X1331063Y1611378D03*
X1322402Y1612166D03*
X1331063Y1616496D03*
X1322402Y1622402D03*
X1348386Y1452717D03*
X1339725Y1504685D03*
X1348386Y1509016D03*
X1339725Y1509804D03*
X1348386Y1514134D03*
X1339725Y1607048D03*
X1348386Y1611378D03*
X1339725Y1612166D03*
X1348386Y1616496D03*
X1339725Y1622402D03*
X1365709Y1452717D03*
X1357047Y1504685D03*
X1365709Y1509016D03*
X1357047Y1509804D03*
X1365709Y1514134D03*
X1357047Y1607048D03*
X1365709Y1611378D03*
X1357047Y1612166D03*
X1365709Y1616496D03*
X1357047Y1622402D03*
X1383032Y1452717D03*
X1374370Y1458622D03*
Y1463741D03*
X1383032Y1462953D03*
Y1468071D03*
X1374370Y1473977D03*
Y1479095D03*
X1383032Y1478308D03*
Y1483426D03*
X1374370Y1489331D03*
Y1494449D03*
X1383032Y1493662D03*
Y1498780D03*
X1374370Y1504685D03*
Y1509804D03*
X1383032Y1509016D03*
Y1514134D03*
X1374370Y1560985D03*
Y1566103D03*
X1383032Y1565315D03*
Y1570434D03*
X1374370Y1576339D03*
Y1581457D03*
X1383032Y1580670D03*
Y1585788D03*
X1374370Y1591693D03*
X1383032Y1596024D03*
X1374370Y1596811D03*
X1383032Y1601142D03*
X1374370Y1607048D03*
Y1612166D03*
X1383032Y1611378D03*
Y1616496D03*
X1374370Y1622402D03*
X1478307Y1458622D03*
Y1463741D03*
Y1489331D03*
Y1494449D03*
Y1576339D03*
Y1581457D03*
Y1607048D03*
Y1612166D03*
Y1622402D03*
X1495630Y1458622D03*
Y1463741D03*
X1486968Y1452717D03*
Y1462953D03*
Y1468071D03*
X1495630Y1489331D03*
Y1494449D03*
X1486968Y1493662D03*
Y1498780D03*
X1495630Y1576339D03*
Y1581457D03*
X1486968Y1580670D03*
Y1585788D03*
X1495630Y1607048D03*
Y1612166D03*
X1486968Y1611378D03*
X1495630Y1622402D03*
X1486968Y1616496D03*
X1512953Y1458622D03*
Y1463741D03*
X1504291Y1452717D03*
Y1462953D03*
Y1468071D03*
X1512953Y1489331D03*
Y1494449D03*
X1504291Y1493662D03*
Y1498780D03*
X1512953Y1576339D03*
Y1581457D03*
X1504291Y1580670D03*
Y1585788D03*
X1512953Y1607048D03*
Y1612166D03*
X1504291Y1611378D03*
X1512953Y1622402D03*
X1504291Y1616496D03*
X1530275Y1458622D03*
Y1463741D03*
X1521614Y1452717D03*
Y1462953D03*
Y1468071D03*
X1530275Y1489331D03*
Y1494449D03*
X1521614Y1493662D03*
Y1498780D03*
X1530275Y1576339D03*
Y1581457D03*
X1521614Y1580670D03*
Y1585788D03*
X1530275Y1607048D03*
Y1612166D03*
X1521614Y1611378D03*
X1530275Y1622402D03*
X1521614Y1616496D03*
X1538937Y1452717D03*
Y1462953D03*
Y1468071D03*
Y1493662D03*
Y1498780D03*
Y1580670D03*
Y1585788D03*
Y1611378D03*
Y1616496D03*
X1556260Y1452717D03*
X1547598Y1458622D03*
Y1463741D03*
X1556260Y1462953D03*
Y1468071D03*
X1547598Y1473977D03*
Y1479095D03*
X1556260Y1478308D03*
Y1483426D03*
X1547598Y1489331D03*
Y1494449D03*
X1556260Y1493662D03*
Y1498780D03*
X1547598Y1504685D03*
Y1509804D03*
X1556260Y1509016D03*
Y1514134D03*
X1547598Y1560985D03*
Y1566103D03*
X1556260Y1565315D03*
Y1570434D03*
X1547598Y1576339D03*
Y1581457D03*
X1556260Y1580670D03*
Y1585788D03*
X1547598Y1591693D03*
X1556260Y1596024D03*
X1547598Y1596811D03*
X1556260Y1601142D03*
X1547598Y1607048D03*
Y1612166D03*
X1556260Y1611378D03*
Y1616496D03*
X1547598Y1622402D03*
X1660196Y1452717D03*
X1651535Y1622402D03*
X1668858D03*
X1677519Y1452717D03*
X1686181Y1622402D03*
X1694842Y1452717D03*
X1703503Y1622402D03*
X1720826Y1458622D03*
Y1463741D03*
X1712165Y1452717D03*
X1720826Y1473977D03*
Y1479095D03*
Y1489331D03*
Y1494449D03*
Y1504685D03*
Y1509804D03*
Y1560985D03*
Y1566103D03*
Y1576339D03*
Y1581457D03*
Y1591693D03*
Y1596811D03*
Y1607048D03*
Y1612166D03*
Y1622402D03*
X1729488Y1452717D03*
Y1462953D03*
Y1468071D03*
Y1478308D03*
Y1483426D03*
Y1493662D03*
Y1498780D03*
Y1509016D03*
Y1514134D03*
Y1565315D03*
Y1570434D03*
Y1580670D03*
Y1585788D03*
Y1596024D03*
Y1601142D03*
Y1611378D03*
Y1616496D03*
G54D54*
X1030635Y754546D03*
Y774546D03*
Y784546D03*
Y794546D03*
Y804546D03*
Y814546D03*
Y824546D03*
G54D28*
X116731Y1052235D03*
X106619Y1056423D03*
X102431Y1066535D03*
X106619Y1076647D03*
X116731Y1080835D03*
Y1249086D03*
X106619Y1253274D03*
X102431Y1263386D03*
X106619Y1273498D03*
X116731Y1277686D03*
X126843Y1056423D03*
Y1076647D03*
X131031Y1066535D03*
X126843Y1253274D03*
X131031Y1263386D03*
X126843Y1273498D03*
X342840Y1056423D03*
X338652Y1066535D03*
X342840Y1076647D03*
Y1253274D03*
X338652Y1263386D03*
X342840Y1273498D03*
X352952Y1052235D03*
Y1080835D03*
Y1249086D03*
Y1277686D03*
X363064Y1056423D03*
Y1076647D03*
X367252Y1066535D03*
X363064Y1253274D03*
X367252Y1263386D03*
X363064Y1273498D03*
X563706Y1056423D03*
X559518Y1066535D03*
X563706Y1076647D03*
Y1253274D03*
X559518Y1263386D03*
X563706Y1273498D03*
X583930Y1056423D03*
X573818Y1052235D03*
X583930Y1076647D03*
X588118Y1066535D03*
X573818Y1080835D03*
X583930Y1253274D03*
X573818Y1249086D03*
X588118Y1263386D03*
X573818Y1277686D03*
X583930Y1273498D03*
X760433Y1480906D03*
X756274Y1490945D03*
X760433Y1500984D03*
X780511Y1480906D03*
X770472Y1476747D03*
Y1505143D03*
X780511Y1500984D03*
X799926Y1056423D03*
X795738Y1066535D03*
X799926Y1076647D03*
Y1253274D03*
X795738Y1263386D03*
X799926Y1273498D03*
X784670Y1490945D03*
X810040Y378544D03*
X805881Y388583D03*
X810040Y398622D03*
X810038Y1052235D03*
Y1080835D03*
Y1249086D03*
Y1277686D03*
X820079Y374385D03*
X830118Y378544D03*
X820079Y402781D03*
X830118Y398622D03*
X820150Y1056423D03*
Y1076647D03*
X824338Y1066535D03*
X820150Y1253274D03*
X824338Y1263386D03*
X820150Y1273498D03*
X834277Y388583D03*
X1010827Y378544D03*
X1006668Y388583D03*
X1010827Y398622D03*
X1020866Y374385D03*
Y402781D03*
X1020793Y1056423D03*
X1016605Y1066535D03*
X1020793Y1076647D03*
Y1253274D03*
X1016605Y1263386D03*
X1020793Y1273498D03*
X1030905Y378544D03*
X1035064Y388583D03*
X1030905Y398622D03*
X1041017Y1056423D03*
X1030905Y1052235D03*
X1041017Y1076647D03*
X1030905Y1080835D03*
X1041017Y1253274D03*
X1030905Y1249086D03*
Y1277686D03*
X1041017Y1273498D03*
X1045205Y1066535D03*
Y1263386D03*
X1060433Y1480906D03*
X1056274Y1490945D03*
X1060433Y1500984D03*
X1070472Y1476747D03*
Y1505143D03*
X1080511Y1480906D03*
X1084670Y1490945D03*
X1080511Y1500984D03*
X1252825Y1066535D03*
Y1263386D03*
X1267125Y1052235D03*
X1257013Y1056423D03*
Y1076647D03*
X1267125Y1080835D03*
Y1249086D03*
X1257013Y1253274D03*
Y1273498D03*
X1267125Y1277686D03*
X1277237Y1056423D03*
Y1076647D03*
X1281425Y1066535D03*
X1277237Y1253274D03*
X1281425Y1263386D03*
X1277237Y1273498D03*
X1477879Y1056423D03*
X1473691Y1066535D03*
X1477879Y1076647D03*
Y1253274D03*
X1473691Y1263386D03*
X1477879Y1273498D03*
X1498103Y1056423D03*
X1487991Y1052235D03*
X1498103Y1076647D03*
X1487991Y1080835D03*
X1498103Y1253274D03*
X1487991Y1249086D03*
Y1277686D03*
X1498103Y1273498D03*
X1502291Y1066535D03*
Y1263386D03*
X1709912Y1066535D03*
Y1263386D03*
X1724212Y1052235D03*
X1714100Y1056423D03*
Y1076647D03*
X1724212Y1080835D03*
Y1249086D03*
X1714100Y1253274D03*
Y1273498D03*
X1724212Y1277686D03*
X1734324Y1056423D03*
Y1076647D03*
X1738512Y1066535D03*
X1734324Y1253274D03*
X1738512Y1263386D03*
X1734324Y1273498D03*
G54D40*
X241623Y1348187D03*
X245023D03*
Y1360099D03*
X241623D03*
X253863Y1372385D03*
X257263D03*
X253863Y1384297D03*
X257263D03*
X281594Y1211712D03*
X270374Y1215452D03*
X269503Y1348187D03*
X266103D03*
Y1360099D03*
X269503D03*
X278343Y1372385D03*
Y1384297D03*
X269503Y1396583D03*
X266103D03*
X269503Y1408495D03*
X266103D03*
X293983Y1348187D03*
X290583D03*
X293983Y1360099D03*
X290583D03*
X281743Y1372385D03*
Y1384297D03*
X293983Y1396583D03*
X290583D03*
X293983Y1408495D03*
X290583D03*
X306223Y1372385D03*
X302823D03*
X306223Y1384297D03*
X302823D03*
X315063Y1348187D03*
X318463D03*
X315063Y1360099D03*
X318463D03*
X327303Y1372385D03*
Y1384297D03*
X315063Y1396583D03*
X318463D03*
Y1408495D03*
X315063D03*
X339543Y1348187D03*
X342943D03*
Y1360099D03*
X339543D03*
X330703Y1372385D03*
Y1384297D03*
X339543Y1396583D03*
X342943D03*
Y1408495D03*
X339543D03*
X351783Y1372385D03*
X355183D03*
Y1384297D03*
X351783D03*
X364023Y1348187D03*
X367423D03*
Y1360099D03*
X364023D03*
Y1396583D03*
X367423D03*
X364023Y1408495D03*
X367423D03*
X393094Y1423600D03*
X395894D03*
X440402Y1348187D03*
Y1360099D03*
X443802Y1348187D03*
Y1360099D03*
X452642Y1372385D03*
X456042D03*
X452642Y1384297D03*
X456042D03*
X468282Y1348187D03*
X464882D03*
X468282Y1360099D03*
X464882D03*
X468282Y1396583D03*
X464882D03*
Y1408495D03*
X468282D03*
X489362Y1348187D03*
Y1360099D03*
X477122Y1372385D03*
X480522D03*
Y1384297D03*
X477122D03*
X489362Y1396583D03*
Y1408495D03*
X492762Y1348187D03*
Y1360099D03*
X505002Y1372385D03*
X501602D03*
X505002Y1384297D03*
X501602D03*
X492762Y1396583D03*
Y1408495D03*
X517242Y1348187D03*
X513842D03*
Y1360099D03*
X517242D03*
Y1396583D03*
X513842D03*
X517242Y1408495D03*
X513842D03*
X538322Y1348187D03*
Y1360099D03*
X529482Y1372385D03*
Y1384297D03*
X526082Y1372385D03*
Y1384297D03*
X538322Y1396583D03*
Y1408495D03*
X541722Y1348187D03*
Y1360099D03*
X550562Y1372385D03*
X553962Y1384297D03*
X550562D03*
X553962Y1372385D03*
X541722Y1396583D03*
Y1408495D03*
X562802Y1348187D03*
X566202D03*
Y1360099D03*
X562802D03*
X566202Y1396583D03*
X562802D03*
X566202Y1408495D03*
X562802D03*
X878220Y848442D03*
Y845293D03*
Y835844D03*
Y851592D03*
X877800Y876500D03*
X897118Y848442D03*
X881370Y835844D03*
X893968Y845293D03*
X884519Y848442D03*
X897118Y842143D03*
X893968D03*
X887669Y848442D03*
X886093Y835318D03*
X897118Y845293D03*
X893968Y838994D03*
X890818Y842143D03*
X893968Y835846D03*
X887669Y845293D03*
X890818D03*
X893968Y848442D03*
X884519Y845293D03*
X881370D03*
X884519Y842143D03*
X887669D03*
X881370Y848442D03*
X890818D03*
X887669Y851592D03*
X890818Y854742D03*
X887669D03*
X897118Y851592D03*
X890818Y864189D03*
Y857891D03*
X887669Y864189D03*
X884519Y854742D03*
Y851592D03*
Y857891D03*
X887669D03*
X890818Y851592D03*
X893967Y851591D03*
X881370Y851592D03*
X887669Y867338D03*
X890818Y870488D03*
X887669D03*
X897118Y876787D03*
X890818Y867338D03*
X881370D03*
X897118Y879937D03*
X884519Y873638D03*
X887669D03*
X884519Y876787D03*
X890818Y879937D03*
X881370Y876787D03*
X887669Y879937D03*
X884519Y867338D03*
X890818Y873638D03*
X893968Y876787D03*
Y879937D03*
X890818Y876787D03*
X884519Y879937D03*
Y870488D03*
X881370D03*
Y883086D03*
X884585Y886354D03*
X885126Y889742D03*
X881370Y886236D03*
X906565Y848442D03*
X900267D03*
X906565Y838994D03*
X900267Y838992D03*
X909714Y848442D03*
X906565Y842143D03*
X900267Y845293D03*
Y842143D03*
X906565Y845293D03*
X900266Y835844D03*
X900267Y851592D03*
X906565D03*
X909714D03*
Y876787D03*
X900267Y879937D03*
Y876787D03*
X906565D03*
X912864Y873638D03*
Y879937D03*
X909714D03*
X906565D03*
X912864Y876787D03*
X922313Y845293D03*
X916014Y848442D03*
Y842143D03*
X919163Y845293D03*
X922313Y842143D03*
X916014Y845293D03*
X919163Y835844D03*
Y838994D03*
Y842143D03*
X925462Y845293D03*
X919163Y854742D03*
Y857891D03*
X922313Y854742D03*
X916014Y857891D03*
Y854742D03*
Y851592D03*
Y864189D03*
X925462Y851592D03*
X922313Y864189D03*
Y857891D03*
X925462D03*
X928612Y864189D03*
X919163D03*
X925462D03*
X916014Y870488D03*
X925462Y873638D03*
X922313Y876787D03*
X928612Y870488D03*
X925462D03*
X916014Y873638D03*
X922313D03*
X916014Y876787D03*
X928612Y873638D03*
X925462Y876787D03*
X928612D03*
Y879937D03*
X916014D03*
X922313D03*
X919163D03*
X925462D03*
X916014Y867338D03*
X919163Y873638D03*
Y870488D03*
X922313D03*
X919163Y876787D03*
X922313Y867338D03*
X919163D03*
X925462D03*
X922313Y883086D03*
Y886236D03*
X925462D03*
X919163Y883086D03*
X928612Y886236D03*
X925462Y883086D03*
X928612D03*
X1184547Y1215452D03*
X1230326Y1348187D03*
X1233726D03*
X1230326Y1360099D03*
X1233726D03*
X1254806Y1348187D03*
Y1360099D03*
X1242566Y1372385D03*
X1245966D03*
X1242566Y1384297D03*
X1245966D03*
X1254806Y1396583D03*
Y1408495D03*
X1258206Y1348187D03*
Y1360099D03*
X1270446Y1372385D03*
X1267046D03*
X1270446Y1384297D03*
X1267046D03*
X1258206Y1396583D03*
Y1408495D03*
X1282686Y1348187D03*
X1279286D03*
Y1360099D03*
X1282686D03*
X1279286Y1396583D03*
X1282686D03*
X1279286Y1408495D03*
X1282686D03*
X1291526Y1372385D03*
X1294926D03*
X1291526Y1384297D03*
X1294926D03*
X1316906Y829871D03*
Y833021D03*
Y848769D03*
X1313756Y833021D03*
Y836170D03*
X1316906Y839320D03*
X1310555Y848675D03*
X1313756Y848769D03*
X1316906Y836170D03*
X1313756Y842470D03*
Y858218D03*
X1316906Y855068D03*
X1313756Y855066D03*
X1316906Y858218D03*
X1307166Y1348187D03*
X1303766D03*
X1307166Y1360099D03*
X1303766D03*
X1316006Y1372385D03*
X1319406D03*
X1316006Y1384297D03*
X1319406D03*
X1303766Y1396583D03*
X1307166D03*
Y1408495D03*
X1303766D03*
X1335803Y829871D03*
X1323205D03*
X1326355Y839320D03*
X1335803D03*
X1329504Y833021D03*
X1332654Y842470D03*
X1329504Y845619D03*
X1332654D03*
X1326355Y836170D03*
X1335803Y842470D03*
X1329504Y836170D03*
X1335803Y845619D03*
Y848769D03*
X1329504Y839320D03*
X1323205Y836170D03*
X1335803D03*
X1329504Y842470D03*
X1335803Y833021D03*
X1323205D03*
X1320055Y845619D03*
X1326355D03*
X1320055Y836170D03*
X1326355Y842470D03*
X1320055Y848769D03*
X1323205Y845619D03*
X1332654Y848769D03*
X1320055Y839320D03*
X1326355Y848769D03*
X1323205D03*
X1329504D03*
X1323204Y839319D03*
X1332654Y839320D03*
X1320055Y842470D03*
X1323205D03*
X1329504Y855068D03*
Y858218D03*
X1320055Y851918D03*
X1332654Y855068D03*
X1326355D03*
Y858218D03*
X1329504Y861367D03*
X1323205Y858218D03*
X1320055D03*
X1332654Y861367D03*
X1329504Y851918D03*
X1323205D03*
X1326355Y861367D03*
X1320055Y855068D03*
X1332654Y858218D03*
X1335803Y855068D03*
Y858218D03*
Y861367D03*
X1320055D03*
X1323204Y855067D03*
X1326355Y851918D03*
X1332654D03*
X1326355Y880263D03*
X1329504Y877114D03*
X1335803Y880263D03*
X1326355Y867665D03*
Y870814D03*
X1323205D03*
X1320055D03*
X1329504Y867665D03*
X1326355Y873964D03*
X1332654Y880263D03*
X1329504D03*
X1332654Y877114D03*
X1326355D03*
X1329504Y870814D03*
X1320055Y873964D03*
X1332654Y870814D03*
X1323204Y873965D03*
X1332654Y867665D03*
X1320055Y880263D03*
Y867665D03*
X1323205Y880263D03*
Y877114D03*
X1320055D03*
X1335803Y867665D03*
Y873964D03*
Y870814D03*
X1332654Y873964D03*
X1329504D03*
X1323205Y867665D03*
Y886562D03*
X1326355Y889712D03*
X1335803Y883413D03*
X1329504Y892862D03*
X1332654Y889712D03*
X1335803Y892862D03*
Y889712D03*
X1326355Y892862D03*
X1329504Y889712D03*
X1320055Y892862D03*
X1323205D03*
X1329504Y886562D03*
X1332654Y883413D03*
X1320055Y886562D03*
X1326355Y883413D03*
X1323205D03*
X1332654Y892862D03*
X1320055Y883413D03*
X1332654Y886562D03*
X1335803D03*
X1320055Y889712D03*
X1323204Y889713D03*
X1329504Y883413D03*
X1328246Y1348187D03*
X1331646D03*
X1328246Y1360099D03*
X1331646D03*
Y1396583D03*
X1328246D03*
X1331646Y1408495D03*
X1328246D03*
X1342103Y845619D03*
X1345252Y836170D03*
X1338953Y845619D03*
X1345252Y833021D03*
X1342103Y836170D03*
X1351550D03*
X1342103Y842470D03*
X1345252Y845619D03*
X1342103Y839320D03*
X1338953Y848769D03*
X1338952Y839319D03*
X1345252Y842470D03*
X1342103Y848769D03*
X1338953Y842470D03*
X1345252Y848769D03*
X1338953Y836170D03*
X1351550Y842470D03*
Y848769D03*
Y845619D03*
X1345252Y839320D03*
X1351550Y858218D03*
X1345252D03*
Y861367D03*
X1342103Y858218D03*
X1351550Y861367D03*
X1338953Y851918D03*
X1342103D03*
X1345252D03*
X1351550D03*
X1338953Y880263D03*
X1351550D03*
X1345252D03*
X1342103Y870814D03*
X1345252D03*
Y867665D03*
X1351550Y870814D03*
Y867665D03*
X1338953Y877114D03*
X1345252D03*
X1351550D03*
X1342103Y880263D03*
X1338953Y883413D03*
X1345252Y889712D03*
Y886562D03*
X1342103Y883413D03*
X1345252D03*
X1338952Y889713D03*
X1338953Y892862D03*
X1342103Y886562D03*
Y892862D03*
Y889712D03*
X1338953Y886562D03*
X1351550Y883413D03*
Y889712D03*
Y886562D03*
Y892862D03*
X1343886Y1372385D03*
X1340486D03*
Y1384297D03*
X1343886D03*
X1364148Y829871D03*
X1367298D03*
X1359425Y829000D03*
X1354699Y842470D03*
Y848769D03*
X1357849D03*
X1364148Y845619D03*
X1354699Y836170D03*
X1357849Y833021D03*
X1367298Y845619D03*
X1364148Y842470D03*
X1357850Y839319D03*
X1357849Y836170D03*
X1360999Y842470D03*
X1354699Y845619D03*
X1357849D03*
X1360999Y839320D03*
X1367298Y842470D03*
X1360999Y848769D03*
Y845619D03*
X1367298Y833021D03*
X1354699Y839320D03*
X1360999Y836170D03*
X1367298Y848769D03*
X1364148Y839320D03*
X1357849Y842470D03*
X1364148Y833021D03*
X1367298Y836170D03*
Y839320D03*
X1364148Y848769D03*
Y851918D03*
X1367298Y861367D03*
X1364148Y858218D03*
Y855068D03*
Y861367D03*
X1367298Y858218D03*
Y851918D03*
X1354699Y858218D03*
X1367298Y855068D03*
X1360999D03*
Y858218D03*
Y861367D03*
X1354699Y851918D03*
X1357849D03*
X1364148Y867665D03*
X1367298Y877114D03*
X1364148Y870814D03*
X1367298Y873964D03*
X1364148D03*
Y877114D03*
X1367298Y870814D03*
X1364148Y880263D03*
X1367298D03*
X1357849D03*
X1360999D03*
X1367298Y867665D03*
X1354699Y870814D03*
X1357849Y877114D03*
X1354699Y880263D03*
X1360999Y867665D03*
Y870814D03*
Y873964D03*
X1367298Y883413D03*
X1354699Y892862D03*
X1360999D03*
X1367298D03*
X1360999Y883413D03*
X1357850Y889713D03*
X1364148Y889712D03*
X1357849Y883413D03*
X1367298Y889712D03*
X1354699D03*
X1357849Y886562D03*
X1364148D03*
X1357849Y892862D03*
X1360999Y889712D03*
X1354699Y883413D03*
X1360999Y886562D03*
X1364148Y892862D03*
Y883413D03*
X1367298Y886562D03*
X1354699D03*
X1356126Y1348187D03*
X1352726D03*
X1356126Y1360099D03*
X1352726D03*
X1356126Y1396583D03*
X1352726D03*
Y1408495D03*
X1356126D03*
X1370447Y829871D03*
Y839320D03*
X1383046Y845619D03*
X1379896D03*
X1373597D03*
Y842470D03*
X1370447Y848769D03*
X1379896D03*
Y839320D03*
X1373597Y848769D03*
X1376747D03*
X1373597Y833021D03*
X1370447D03*
X1373597Y836170D03*
X1370447D03*
X1373598Y839319D03*
X1370447Y842470D03*
Y845619D03*
X1383046Y842470D03*
X1376747Y836170D03*
Y842470D03*
X1379896Y833021D03*
X1383046Y839320D03*
X1376747Y845619D03*
Y839320D03*
X1379896Y855068D03*
Y861367D03*
X1376747Y858218D03*
Y851918D03*
X1373597Y861367D03*
X1376747Y855068D03*
X1373597Y858218D03*
X1376747Y861367D03*
X1383046Y851918D03*
X1373597D03*
X1373598Y855067D03*
X1379896Y851918D03*
X1370447D03*
Y858218D03*
X1383046D03*
Y861367D03*
X1370447Y855068D03*
Y861367D03*
X1383046Y873964D03*
X1376747Y880263D03*
X1370447Y877114D03*
X1373598Y873965D03*
X1370447Y873964D03*
X1379896Y877114D03*
X1373597Y880263D03*
X1383046Y877114D03*
X1370447Y880263D03*
X1376747Y873964D03*
X1383046Y880263D03*
X1370447Y870814D03*
X1376747D03*
X1373597D03*
X1376747Y867665D03*
Y877114D03*
X1373597Y867665D03*
X1379896D03*
X1383046Y870814D03*
X1379896Y880263D03*
X1373597Y877114D03*
X1379896Y873964D03*
X1383046Y892862D03*
X1379896Y886562D03*
X1370447Y883413D03*
X1373598Y889713D03*
X1376747Y886562D03*
X1383046Y883413D03*
X1376747Y889712D03*
X1383046D03*
X1379896D03*
X1373597Y883413D03*
Y886562D03*
X1370447Y892862D03*
X1376747D03*
X1370447Y889712D03*
X1373597Y892862D03*
X1383046Y886562D03*
X1379896Y892862D03*
X1376747Y883413D03*
X1464770Y1348187D03*
X1461370D03*
X1464770Y1360099D03*
X1461370D03*
X1473610Y1372385D03*
X1477010D03*
X1473610Y1384297D03*
X1477010D03*
X1489250Y1348187D03*
X1485850D03*
Y1360099D03*
X1489250D03*
X1498090Y1372385D03*
Y1384297D03*
X1485850Y1396583D03*
X1489250D03*
Y1408495D03*
X1485850D03*
X1513730Y1348187D03*
X1510330D03*
Y1360099D03*
X1513730D03*
X1501490Y1372385D03*
Y1384297D03*
X1510330Y1396583D03*
X1513730D03*
X1510330Y1408495D03*
X1513730D03*
X1525970Y1372385D03*
X1522570D03*
X1525970Y1384297D03*
X1522570D03*
X1538210Y1348187D03*
X1534810D03*
X1538210Y1360099D03*
X1534810D03*
X1547050Y1372385D03*
Y1384297D03*
X1538210Y1396583D03*
X1534810D03*
X1538210Y1408495D03*
X1534810D03*
X1559290Y1348187D03*
X1562690D03*
X1559290Y1360099D03*
X1562690D03*
X1550450Y1372385D03*
Y1384297D03*
X1562690Y1396583D03*
X1559290D03*
Y1408495D03*
X1562690D03*
X1574930Y1372385D03*
X1571530D03*
Y1384297D03*
X1574930D03*
X1587170Y1348187D03*
X1583770D03*
X1587170Y1360099D03*
X1583770D03*
Y1396583D03*
X1587170D03*
X1583770Y1408495D03*
X1587170D03*
X1641634Y1215452D03*
G54D45*
X710406Y-26826D03*
Y-36826D03*
D03*
Y-26826D03*
X735406D03*
Y-36826D03*
D03*
Y-26826D03*
X830406Y-76006D03*
D03*
Y-66006D03*
D03*
X855406Y-76006D03*
D03*
Y-66006D03*
D03*
X939542Y-36798D03*
Y-26798D03*
D03*
Y-36798D03*
X964386Y-75978D03*
D03*
Y-65978D03*
D03*
X964542Y-36798D03*
Y-26798D03*
D03*
Y-36798D03*
X989386Y-75978D03*
D03*
Y-65978D03*
D03*
X993906Y-46826D03*
Y-36826D03*
D03*
Y-26826D03*
X1018906Y-46826D03*
Y-36826D03*
D03*
Y-26826D03*
X1063906Y-76006D03*
Y-86006D03*
Y-76006D03*
Y-66006D03*
X1088906Y-76006D03*
Y-86006D03*
Y-76006D03*
Y-66006D03*
X1217686Y-85978D03*
Y-75978D03*
D03*
Y-65978D03*
X1223042Y-46928D03*
Y-36928D03*
Y-26928D03*
Y-36928D03*
X1242686Y-85978D03*
Y-75978D03*
D03*
Y-65978D03*
X1248042Y-46928D03*
Y-36928D03*
Y-26928D03*
Y-36928D03*
X1280406Y-46956D03*
Y-36956D03*
D03*
Y-26956D03*
X1305406Y-46956D03*
Y-36956D03*
D03*
Y-26956D03*
X1320406Y-76006D03*
Y-86006D03*
Y-76006D03*
Y-66006D03*
X1345406Y-76006D03*
Y-86006D03*
Y-76006D03*
Y-66006D03*
X1474186Y-85978D03*
Y-75978D03*
D03*
Y-65978D03*
X1499186Y-85978D03*
Y-75978D03*
D03*
Y-65978D03*
X1509542Y-47058D03*
Y-37058D03*
Y-27058D03*
Y-37058D03*
X1534542Y-47058D03*
Y-37058D03*
Y-27058D03*
Y-37058D03*
X1564906Y-47086D03*
Y-37086D03*
D03*
Y-27086D03*
X1574906Y-76006D03*
Y-86006D03*
Y-76006D03*
Y-66006D03*
X1589906Y-47086D03*
Y-37086D03*
D03*
Y-27086D03*
X1599906Y-76006D03*
Y-86006D03*
Y-76006D03*
Y-66006D03*
X1728686Y-85978D03*
Y-75978D03*
D03*
Y-65978D03*
X1753686Y-85978D03*
Y-75978D03*
D03*
Y-65978D03*
X1794042Y-47188D03*
Y-37188D03*
Y-27188D03*
Y-37188D03*
X1819042Y-47188D03*
Y-37188D03*
Y-27188D03*
Y-37188D03*
G54D10*
X3704Y5374D03*
X3017Y24773D03*
Y44773D03*
Y64773D03*
Y84773D03*
Y104773D03*
Y124773D03*
Y144773D03*
Y164773D03*
Y184773D03*
Y204773D03*
Y224773D03*
Y244773D03*
Y264773D03*
Y284773D03*
Y304773D03*
X3221Y324773D03*
X3035Y978036D03*
Y998036D03*
Y1018036D03*
Y1038036D03*
Y1058036D03*
Y1078036D03*
Y1098036D03*
Y1118036D03*
Y1138036D03*
Y1158036D03*
Y1178036D03*
Y1198036D03*
Y1238036D03*
Y1258036D03*
Y1278036D03*
Y1298036D03*
Y1318036D03*
Y1338036D03*
Y1358036D03*
Y1378036D03*
Y1398036D03*
Y1418036D03*
Y1438036D03*
Y1458036D03*
Y1478036D03*
Y1498036D03*
Y1538036D03*
Y1558036D03*
X15972Y3000D03*
X10971Y333342D03*
X17964Y349298D03*
Y369298D03*
Y389298D03*
Y409298D03*
Y429298D03*
Y449298D03*
Y469298D03*
Y489298D03*
Y509298D03*
Y529298D03*
Y549298D03*
Y569298D03*
Y589298D03*
Y609298D03*
Y629298D03*
Y649298D03*
Y669298D03*
Y689298D03*
Y709298D03*
Y729298D03*
Y749298D03*
Y769298D03*
Y789298D03*
Y809298D03*
Y829298D03*
Y849298D03*
Y869298D03*
Y889298D03*
Y909298D03*
Y929298D03*
X9554Y961954D03*
X17964Y949298D03*
X6161Y1075991D03*
X6108Y1070611D03*
Y1065318D03*
X6059Y1091964D03*
X6055Y1086546D03*
X6053Y1081305D03*
X8042Y1522199D03*
X7922Y1532494D03*
X26956Y4469D03*
X28317Y24773D03*
Y44773D03*
X35638Y53597D03*
X36692Y641817D03*
X27934Y1204311D03*
X30934D03*
X27934Y1215511D03*
X30934D03*
X27934Y1212711D03*
Y1209911D03*
Y1207111D03*
X30934Y1212711D03*
Y1209911D03*
Y1207111D03*
X21544Y1479662D03*
X33536Y1467485D03*
X21544Y1489648D03*
X42192Y641817D03*
X51449Y822718D03*
X47949D03*
X44960Y1190619D03*
X49638Y1203884D03*
X40996Y1467703D03*
X40195Y1511279D03*
X55638Y53597D03*
X66371Y482134D03*
Y484634D03*
X60233Y521804D03*
X68202Y522129D03*
X60233Y524304D03*
X56540Y531378D03*
Y528878D03*
X68202Y527129D03*
Y524629D03*
Y529629D03*
X62789Y608311D03*
X66510Y628242D03*
X60849Y826818D03*
X64649D03*
X58949Y821018D03*
X64849Y840418D03*
X60249D03*
X74432Y5374D03*
X73745Y24773D03*
Y44773D03*
X73509Y110445D03*
Y115401D03*
X83911Y117557D03*
X80660Y103783D03*
X73509Y129574D03*
Y124618D03*
X83911Y122513D03*
Y131731D03*
Y136687D03*
X69816Y475946D03*
Y478446D03*
X78033Y478586D03*
Y481086D03*
Y476086D03*
Y483586D03*
X72549Y838818D03*
X93334Y3000D03*
X95943Y377953D03*
X113334Y3000D03*
X129318Y4469D03*
X130679Y24773D03*
Y44773D03*
X138000Y53597D03*
X146196Y390223D03*
X138194Y397335D03*
X146196Y395179D03*
Y404396D03*
Y409352D03*
X138194Y402291D03*
X135794Y416465D03*
Y411509D03*
X146196Y418569D03*
Y423525D03*
X135794Y425682D03*
Y430638D03*
X146196Y432743D03*
Y437699D03*
X135794Y439855D03*
Y444811D03*
Y468609D03*
Y473565D03*
X146196Y489895D03*
X135794Y487738D03*
X146196Y480677D03*
Y475721D03*
X135794Y482782D03*
X146196Y494851D03*
X135794Y512743D03*
Y517699D03*
X146196Y519855D03*
X135794Y526916D03*
Y531872D03*
X146196Y524811D03*
Y538984D03*
Y534028D03*
X158000Y53597D03*
X176794Y5374D03*
X176107Y24773D03*
Y44773D03*
X195697Y3000D03*
X183022Y103783D03*
X215697Y3000D03*
X231681Y4469D03*
X229745Y1446675D03*
X224753D03*
Y1462631D03*
X229745Y1457675D03*
X224753D03*
X229745Y1451631D03*
Y1462631D03*
X224753Y1451631D03*
X233042Y24773D03*
Y44773D03*
X240363Y53597D03*
X260363D03*
X279156Y5374D03*
X278469Y24773D03*
Y44773D03*
X265945Y440098D03*
Y437598D03*
Y435098D03*
Y432598D03*
Y430098D03*
X294959Y11097D03*
X285384Y103783D03*
X298059Y3000D03*
X301943Y332017D03*
X318059Y3000D03*
X318497Y466528D03*
Y471484D03*
X328899Y473640D03*
Y487813D03*
Y478596D03*
X318497Y480701D03*
Y485657D03*
X328899Y492769D03*
Y517774D03*
X318497Y510661D03*
Y515617D03*
X328899Y522730D03*
X318497Y524835D03*
X328899Y536903D03*
Y531947D03*
X318497Y529791D03*
X328899Y572769D03*
X318497Y565657D03*
Y560701D03*
X328899Y567813D03*
X318497Y579830D03*
Y574874D03*
X328899Y581987D03*
X318497Y589047D03*
X328899Y586943D03*
X318497Y594003D03*
X328899Y596160D03*
X318497Y603221D03*
X328899Y601116D03*
Y610333D03*
X318497Y608177D03*
X328899Y615289D03*
X334043Y4469D03*
X335404Y24773D03*
Y44773D03*
X342725Y53597D03*
X348737Y375386D03*
X354486Y377173D03*
X357173Y392183D03*
X357218Y396866D03*
X361234Y402867D03*
X358042Y442518D03*
Y439718D03*
X362725Y53597D03*
X361767Y392228D03*
X376992Y395248D03*
X368587Y409016D03*
X364551Y409032D03*
X361811Y396866D03*
X375919Y449118D03*
Y446318D03*
X367919Y449118D03*
Y446318D03*
X376099Y458309D03*
Y454309D03*
Y462309D03*
X369282Y468088D03*
Y465288D03*
X367816Y1310586D03*
Y1315542D03*
X388059Y3000D03*
X381518Y5374D03*
X388487Y24069D03*
X380831Y24773D03*
X383612Y30618D03*
X380831Y44773D03*
X387746Y103783D03*
X389237Y371070D03*
X385237Y370976D03*
X396373Y407104D03*
X385584Y450041D03*
Y452841D03*
Y455641D03*
X387587Y1296675D03*
X387644Y1302089D03*
X389458Y1365466D03*
X389188Y1369033D03*
X388600Y1395500D03*
X389985Y1405762D03*
X408059Y3000D03*
X396373Y409904D03*
X395577Y455641D03*
Y450041D03*
Y452841D03*
X397315Y479560D03*
X400914Y762675D03*
X408300Y755487D03*
X407965Y770196D03*
X408400Y795200D03*
Y792200D03*
X406600Y789000D03*
X402376Y842677D03*
X399876D03*
X402376Y850677D03*
X399876D03*
X395959Y1352153D03*
X403029Y1379716D03*
X403111Y1384920D03*
X408212Y1379695D03*
X394657Y1377875D03*
X403111Y1390103D03*
X408212Y1390083D03*
X410152Y1410928D03*
X398112Y1403741D03*
X415453Y455039D03*
X419040Y533690D03*
Y528390D03*
Y530990D03*
Y536290D03*
Y538890D03*
X423266Y631438D03*
X420266D03*
X417666D03*
X420266Y637038D03*
Y634238D03*
X417666Y637038D03*
Y634238D03*
X423266Y637038D03*
Y634238D03*
Y642638D03*
X420266D03*
X417666D03*
X423266Y639838D03*
X420266D03*
X417666D03*
X415696Y762466D03*
X424649Y842644D03*
X422149D03*
Y850644D03*
X424649D03*
X422149Y858644D03*
X424649D03*
X414280Y1362561D03*
X413437Y1379736D03*
Y1384899D03*
X413395Y1390062D03*
X428059Y3000D03*
X433724Y433975D03*
X432310Y436164D03*
X428740Y533690D03*
X442704Y533790D03*
X428740Y528390D03*
Y530990D03*
X442704Y528490D03*
Y531090D03*
X428740Y536290D03*
Y538890D03*
X442704Y536390D03*
Y538990D03*
X436369Y622883D03*
X441612Y631011D03*
X435881Y1394934D03*
Y1398800D03*
X448059Y3000D03*
X452404Y533690D03*
Y528390D03*
Y530990D03*
Y536290D03*
Y538890D03*
X468059Y3000D03*
X468850Y537507D03*
X461849Y668016D03*
X459349D03*
X466849D03*
X469349D03*
X464349D03*
X469349Y678016D03*
X466849D03*
X459349D03*
X461849D03*
X464349D03*
X484043Y4469D03*
X485404Y24773D03*
Y44773D03*
X482193Y472784D03*
Y468784D03*
Y476784D03*
X484341Y700528D03*
Y705484D03*
X492725Y53597D03*
X499278Y641817D03*
X493778D03*
X512725Y53597D03*
X523457Y482134D03*
Y484634D03*
X517319Y521804D03*
X513626Y528578D03*
Y531378D03*
X517319Y524304D03*
X519875Y608311D03*
X523596Y628242D03*
X531518Y5374D03*
X530831Y24773D03*
Y44773D03*
X537747Y103783D03*
X535119Y483886D03*
Y481086D03*
Y478586D03*
X526902Y478446D03*
Y475946D03*
X535119Y476086D03*
X525288Y522129D03*
Y524629D03*
Y527129D03*
Y529929D03*
X542275Y760782D03*
X532449Y782389D03*
X534672Y785037D03*
X536641Y838649D03*
X550421Y3000D03*
X542599Y782389D03*
X542546Y784911D03*
X554357Y784889D03*
X551524D03*
X570421Y3000D03*
X562231Y784911D03*
X558294D03*
X560263Y829989D03*
X568503Y936807D03*
X565003D03*
X586405Y4469D03*
X587766Y24773D03*
Y44773D03*
X583501Y800831D03*
X577903Y940907D03*
X581703D03*
X576003Y935107D03*
X581903Y954507D03*
X577303D03*
X595087Y53597D03*
X603282Y390223D03*
Y395179D03*
Y404396D03*
Y409352D03*
X595280Y402291D03*
Y397335D03*
X592880Y416465D03*
Y411509D03*
X603282Y418569D03*
Y423525D03*
X592880Y425682D03*
X603282Y432743D03*
Y437699D03*
X592880Y439855D03*
Y430638D03*
Y444811D03*
Y468609D03*
Y473565D03*
X603282Y489895D03*
X592880Y487738D03*
X603282Y480677D03*
Y475721D03*
X592880Y482782D03*
X603282Y494851D03*
X592880Y517699D03*
X603282Y519855D03*
X592880Y526916D03*
Y531872D03*
X603282Y524811D03*
Y538984D03*
Y534028D03*
X589603Y952907D03*
X615087Y53597D03*
X633248Y44884D03*
X640109Y103783D03*
X690073Y44662D03*
X697387Y53619D03*
X717387D03*
X723031Y440098D03*
Y437598D03*
Y435098D03*
Y432598D03*
Y430098D03*
X736242Y5374D03*
X735555Y24773D03*
Y44773D03*
X742471Y103783D03*
X755145Y3000D03*
X759029Y332017D03*
X775145Y3000D03*
X775584Y466528D03*
X775583Y471484D03*
Y480701D03*
Y485657D03*
Y515617D03*
Y510661D03*
Y524835D03*
Y529791D03*
Y560701D03*
Y565657D03*
Y579830D03*
Y574874D03*
Y589047D03*
Y594003D03*
Y603221D03*
Y608177D03*
X791129Y4469D03*
X792490Y24773D03*
Y44773D03*
X799811Y53597D03*
X785985Y473640D03*
Y487813D03*
Y478596D03*
Y492769D03*
Y517774D03*
Y522730D03*
Y531947D03*
Y536903D03*
Y572769D03*
Y567813D03*
Y581987D03*
Y586943D03*
Y601116D03*
Y596160D03*
Y615289D03*
Y610333D03*
X806318Y1401661D03*
X806874Y1447457D03*
X812474D03*
X806874Y1452587D03*
Y1457717D03*
X812474D03*
X815096Y1464387D03*
X812009Y1473432D03*
Y1470432D03*
X815096Y1467387D03*
X812096Y1479587D03*
Y1476587D03*
X815096Y1473387D03*
Y1479587D03*
Y1476587D03*
Y1470387D03*
X819811Y53597D03*
X829791Y839020D03*
X825721Y836666D03*
X823234Y867680D03*
X825774Y895553D03*
X816648Y1377608D03*
X817974Y1447457D03*
Y1452587D03*
Y1457717D03*
X818096Y1464387D03*
X821096D03*
X818096Y1473387D03*
X821096D03*
X824096D03*
X818096Y1479587D03*
X821096D03*
X824096D03*
X818096Y1476587D03*
X821096D03*
X824096D03*
X818096Y1467387D03*
Y1470387D03*
X821096D03*
Y1467387D03*
X824096D03*
Y1470387D03*
X838606Y5374D03*
X837919Y24773D03*
Y44773D03*
X844833Y103783D03*
X833185Y456309D03*
Y452309D03*
Y448309D03*
X850145Y3000D03*
X857973Y404867D03*
X862522Y400229D03*
X862566Y404867D03*
X857928Y400184D03*
X862020Y410899D03*
X862882Y468791D03*
Y465991D03*
X854882D03*
Y468791D03*
X861468Y491303D03*
X859071Y1447459D03*
X864671D03*
X859071Y1452589D03*
Y1457719D03*
X864671D03*
X864644Y1464759D03*
X861644D03*
X855644D03*
X858644D03*
Y1467759D03*
X855644Y1470759D03*
X858644D03*
X864644Y1467759D03*
Y1470759D03*
X861644Y1467759D03*
Y1470759D03*
X855644Y1467759D03*
Y1473759D03*
X858644D03*
X864644D03*
X861644D03*
X855644Y1476759D03*
X858644D03*
X864644D03*
X861644D03*
X872736Y383125D03*
X872318Y408589D03*
X866128Y417532D03*
X869342Y417399D03*
X880910Y471982D03*
Y469182D03*
Y466382D03*
X870882Y465991D03*
Y468791D03*
X878610Y747171D03*
X871294Y771809D03*
X871624Y1213314D03*
X874624D03*
X871624Y1221714D03*
Y1218914D03*
Y1216114D03*
X874624Y1221714D03*
Y1218914D03*
Y1216114D03*
X871624Y1224514D03*
X874624D03*
X870171Y1447459D03*
Y1452589D03*
Y1457719D03*
X867644Y1464759D03*
X870644D03*
X867644Y1467759D03*
X870644D03*
X867644Y1470759D03*
X870644D03*
X867644Y1473759D03*
X870644D03*
X867644Y1476759D03*
X870644D03*
X884736Y383125D03*
X893736D03*
X888736D03*
X891699Y420445D03*
Y423245D03*
X890903Y469182D03*
Y471982D03*
Y466382D03*
X896431Y534093D03*
X897118Y857891D03*
Y864189D03*
Y854742D03*
X893968Y864189D03*
Y857891D03*
Y854742D03*
X897118Y873638D03*
Y870488D03*
Y867338D03*
X893968Y870488D03*
Y873638D03*
Y867338D03*
X887669Y876787D03*
X888650Y1199622D03*
X893328Y1212887D03*
X912278Y343881D03*
X910779Y471380D03*
X903431Y534093D03*
X912462Y695770D03*
X912864Y848442D03*
Y845293D03*
Y842143D03*
X909714Y845293D03*
Y842143D03*
X900267Y864189D03*
X909714Y854742D03*
X906565Y857891D03*
X909714D03*
X906565Y864189D03*
X909714D03*
X906565Y854742D03*
X900267Y857891D03*
Y854742D03*
X912864Y851592D03*
Y857891D03*
Y854742D03*
X909714Y873638D03*
Y870488D03*
X906565Y873638D03*
Y870488D03*
Y867338D03*
X900267Y873638D03*
Y870488D03*
Y867338D03*
X909714D03*
X912171Y1447459D03*
X906671D03*
X901071D03*
X912171Y1457719D03*
Y1452589D03*
X906671Y1457719D03*
X901071D03*
Y1452589D03*
X908370Y1464583D03*
X905370D03*
X899370D03*
X902370D03*
X911370D03*
X905370Y1476583D03*
X908370D03*
X902370D03*
X899370D03*
X905370Y1473583D03*
X908370D03*
X902370D03*
X899370D03*
X902370Y1467583D03*
X899370Y1470583D03*
X902370D03*
X908370Y1467583D03*
Y1470583D03*
X905370Y1467583D03*
Y1470583D03*
X899370Y1467583D03*
X911370Y1476583D03*
Y1473583D03*
Y1467583D03*
Y1470583D03*
X930145Y3000D03*
X921847Y346622D03*
X927636Y452505D03*
X929050Y450316D03*
X928612Y835844D03*
X922313Y851592D03*
X929611Y858669D03*
X914370Y1464583D03*
Y1476583D03*
Y1473583D03*
Y1467583D03*
Y1470583D03*
X941129Y4469D03*
X942490Y24773D03*
Y44773D03*
X931620Y584417D03*
X931594Y599420D03*
X931647Y593271D03*
X931578Y590669D03*
X933810Y972433D03*
X935601Y1221714D03*
Y1218914D03*
Y1216114D03*
Y1213314D03*
X938601Y1221714D03*
Y1218914D03*
Y1216114D03*
Y1213314D03*
X935601Y1224514D03*
X938601D03*
X949811Y53597D03*
X956365Y641817D03*
X950865D03*
X950567Y927654D03*
X952627Y1199622D03*
X957305Y1212887D03*
X969811Y53597D03*
X976763Y307303D03*
X969623Y405614D03*
X963577Y426391D03*
X974406Y521804D03*
Y524304D03*
X970713Y531378D03*
Y528878D03*
X976962Y608311D03*
X980683Y628242D03*
X972278Y934429D03*
X988606Y5374D03*
X987919Y24773D03*
Y44773D03*
X994833Y103783D03*
X993132Y310942D03*
X993243Y321325D03*
X987055Y320273D03*
X993920Y335454D03*
X993420Y337954D03*
X992206Y478586D03*
Y481086D03*
Y483886D03*
X980544Y482134D03*
Y484634D03*
X992206Y476086D03*
X983989Y475946D03*
Y478446D03*
X982375Y522129D03*
Y527129D03*
Y524629D03*
Y529929D03*
X1007508Y3000D03*
X1004635Y300276D03*
X1008635D03*
X998667Y322239D03*
X1000420Y348954D03*
X1010119Y933822D03*
X1006619D03*
X1013683Y-44304D03*
Y-39348D03*
Y-29348D03*
Y-34304D03*
X1027508Y3000D03*
X1021895Y771974D03*
X1019519Y937922D03*
X1023319D03*
X1017619Y932122D03*
X1023519Y951522D03*
X1018919D03*
X1043492Y4469D03*
X1041496Y300276D03*
X1031354Y322905D03*
X1031219Y949922D03*
X1044853Y24773D03*
Y44773D03*
X1052174Y53597D03*
X1046674Y340031D03*
X1045966Y346808D03*
X1052367Y402291D03*
Y397335D03*
X1049967Y416465D03*
Y411509D03*
Y425682D03*
Y439855D03*
Y430638D03*
Y444811D03*
Y468609D03*
Y473565D03*
Y487738D03*
Y482782D03*
Y512743D03*
Y517699D03*
Y526916D03*
Y531872D03*
X1072174Y53597D03*
X1060369Y390223D03*
Y395179D03*
Y404396D03*
Y409352D03*
Y418569D03*
Y423525D03*
Y432743D03*
Y437699D03*
Y489895D03*
Y480677D03*
Y475721D03*
Y494851D03*
Y519855D03*
Y524811D03*
Y538984D03*
Y534028D03*
X1083683Y-78528D03*
Y-83484D03*
Y-73484D03*
Y-68528D03*
X1090280Y44773D03*
X1083483Y1523433D03*
X1097195Y103783D03*
X1147214Y44773D03*
X1154535Y53597D03*
X1174535D03*
X1176858Y306534D03*
X1180118Y430098D03*
Y440098D03*
Y437598D03*
Y435098D03*
Y432598D03*
X1193330Y5374D03*
X1192643Y24773D03*
Y44773D03*
X1199557Y103783D03*
X1192500Y322400D03*
X1199615Y950670D03*
X1201794Y985289D03*
X1212232Y3000D03*
X1221337Y332017D03*
X1232232Y3000D03*
X1232670Y466528D03*
Y471484D03*
Y480701D03*
Y485657D03*
Y515617D03*
Y510661D03*
Y524835D03*
Y529791D03*
Y565657D03*
Y560701D03*
Y579830D03*
Y589047D03*
Y574874D03*
Y603221D03*
Y594003D03*
Y608177D03*
X1248216Y4469D03*
X1249577Y24773D03*
Y44773D03*
X1243072Y473640D03*
Y487813D03*
Y478596D03*
Y492769D03*
Y522730D03*
Y517774D03*
Y536903D03*
Y531947D03*
Y567813D03*
Y572769D03*
Y586943D03*
Y581987D03*
Y601116D03*
Y596160D03*
Y610333D03*
Y615289D03*
X1256898Y53597D03*
X1266219Y374300D03*
X1268659Y377173D03*
X1276898Y53597D03*
X1275940Y392228D03*
X1271346Y392183D03*
X1275407Y402867D03*
X1271391Y396866D03*
X1275984D03*
X1282760Y409016D03*
X1278724Y409032D03*
X1272215Y442518D03*
Y439718D03*
X1282092Y449118D03*
Y446318D03*
X1283455Y468088D03*
Y465288D03*
X1300183Y-44434D03*
Y-29478D03*
Y-34434D03*
Y-39478D03*
X1302232Y3000D03*
X1295692Y5374D03*
X1303229Y23274D03*
X1295005Y24773D03*
X1297785Y30618D03*
X1295005Y44773D03*
X1301919Y103783D03*
X1303158Y371043D03*
X1299410Y370976D03*
X1291165Y395248D03*
X1290092Y449118D03*
Y446318D03*
X1299757Y450041D03*
Y452841D03*
Y455641D03*
X1290272Y458309D03*
Y454309D03*
Y462309D03*
X1310546Y409904D03*
Y407104D03*
X1309750Y455641D03*
Y450041D03*
Y452841D03*
X1311488Y479560D03*
X1309856Y899161D03*
X1305761D03*
X1313756D03*
X1322232Y3000D03*
X1320903Y370995D03*
X1333331Y370905D03*
X1329064Y370951D03*
X1329626Y455039D03*
X1340183Y-83484D03*
Y-78528D03*
Y-68528D03*
Y-73484D03*
X1342232Y3000D03*
X1338287Y370905D03*
X1347897Y433975D03*
X1346483Y436164D03*
X1362232Y3000D03*
X1382232D03*
X1373748Y397758D03*
X1375375Y428995D03*
X1398216Y4469D03*
X1399577Y24773D03*
Y44773D03*
X1397550Y390484D03*
X1387814Y397136D03*
X1389295Y408443D03*
X1386809Y414173D03*
X1388788Y428348D03*
X1406898Y53597D03*
X1416830Y407134D03*
X1411400Y398032D03*
X1413889Y415642D03*
X1413452Y641817D03*
X1407952D03*
X1426898Y53597D03*
X1431493Y521804D03*
X1427800Y528578D03*
X1431493Y524304D03*
X1427800Y531378D03*
X1422176Y1491198D03*
X1423806Y1524252D03*
X1445692Y5374D03*
X1445005Y24773D03*
Y44773D03*
X1440568Y369566D03*
X1449619Y363290D03*
X1438588Y380589D03*
X1437631Y482134D03*
Y484634D03*
X1449293Y476086D03*
X1441076Y475946D03*
Y478446D03*
X1449293Y478586D03*
Y481086D03*
Y483886D03*
X1439462Y522129D03*
Y529929D03*
Y527129D03*
Y524629D03*
X1434049Y608311D03*
X1437770Y628242D03*
X1464594Y3000D03*
X1462675Y14334D03*
X1451920Y103783D03*
X1455979Y391756D03*
X1458212Y403374D03*
X1473364Y410724D03*
X1472403Y417338D03*
X1469293Y428815D03*
X1484594Y3000D03*
X1498446Y912370D03*
X1497208Y909740D03*
X1500578Y4469D03*
X1501939Y24773D03*
Y44773D03*
X1509260Y53597D03*
X1509454Y402291D03*
Y397335D03*
X1507054Y416465D03*
Y411509D03*
Y425682D03*
Y439855D03*
Y430638D03*
Y444811D03*
Y468609D03*
Y473565D03*
Y487738D03*
Y482782D03*
Y517699D03*
Y512743D03*
Y526916D03*
Y531872D03*
X1507034Y888133D03*
X1507358Y909740D03*
X1507305Y912262D03*
X1501400Y966000D03*
X1529260Y53597D03*
X1517456Y390223D03*
Y395179D03*
Y404396D03*
Y409352D03*
Y418569D03*
Y423525D03*
Y432743D03*
Y437699D03*
Y489895D03*
Y480677D03*
Y475721D03*
Y494851D03*
Y519855D03*
Y538984D03*
Y524811D03*
Y534028D03*
X1516283Y912240D03*
X1519116D03*
X1523053Y912262D03*
X1525022Y957340D03*
X1547367Y44773D03*
X1554282Y103783D03*
X1594683Y-83484D03*
Y-78528D03*
Y-68528D03*
Y-73484D03*
X1584683Y-44564D03*
Y-29608D03*
Y-34564D03*
Y-39608D03*
X1604301Y44773D03*
X1611622Y53597D03*
X1631622D03*
X1637205Y440098D03*
Y437598D03*
Y435098D03*
Y432598D03*
Y430098D03*
X1650417Y5374D03*
X1649730Y24773D03*
Y44773D03*
X1656644Y103783D03*
X1669319Y3001D03*
X1673203Y332017D03*
X1689319Y3001D03*
X1689757Y466528D03*
Y471484D03*
Y480701D03*
Y485657D03*
Y515617D03*
Y510661D03*
Y524835D03*
Y529791D03*
Y565657D03*
Y560701D03*
Y589047D03*
Y574874D03*
Y579830D03*
Y603221D03*
Y594003D03*
Y608177D03*
X1705303Y4470D03*
X1706664Y24774D03*
Y44774D03*
X1700159Y473640D03*
Y487813D03*
Y478596D03*
Y492769D03*
Y517774D03*
Y522730D03*
Y536903D03*
Y531947D03*
Y572769D03*
Y567813D03*
Y586943D03*
Y581987D03*
Y601116D03*
Y596160D03*
Y610333D03*
Y615289D03*
X1713985Y53598D03*
X1725746Y377173D03*
X1723964Y370935D03*
X1733985Y53598D03*
X1733027Y392228D03*
X1728433Y392183D03*
X1739847Y409016D03*
X1735811Y409032D03*
X1732494Y402867D03*
X1728478Y396866D03*
X1733071D03*
X1729302Y439718D03*
Y442518D03*
X1739179Y449118D03*
Y446318D03*
X1740542Y468088D03*
Y465288D03*
X1752778Y5374D03*
X1752091Y24773D03*
Y44773D03*
X1756497Y370976D03*
X1748252Y395248D03*
X1756844Y450041D03*
Y452841D03*
Y455641D03*
X1747179Y449118D03*
Y446318D03*
X1747359Y454309D03*
Y458309D03*
Y462309D03*
X1765559Y3001D03*
X1759006Y103783D03*
X1760497Y371070D03*
X1767633Y409904D03*
Y407104D03*
X1766837Y450041D03*
Y452841D03*
Y455641D03*
X1768575Y479560D03*
X1773600Y888100D03*
X1773614Y895275D03*
X1773600Y902800D03*
X1786713Y455039D03*
X1788400Y888100D03*
X1781000Y888087D03*
X1788396Y895066D03*
X1788300Y902800D03*
X1780665Y902796D03*
X1781263Y964660D03*
X1784763D03*
X1779581Y1222200D03*
Y1219400D03*
Y1216600D03*
Y1213800D03*
X1782581Y1222200D03*
Y1219400D03*
Y1216600D03*
Y1213800D03*
X1779581Y1225000D03*
X1782581D03*
X1804984Y433975D03*
X1803570Y436164D03*
X1794163Y968760D03*
X1797963D03*
X1792263Y962960D03*
X1798163Y982360D03*
X1793563D03*
X1805863Y980760D03*
X1796607Y1200108D03*
X1801285Y1213373D03*
X1822983Y346053D03*
Y366053D03*
Y386053D03*
Y406053D03*
Y426053D03*
Y446053D03*
Y466053D03*
Y486053D03*
Y506053D03*
Y526053D03*
Y546053D03*
Y566053D03*
Y586053D03*
Y606053D03*
Y626053D03*
Y646053D03*
Y666053D03*
Y686053D03*
Y706053D03*
Y726053D03*
Y746053D03*
Y766053D03*
Y786053D03*
Y806053D03*
Y826053D03*
Y846053D03*
Y866053D03*
Y886053D03*
Y906053D03*
Y926053D03*
Y946053D03*
X1825559Y3001D03*
X1836543Y4470D03*
X1837904Y24774D03*
Y44774D03*
Y64774D03*
Y84774D03*
Y104774D03*
Y124774D03*
Y144774D03*
Y164774D03*
Y184774D03*
Y204774D03*
Y224774D03*
Y244774D03*
Y264774D03*
Y284774D03*
Y304774D03*
X1837728Y324733D03*
X1830094Y333210D03*
X1830472Y960970D03*
X1837937Y973244D03*
Y993244D03*
Y1013244D03*
Y1033244D03*
Y1053244D03*
Y1073244D03*
X1824733Y1102830D03*
X1837937Y1093244D03*
X1825832Y1097589D03*
X1837937Y1113244D03*
Y1133244D03*
Y1153244D03*
Y1173244D03*
Y1193244D03*
Y1213244D03*
Y1253244D03*
Y1273244D03*
Y1293244D03*
Y1313244D03*
Y1333244D03*
Y1353244D03*
Y1373244D03*
Y1393244D03*
Y1433244D03*
Y1453244D03*
Y1473244D03*
Y1493244D03*
Y1513244D03*
Y1533244D03*
Y1553244D03*
Y1573244D03*
G54D14*
X20408Y51296D03*
Y55296D03*
X9057Y138939D03*
X19184Y144728D03*
X15184D03*
X15520Y195176D03*
X18320D03*
X13020D03*
X10520D03*
X12880Y203393D03*
X10380D03*
X19068Y206838D03*
X16568D03*
X13606Y1476707D03*
X19365Y1494298D03*
X24316Y67527D03*
Y63527D03*
Y59527D03*
X23184Y144728D03*
X35650Y487982D03*
Y478982D03*
Y483982D03*
Y499982D03*
X25819Y531726D03*
Y536726D03*
Y552726D03*
Y540726D03*
X30410Y1218497D03*
Y1220997D03*
Y1234797D03*
Y1232297D03*
Y1227897D03*
Y1225397D03*
Y1241697D03*
Y1239197D03*
X25674Y1486291D03*
X32195Y1511279D03*
X32079Y1521641D03*
X31237Y1532096D03*
X46240Y109410D03*
X45988Y102323D03*
X46240Y116496D03*
X46931Y130670D03*
X49236Y121658D03*
X46932Y137756D03*
X49839Y546830D03*
X44195Y1511279D03*
X39237Y1532096D03*
X64098Y102323D03*
Y109410D03*
Y116496D03*
Y123583D03*
Y130670D03*
Y137756D03*
X69139Y236611D03*
X68841Y248891D03*
X66224Y473045D03*
X58224D03*
X53643Y472905D03*
X59670Y500086D03*
X64495Y527449D03*
X61695D03*
X60554Y1612002D03*
X66291Y1633801D03*
X74139Y236611D03*
X71639D03*
X71341Y248891D03*
X73841D03*
X74326Y480705D03*
X71995Y532749D03*
X74795D03*
X74291Y1633801D03*
X86291D03*
X119582Y102249D03*
X111582D03*
X115582D03*
X115382Y195176D03*
X112882D03*
X117882D03*
X115242Y203393D03*
X112742D03*
X120682Y195176D03*
X118930Y206838D03*
X121430D03*
X148602Y109410D03*
Y116496D03*
X148350Y102323D03*
X148774Y124576D03*
X149827Y130670D03*
X149822Y137756D03*
X166460Y116496D03*
Y109410D03*
Y102323D03*
Y123583D03*
Y130670D03*
Y137756D03*
X174001Y236611D03*
X176501D03*
X171501D03*
X176203Y248891D03*
X173703D03*
X171203D03*
X185169Y389154D03*
Y396240D03*
X186448Y404911D03*
X186589Y426299D03*
X185402Y412571D03*
X186900Y445847D03*
X185169Y467539D03*
Y474626D03*
X185430Y480828D03*
X187380Y498834D03*
X185169Y518760D03*
Y511673D03*
Y525847D03*
X191125Y602400D03*
Y598400D03*
Y594400D03*
Y606400D03*
Y614400D03*
X203591Y91951D03*
X213944Y102249D03*
X215244Y195176D03*
X215104Y203393D03*
X203280Y389154D03*
Y396240D03*
Y403327D03*
Y410413D03*
Y417500D03*
Y424586D03*
Y431673D03*
Y438760D03*
Y445847D03*
Y467539D03*
Y474626D03*
Y488799D03*
Y481713D03*
Y495886D03*
Y511673D03*
Y518760D03*
Y525847D03*
Y532933D03*
Y540020D03*
Y547106D03*
Y554193D03*
Y602205D03*
Y595118D03*
X221944Y102249D03*
X217944D03*
X220244Y195176D03*
X217744D03*
X223044D03*
X223792Y206838D03*
X221292D03*
X217604Y203393D03*
X228267Y392718D03*
Y408718D03*
Y400718D03*
Y404718D03*
Y412718D03*
X250964Y109410D03*
X250712Y102323D03*
X250964Y116496D03*
X251136Y124576D03*
X252189Y130670D03*
X252184Y137756D03*
X268822Y116496D03*
Y109410D03*
Y102323D03*
Y130670D03*
Y123583D03*
Y137756D03*
X276363Y236611D03*
X278863D03*
X273863D03*
X276065Y248891D03*
X273565D03*
X278565D03*
X274205Y466027D03*
X274347Y475262D03*
Y489435D03*
Y482666D03*
X274163Y495088D03*
X274205Y509626D03*
X274820Y522134D03*
X274898Y514608D03*
X275463Y529136D03*
X275302Y535677D03*
X274586Y565574D03*
X274205Y559665D03*
X274233Y574338D03*
X274332Y616358D03*
X292500Y410394D03*
Y403307D03*
X284295Y430760D03*
X284316Y433570D03*
X284132Y437072D03*
X284173Y439963D03*
X284417Y443180D03*
X284437Y454744D03*
X284379Y452018D03*
X292316Y458406D03*
Y465492D03*
Y472579D03*
Y479665D03*
Y486752D03*
Y493839D03*
Y523799D03*
Y516713D03*
Y509626D03*
Y537973D03*
Y530886D03*
Y559665D03*
Y566752D03*
Y573839D03*
Y588012D03*
Y580925D03*
Y595099D03*
Y602185D03*
Y616358D03*
Y609272D03*
X324306Y102249D03*
X320306D03*
X316306D03*
X322606Y195176D03*
X325406D03*
X320106D03*
X317606D03*
X323654Y206838D03*
X319966Y203393D03*
X317466D03*
X326154Y206838D03*
X319857Y321649D03*
X324291Y556775D03*
X353074Y102323D03*
X353326Y109410D03*
Y116496D03*
X353498Y124576D03*
X354551Y130670D03*
X354546Y137756D03*
X371184Y116496D03*
Y109410D03*
Y102323D03*
Y130670D03*
Y123583D03*
Y137756D03*
X376225Y236611D03*
X375927Y248891D03*
X373101Y779608D03*
X376300Y779800D03*
X370214Y959812D03*
Y967812D03*
X381225Y236611D03*
X378725D03*
X378427Y248891D03*
X380927D03*
X379800Y778000D03*
X387692Y790056D03*
X393547D03*
X386614Y868286D03*
X385512Y955356D03*
X390150Y955312D03*
Y959905D03*
X385467Y959950D03*
X409268Y408240D03*
X409386Y420393D03*
X400900Y755400D03*
Y770100D03*
X407193Y883566D03*
X396182Y955858D03*
X402682Y948536D03*
X402815Y951750D03*
X404004Y1198321D03*
Y1200821D03*
X407469Y1495035D03*
X407854Y1492118D03*
X406377Y1499142D03*
X411768Y408240D03*
X414268D03*
X411847Y424240D03*
X414386Y420393D03*
X411886D03*
X411847Y426740D03*
X415700Y755400D03*
Y770200D03*
X422430Y834800D03*
X422379Y867229D03*
X420661Y1119422D03*
X423141Y1113822D03*
Y1119422D03*
X418181Y1113822D03*
Y1119422D03*
X420661Y1113822D03*
X417469Y1200821D03*
Y1198321D03*
X439804Y536682D03*
Y539182D03*
X430934Y1200821D03*
Y1198321D03*
X430657Y1563562D03*
X446179Y447101D03*
X448726Y653288D03*
Y646480D03*
Y648980D03*
Y655788D03*
X450244Y1090268D03*
Y1093068D03*
X455269Y1119422D03*
X450309Y1113822D03*
Y1119422D03*
X452789Y1113822D03*
Y1119422D03*
X455269Y1113822D03*
X474307Y102249D03*
X470307D03*
X466307D03*
X470107Y195176D03*
X467607D03*
X472607D03*
X475407D03*
X473655Y206838D03*
X467467Y203393D03*
X469967D03*
X463104Y536582D03*
Y539082D03*
X476155Y206838D03*
X492736Y478982D03*
X482905Y531726D03*
X482737Y537215D03*
X482905Y552726D03*
Y540726D03*
X488728Y1119422D03*
X483768Y1113822D03*
X486248D03*
Y1119422D03*
X483768D03*
X488728Y1113822D03*
X477206Y1198321D03*
X490671D03*
Y1200821D03*
X477206D03*
X503075Y102323D03*
X503327Y109410D03*
Y116496D03*
X506653Y121652D03*
X504552Y130670D03*
X504547Y137756D03*
X493485Y439903D03*
X492736Y487982D03*
Y483982D03*
Y499982D03*
X506925Y546830D03*
X504136Y1198321D03*
Y1200821D03*
X521185Y116496D03*
Y109410D03*
Y102323D03*
Y130670D03*
Y123583D03*
Y137756D03*
X508729Y469905D03*
X521310Y470045D03*
X513310D03*
X516756Y500086D03*
X518781Y527449D03*
X521581D03*
X518812Y665867D03*
X515831Y1090568D03*
Y1093068D03*
X518376Y1113822D03*
Y1119422D03*
X520856Y1113822D03*
Y1119422D03*
X515896Y1113822D03*
Y1119422D03*
X526226Y236611D03*
X531226D03*
X528726D03*
X528428Y248891D03*
X530928D03*
X525928D03*
X531412Y480705D03*
X528612D03*
X529481Y532849D03*
X532281D03*
X533486Y664052D03*
X538442D03*
X524941Y661387D03*
X530796D03*
X572669Y102249D03*
X568669D03*
X572469Y195176D03*
X572329Y203393D03*
X567559Y812850D03*
X576669Y102249D03*
X574969Y195176D03*
X577769D03*
X578517Y206838D03*
X576017D03*
X605437Y102323D03*
X605689Y109410D03*
Y116496D03*
X605861Y124576D03*
X606914Y130670D03*
X606909Y137756D03*
X623547Y109410D03*
Y116496D03*
Y102323D03*
Y123583D03*
Y130670D03*
Y137756D03*
X633588Y236611D03*
X631088D03*
X628588D03*
X630790Y248891D03*
X633290D03*
X628290D03*
X642255Y389154D03*
Y396240D03*
X643534Y404911D03*
X642488Y412571D03*
X643675Y426299D03*
X643986Y445847D03*
X642255Y467539D03*
Y474626D03*
X642516Y480828D03*
X644466Y498834D03*
X642255Y518760D03*
Y511673D03*
Y525847D03*
X648211Y602400D03*
Y598400D03*
Y594400D03*
Y606400D03*
Y614400D03*
X660366Y389154D03*
Y403327D03*
Y410413D03*
Y396240D03*
Y417500D03*
Y424586D03*
Y431673D03*
Y438760D03*
Y445847D03*
Y467539D03*
Y474626D03*
Y488799D03*
Y481713D03*
Y495886D03*
Y511673D03*
Y518760D03*
Y525847D03*
Y532933D03*
Y540020D03*
Y554193D03*
Y547106D03*
Y602205D03*
Y595118D03*
X679031Y102249D03*
X672331Y195176D03*
X674831D03*
X680131D03*
X672191Y203393D03*
X674691D03*
X678379Y206838D03*
X680879D03*
X685353Y392718D03*
Y408718D03*
Y400718D03*
Y404718D03*
Y412718D03*
X707799Y102323D03*
X708051Y109410D03*
Y116496D03*
X708223Y124576D03*
X709276Y130670D03*
X709271Y137756D03*
X725909Y102323D03*
Y116496D03*
Y109410D03*
Y130670D03*
Y123583D03*
Y137756D03*
X733450Y236611D03*
X730950D03*
X733152Y248891D03*
X730652D03*
X731291Y466027D03*
X731433Y475262D03*
Y489435D03*
Y482666D03*
X731249Y495088D03*
X731984Y514608D03*
X731906Y522134D03*
X731291Y509626D03*
X732549Y529136D03*
X732388Y535677D03*
X731291Y559665D03*
X731672Y565574D03*
X731319Y574338D03*
X731418Y616358D03*
X735950Y236611D03*
X735652Y248891D03*
X749586Y410394D03*
Y403307D03*
X741259Y439963D03*
X741381Y430760D03*
X741402Y433570D03*
X741218Y437072D03*
X741503Y443180D03*
X741523Y454744D03*
X741465Y452018D03*
X749402Y458406D03*
Y465492D03*
Y472579D03*
Y479665D03*
Y486752D03*
Y493839D03*
Y523799D03*
Y516713D03*
Y509626D03*
Y537973D03*
Y530886D03*
Y559665D03*
Y566752D03*
Y573839D03*
Y588012D03*
Y580925D03*
Y602185D03*
Y595099D03*
Y609272D03*
Y616358D03*
X751140Y1581335D03*
X740640Y1586885D03*
X748924Y1617709D03*
X735878Y1617010D03*
X763040Y91951D03*
X781393Y102249D03*
X777393D03*
X773393D03*
X779693Y195176D03*
X777193D03*
X782493D03*
X774693D03*
X780741Y206838D03*
X783241D03*
X777053Y203393D03*
X774553D03*
X776943Y321649D03*
X778985Y442498D03*
X778881Y446510D03*
X779029Y450510D03*
X777033Y1595215D03*
X781545Y1602835D03*
X774658Y1601012D03*
X792564Y406410D03*
X784586Y421000D03*
Y418500D03*
Y413500D03*
Y416000D03*
X784665Y564843D03*
X787447Y1593586D03*
X791610Y1593708D03*
X810161Y102323D03*
X810413Y109410D03*
Y116496D03*
X810585Y124576D03*
X811638Y130670D03*
X811633Y137756D03*
X828271Y116496D03*
Y109410D03*
Y102323D03*
Y130670D03*
Y123583D03*
Y137756D03*
X835812Y236611D03*
X838312D03*
X833312D03*
X833014Y248891D03*
X838014D03*
X835514D03*
X867093Y570703D03*
Y582828D03*
Y558703D03*
Y562703D03*
Y566703D03*
Y578703D03*
X872440Y1230083D03*
Y1227583D03*
Y1234483D03*
Y1236983D03*
Y1243883D03*
Y1241383D03*
Y1248283D03*
Y1250783D03*
X889436Y715970D03*
X905094Y424581D03*
X902594D03*
X907594D03*
X905212Y436734D03*
X902712D03*
X907712D03*
X907173Y440581D03*
Y443081D03*
X909024Y578394D03*
Y574394D03*
X909714Y838994D03*
X931393Y102249D03*
X923393D03*
X927393D03*
X925359Y180347D03*
X927859D03*
X925219Y188564D03*
X927719D03*
X919606Y231000D03*
X919577Y245669D03*
Y233858D03*
X919682Y236921D03*
X919577Y259843D03*
Y255118D03*
X919729Y274580D03*
X930359Y180347D03*
X933159D03*
X931407Y192009D03*
X933907D03*
X941505Y463442D03*
X939827Y531104D03*
X939992Y536726D03*
Y540726D03*
Y552726D03*
X936417Y1234483D03*
Y1236983D03*
Y1230083D03*
Y1227583D03*
Y1243883D03*
Y1241383D03*
Y1248283D03*
Y1250783D03*
X956460Y-35982D03*
X953207Y-35996D03*
X956445Y-38497D03*
X953192Y-38511D03*
X950167Y-37191D03*
X960161Y102323D03*
X960413Y109410D03*
Y116496D03*
X961638Y130670D03*
X961633Y137756D03*
X950315Y464851D03*
X949823Y487982D03*
X949876Y478486D03*
X949823Y483982D03*
Y499982D03*
X978036Y-77691D03*
X978051Y-75176D03*
X975011Y-76371D03*
X978271Y109410D03*
Y102323D03*
Y116496D03*
Y130670D03*
Y123583D03*
X963360Y121459D03*
X978271Y137756D03*
X977150Y328472D03*
Y335472D03*
X967816Y472905D03*
X972397Y472954D03*
X973843Y500086D03*
X978668Y527449D03*
X975868D03*
X964012Y546830D03*
X978857Y1360945D03*
X981289Y-77677D03*
X981304Y-75162D03*
X985812Y236611D03*
X988312D03*
X983312D03*
X983014Y248891D03*
X988014D03*
X985514D03*
X980397Y473045D03*
X985699Y480705D03*
X988499D03*
X989068Y532949D03*
X986268D03*
X981857Y1360945D03*
X978944Y1413859D03*
X981944D03*
X1007611Y1561247D03*
Y1558247D03*
Y1555247D03*
Y1552247D03*
X1004611Y1561247D03*
Y1558247D03*
Y1555247D03*
Y1552247D03*
X1015402Y91951D03*
X1025755Y102249D03*
X1027055Y195176D03*
X1033755Y102249D03*
X1029755D03*
X1032055Y195176D03*
X1029555D03*
X1034855D03*
X1033103Y206838D03*
X1035603D03*
X1029415Y203393D03*
X1062523Y102323D03*
X1062775Y109410D03*
Y116496D03*
X1062947Y124576D03*
X1064000Y130670D03*
X1063995Y137756D03*
X1080633Y102323D03*
Y116496D03*
Y109410D03*
Y130670D03*
Y123583D03*
Y137756D03*
X1085674Y236611D03*
X1088174D03*
X1090674D03*
X1090376Y248891D03*
X1087876D03*
X1085376D03*
X1077855Y327478D03*
X1077252Y323521D03*
Y318565D03*
X1077855Y332434D03*
X1099342Y389154D03*
Y396240D03*
X1100621Y404911D03*
X1099575Y412571D03*
X1100762Y426299D03*
X1101073Y445847D03*
X1099342Y467539D03*
Y474626D03*
X1099603Y480828D03*
X1101553Y498834D03*
X1099342Y518760D03*
Y511673D03*
Y525847D03*
X1105298Y598400D03*
Y602400D03*
Y594400D03*
Y614400D03*
Y606400D03*
X1117764Y91951D03*
X1117453Y389154D03*
Y396240D03*
Y403327D03*
Y410413D03*
Y417500D03*
Y424586D03*
Y431673D03*
Y438760D03*
Y445847D03*
Y467539D03*
Y474626D03*
Y488799D03*
Y481713D03*
Y495886D03*
Y511673D03*
Y518760D03*
Y525847D03*
Y532933D03*
Y540020D03*
Y554193D03*
Y547106D03*
Y602205D03*
Y595118D03*
X1136117Y102249D03*
X1132117D03*
X1128117D03*
X1134417Y195176D03*
X1131917D03*
X1137217D03*
X1129417D03*
X1137965Y206838D03*
X1131777Y203393D03*
X1135465Y206838D03*
X1142440Y404718D03*
Y412718D03*
X1125287Y592897D03*
X1142440Y392718D03*
Y400718D03*
Y408718D03*
X1164885Y102323D03*
X1165137Y109410D03*
Y116496D03*
X1165309Y124576D03*
X1166362Y130670D03*
X1166357Y137756D03*
X1182995Y116496D03*
Y109410D03*
Y102323D03*
Y130670D03*
Y123583D03*
Y137756D03*
X1188036Y236611D03*
X1187738Y248891D03*
X1188378Y466027D03*
X1188520Y475262D03*
Y489435D03*
Y482666D03*
X1188336Y495088D03*
X1189071Y514608D03*
X1188993Y522134D03*
X1188378Y509626D03*
X1189475Y535677D03*
X1189636Y529136D03*
X1188378Y559665D03*
X1188759Y565574D03*
X1188406Y574338D03*
X1188505Y616358D03*
X1190536Y236611D03*
X1193036D03*
X1192738Y248891D03*
X1190238D03*
X1198468Y430760D03*
X1198489Y433570D03*
X1198305Y437072D03*
X1198346Y439963D03*
X1198552Y452018D03*
X1198590Y443180D03*
X1198610Y454744D03*
X1220126Y91951D03*
X1206673Y410394D03*
Y403307D03*
X1206489Y458406D03*
Y465492D03*
Y472579D03*
Y479665D03*
Y486752D03*
Y493839D03*
Y523799D03*
Y516713D03*
Y509626D03*
Y537973D03*
Y530886D03*
Y566752D03*
Y559665D03*
Y580925D03*
Y588012D03*
Y573839D03*
Y602185D03*
Y595099D03*
Y616358D03*
Y609272D03*
X1231336Y-87691D03*
X1234589Y-87777D03*
X1231351Y-85176D03*
X1234604Y-85262D03*
X1228311Y-86371D03*
X1236692Y-48727D03*
X1236707Y-46212D03*
X1233667Y-47421D03*
X1238479Y102249D03*
X1230479D03*
X1234479D03*
X1236779Y195176D03*
X1234279D03*
X1239579D03*
X1231779D03*
X1234139Y203393D03*
X1231639D03*
X1237827Y206838D03*
X1234100Y322924D03*
X1239945Y-48727D03*
X1239960Y-46212D03*
X1240327Y206838D03*
X1241752Y564843D03*
X1267499Y116496D03*
X1267247Y102323D03*
X1267499Y109410D03*
X1267671Y124576D03*
X1268724Y130670D03*
X1268719Y137756D03*
X1259500Y330000D03*
X1285357Y116496D03*
Y109410D03*
Y102323D03*
Y123583D03*
Y130670D03*
Y137756D03*
X1281834Y374839D03*
X1290398Y236611D03*
X1295398D03*
X1292898D03*
X1290100Y248891D03*
X1292600D03*
X1295100D03*
X1301500Y329000D03*
X1292731Y331820D03*
X1300400Y339619D03*
Y344575D03*
X1290066Y804246D03*
X1319000Y566500D03*
Y582500D03*
Y613000D03*
Y629000D03*
Y657500D03*
Y673500D03*
Y704500D03*
Y720500D03*
X1305412Y799061D03*
X1318178Y1198321D03*
Y1200821D03*
X1325941Y408240D03*
X1328441D03*
X1323441D03*
X1326059Y420393D03*
X1326020Y424240D03*
X1323559Y420393D03*
X1328559D03*
X1326020Y426740D03*
X1335802Y896011D03*
X1332355Y1113822D03*
Y1119422D03*
X1334835Y1113822D03*
Y1119422D03*
X1331643Y1200821D03*
Y1198321D03*
X1344768Y769675D03*
X1337315Y1113822D03*
Y1119422D03*
X1345108Y1200821D03*
Y1198321D03*
X1361039Y327099D03*
Y332055D03*
X1364039Y334973D03*
Y339929D03*
X1361039Y342847D03*
X1364039Y350721D03*
X1361039Y347803D03*
X1364039Y355677D03*
X1360352Y447101D03*
X1364148Y896011D03*
X1364418Y1090568D03*
Y1093068D03*
X1366963Y1119422D03*
Y1113822D03*
X1364483Y1119422D03*
Y1113822D03*
X1380480Y102249D03*
X1384480D03*
X1384280Y195176D03*
X1381780D03*
X1384140Y203393D03*
X1381640D03*
X1384253Y346826D03*
X1384447Y356871D03*
X1384174Y362641D03*
X1379896Y870814D03*
Y883413D03*
X1383046Y899161D03*
X1369443Y1119422D03*
Y1113822D03*
X1388480Y102249D03*
X1389580Y195176D03*
X1386780D03*
X1390328Y206838D03*
X1387828D03*
X1385943Y323222D03*
X1385971Y327688D03*
X1386143Y331982D03*
X1386057Y341200D03*
X1385971Y336791D03*
X1386286Y350218D03*
X1397079Y531726D03*
Y536726D03*
Y552726D03*
Y540726D03*
X1397942Y1119422D03*
X1400422D03*
Y1113822D03*
X1397942D03*
X1391380Y1200821D03*
Y1198321D03*
X1417248Y102323D03*
X1416347Y384373D03*
X1406910Y487982D03*
Y478982D03*
Y483982D03*
Y499982D03*
X1410000Y689000D03*
Y705000D03*
Y733000D03*
Y749000D03*
X1402902Y1119422D03*
Y1113822D03*
X1404845Y1198321D03*
Y1200821D03*
X1404239Y1547755D03*
X1403747Y1570433D03*
X1417500Y109410D03*
Y116496D03*
X1421700Y122900D03*
X1418725Y130670D03*
X1418720Y137756D03*
X1427484Y470045D03*
X1422903Y469905D03*
X1430930Y500086D03*
X1432955Y527449D03*
X1421099Y546830D03*
X1427000Y774500D03*
Y790500D03*
Y818500D03*
Y834500D03*
X1430005Y1090568D03*
Y1093068D03*
X1432550Y1119422D03*
Y1113822D03*
X1430070Y1119422D03*
Y1113822D03*
X1418310Y1198321D03*
Y1200821D03*
X1435358Y116496D03*
Y109410D03*
Y102323D03*
Y130670D03*
Y123583D03*
Y137756D03*
X1440399Y236611D03*
X1442899D03*
X1445399D03*
X1440101Y248891D03*
X1442601D03*
X1445101D03*
X1435484Y470045D03*
X1442786Y480705D03*
X1445586D03*
X1435755Y527449D03*
X1443555Y532949D03*
X1446355D03*
X1435030Y1119422D03*
Y1113822D03*
X1437293Y1546125D03*
X1436801Y1568803D03*
X1451215Y323193D03*
X1451330Y327588D03*
X1451272Y340971D03*
X1451344Y336620D03*
X1451300Y332225D03*
X1451387Y345609D03*
X1451186Y350447D03*
X1472489Y91951D03*
X1479500Y706500D03*
Y750500D03*
X1487836Y-87777D03*
X1491089D03*
X1487851Y-85262D03*
X1491104D03*
X1484811Y-86371D03*
X1490842Y102249D03*
X1486842D03*
X1482842D03*
X1486642Y195176D03*
X1489142D03*
X1484142D03*
X1491942D03*
X1492690Y206838D03*
X1490190D03*
X1484002Y203393D03*
X1486502D03*
X1484796Y320359D03*
X1484968Y325025D03*
X1484876Y329377D03*
X1488255Y342921D03*
X1484682Y338394D03*
X1497760Y336543D03*
X1487926Y347387D03*
X1496500Y792000D03*
Y836000D03*
X1500480Y295727D03*
X1523192Y-48857D03*
X1526445D03*
X1523207Y-46342D03*
X1526460D03*
X1520167Y-47451D03*
X1519610Y102323D03*
X1519862Y109410D03*
Y116496D03*
X1520034Y124576D03*
X1521087Y130670D03*
X1521082Y137756D03*
X1527876Y939439D03*
X1537720Y116496D03*
Y109410D03*
Y102323D03*
Y130670D03*
Y123583D03*
Y137756D03*
X1542761Y236611D03*
X1545261D03*
X1542463Y248891D03*
X1544963D03*
X1541534Y322850D03*
X1547761Y236611D03*
X1547463Y248891D03*
X1547972Y304906D03*
X1556151Y318596D03*
X1556294Y327814D03*
X1556437Y332022D03*
X1556380Y336917D03*
X1556498Y340958D03*
X1556353Y345636D03*
X1556429Y389154D03*
Y396240D03*
X1557708Y404911D03*
X1556662Y412571D03*
X1557849Y426299D03*
X1558160Y445847D03*
X1556429Y467539D03*
Y474626D03*
X1556690Y480828D03*
X1558640Y498834D03*
X1556429Y518760D03*
Y511673D03*
Y525847D03*
X1562385Y598400D03*
Y602400D03*
Y594400D03*
Y614400D03*
Y606400D03*
X1574851Y91951D03*
X1574845Y338843D03*
X1574540Y389154D03*
Y396240D03*
Y403327D03*
Y410413D03*
Y417500D03*
Y424586D03*
Y438760D03*
Y431673D03*
Y445847D03*
Y467539D03*
Y474626D03*
Y488799D03*
Y481713D03*
Y495886D03*
Y511673D03*
Y518760D03*
Y540020D03*
Y525847D03*
Y532933D03*
Y547106D03*
Y554193D03*
Y602205D03*
Y595118D03*
X1593204Y102249D03*
X1585204D03*
X1589204D03*
X1586504Y195176D03*
X1594304D03*
X1589004D03*
X1591504D03*
X1586364Y203393D03*
X1588864D03*
X1595052Y206838D03*
X1592552D03*
X1593290Y339876D03*
X1597006Y290417D03*
X1599527Y392718D03*
Y408718D03*
Y400718D03*
Y404718D03*
Y412718D03*
X1621972Y102323D03*
X1622224Y109410D03*
Y116496D03*
X1622396Y124576D03*
X1623449Y130670D03*
X1623444Y137756D03*
X1640082Y116496D03*
Y109410D03*
Y102323D03*
Y130670D03*
Y123583D03*
Y137756D03*
X1644825Y248891D03*
X1632230Y330400D03*
X1645123Y236611D03*
X1650123D03*
X1647623D03*
X1647325Y248891D03*
X1649825D03*
X1655555Y430760D03*
X1655576Y433570D03*
X1655392Y437072D03*
X1655433Y439963D03*
X1655677Y443180D03*
X1655697Y454744D03*
X1655639Y452018D03*
X1645465Y466027D03*
X1645607Y475262D03*
Y489435D03*
Y482666D03*
X1645423Y495088D03*
X1646158Y514608D03*
X1646080Y522134D03*
X1645465Y509626D03*
X1646562Y535677D03*
X1646723Y529136D03*
X1645465Y559665D03*
X1645846Y565574D03*
X1645493Y574338D03*
X1645592Y616358D03*
X1677213Y91951D03*
X1663760Y410394D03*
Y403307D03*
X1663576Y458406D03*
Y465492D03*
Y472579D03*
Y479665D03*
Y486752D03*
Y493839D03*
Y523799D03*
Y516713D03*
Y509626D03*
Y537973D03*
Y530886D03*
Y559665D03*
Y566752D03*
Y580925D03*
Y588012D03*
Y573839D03*
Y602185D03*
Y595099D03*
Y616358D03*
Y609272D03*
X1695566Y102249D03*
X1687566D03*
X1691566D03*
X1691366Y195176D03*
X1688866D03*
X1691226Y203393D03*
X1688726D03*
X1691117Y321649D03*
X1696666Y195176D03*
X1693866D03*
X1697414Y206838D03*
X1694914D03*
X1698839Y564843D03*
X1724334Y102323D03*
X1724586Y109410D03*
Y116496D03*
X1724758Y124576D03*
X1725811Y130670D03*
X1725806Y137756D03*
X1715705Y328692D03*
X1712734Y340534D03*
X1742336Y-87777D03*
X1739311Y-86371D03*
X1734826Y376499D03*
X1745589Y-87777D03*
X1742351Y-85262D03*
X1745604D03*
X1742444Y102323D03*
Y116496D03*
Y109410D03*
Y130670D03*
Y123583D03*
Y137756D03*
X1752485Y236611D03*
X1749985D03*
X1747485D03*
X1747187Y248891D03*
X1749687D03*
X1752187D03*
X1747561Y385161D03*
X1758583Y1581027D03*
X1750685Y1618504D03*
X1756422Y1640303D03*
X1770680Y926322D03*
X1763818Y926241D03*
X1765294Y1575434D03*
X1759092Y1588137D03*
X1767142Y1588219D03*
X1764422Y1640303D03*
X1779575Y91951D03*
X1790533Y303750D03*
X1783028Y408240D03*
X1785528D03*
X1780528D03*
X1783107Y424240D03*
X1780646Y420393D03*
X1785646D03*
X1783146D03*
X1783107Y426740D03*
X1780397Y1237469D03*
Y1230569D03*
Y1228069D03*
Y1234969D03*
Y1241869D03*
Y1244369D03*
Y1248769D03*
Y1251269D03*
X1776422Y1640303D03*
X1804667Y-47581D03*
X1804993Y297591D03*
X1807692Y-49001D03*
X1810945Y-48987D03*
X1807707Y-46486D03*
X1810960Y-46472D03*
X1817439Y447101D03*
G54D30*
X106586Y1204932D03*
X563673D03*
X1020434Y1205579D03*
X1477846Y1204932D03*
G54D38*
X190325Y368760D03*
Y455492D03*
Y503760D03*
Y583957D03*
Y636752D03*
X647411Y368760D03*
Y455492D03*
Y503760D03*
Y583957D03*
Y636752D03*
X1104498Y368760D03*
Y455492D03*
Y503760D03*
Y583957D03*
Y636752D03*
X1561585Y368760D03*
Y455492D03*
Y503760D03*
Y583957D03*
Y636752D03*
G54D43*
X515573Y692515D03*
X518299Y692384D03*
X520799D03*
X529493Y692443D03*
Y697443D03*
Y699943D03*
X529501Y702622D03*
X526993Y692443D03*
X529493Y694943D03*
X524493Y692443D03*
X1809078Y2165771D03*
X1806706Y2180760D03*
X1812366Y2063809D03*
X1822066Y2054109D03*
X1812366D03*
X1813087Y2087512D03*
X1825427Y2104853D03*
X1817378Y2165771D03*
X1815006Y2180760D03*
X1841295Y2065122D03*
X1832995D03*
X1833649Y2057507D03*
X1830872Y2083503D03*
X1840875Y2083215D03*
X1837649Y2072324D03*
X1829349D03*
X1833727Y2104853D03*
X1835862Y2121040D03*
X1833506Y2185252D03*
X1852032Y2052576D03*
X1854559Y2077931D03*
X1851762Y2121040D03*
X1854796Y2170548D03*
X1846496D03*
X1855978Y2185118D03*
X1847678D03*
X1859032Y2052576D03*
X1870505Y2064156D03*
X1860338Y2071384D03*
X1874505Y2078973D03*
X1860234Y2157701D03*
X1867072Y2174962D03*
X1864547Y2185020D03*
X1890039Y2066092D03*
X1878805Y2064156D03*
X1886128Y2075919D03*
X1882805Y2078973D03*
X1876497Y2070684D03*
X1884535Y2155415D03*
X1882972Y2174962D03*
X1882111Y2179074D03*
X1874932Y2180585D03*
X1881852Y2196600D03*
X1886699Y2183170D03*
X1876697D03*
X1905939Y2066092D03*
X1893118Y2054585D03*
X1905944Y2055424D03*
X1898342Y2062143D03*
X1901295Y2072745D03*
X1892835Y2155415D03*
X1902872Y2178531D03*
X1894572D03*
X1893087Y2168011D03*
X1896403Y2185019D03*
X1917195Y2072745D03*
X1917550Y2158451D03*
X1909250D03*
X1922010Y2151829D03*
X1913710D03*
X1921855Y2172152D03*
X1936295Y2074343D03*
X1935195Y2155918D03*
X1936377Y2163810D03*
X1924735Y2178131D03*
X1936212Y2173508D03*
X1930155Y2172152D03*
X1931738Y2182647D03*
X1923438D03*
X1941040Y2070124D03*
X1951095Y2155918D03*
X1946077Y2163810D03*
X1969128Y2161283D03*
X1959428D03*
X1969128Y2151583D03*
X1959428D03*
G54D51*
X909360Y230906D03*
Y274606D03*
G54D22*
X51043Y144095D03*
X57933Y66811D03*
X160295D03*
X153405Y144095D03*
X183435Y630650D03*
X190325Y374862D03*
X262657Y66811D03*
X255767Y144095D03*
X279360Y630650D03*
X286250Y374862D03*
X358129Y144095D03*
X365019Y66811D03*
X508130Y144095D03*
X515020Y66811D03*
X617382D03*
X610492Y144095D03*
X647411Y374862D03*
X640521Y630650D03*
X719744Y66811D03*
X712854Y144095D03*
X736446Y630650D03*
X743336Y374862D03*
X815216Y144095D03*
X822106Y66811D03*
X972106D03*
X965216Y144095D03*
X1074468Y66811D03*
X1067578Y144095D03*
X1104498Y374862D03*
X1097608Y630650D03*
X1169940Y144095D03*
X1176830Y66811D03*
X1200423Y374862D03*
X1193533Y630650D03*
X1272302Y144095D03*
X1279192Y66811D03*
X1429193D03*
X1422303Y144095D03*
X1531555Y66811D03*
X1524665Y144095D03*
X1561585Y374862D03*
X1554695Y630650D03*
X1627027Y144095D03*
X1633917Y66811D03*
X1657510Y374862D03*
X1650620Y630650D03*
X1736279Y66811D03*
X1729389Y144095D03*
G54D25*
X46248Y1760941D03*
Y1750941D03*
Y1806941D03*
Y1796941D03*
X143208Y1084547D03*
Y1092027D03*
X146948Y1077066D03*
Y1084547D03*
Y1092027D03*
X143208Y1095767D03*
X146948D03*
X143208Y1110728D03*
Y1118208D03*
X146948Y1110728D03*
Y1118208D03*
X146949Y1166830D03*
X154429Y1073326D03*
X161909D03*
X154429Y1092027D03*
X161909Y1077066D03*
X165649Y1080807D03*
Y1088287D03*
X161909D03*
Y1092027D03*
X154429Y1077066D03*
X158169Y1080807D03*
X150689D03*
X158169Y1084547D03*
X150689D03*
X158169Y1088287D03*
X154429D03*
X150689D03*
X165649Y1084547D03*
X158169Y1099507D03*
X150689D03*
X158169Y1103247D03*
X150689D03*
X161909Y1095767D03*
X165649Y1099507D03*
Y1103247D03*
X154429Y1106988D03*
X150689D03*
X154429Y1095767D03*
X158169Y1110728D03*
Y1114468D03*
X154429D03*
X150689D03*
X158169Y1129429D03*
X165649Y1166830D03*
Y1170570D03*
Y1178050D03*
Y1174310D03*
X163779Y1213582D03*
X160039D03*
X214271Y1114468D03*
X238582Y1078936D03*
X242322Y1082677D03*
X238582Y1097637D03*
X246062Y1254724D03*
X238582D03*
Y1250984D03*
X234842Y1247243D03*
X242322Y1243503D03*
Y1247243D03*
X246062Y1250984D03*
X249803Y1082677D03*
X257283D03*
X249803Y1101377D03*
X253543Y1250984D03*
Y1254724D03*
X249803Y1247243D03*
X253543Y1239763D03*
X249803D03*
X257283Y1247243D03*
X261023Y1250984D03*
Y1239763D03*
Y1254724D03*
X279724Y1082677D03*
Y1086417D03*
X275984Y1078936D03*
X264763Y1082677D03*
X275984Y1097637D03*
X274114Y1121948D03*
X277854Y1133169D03*
Y1125688D03*
X274114Y1204232D03*
X279724Y1247243D03*
X272244Y1243503D03*
Y1247243D03*
X264763D03*
X268503Y1250984D03*
X264763Y1243503D03*
X272244Y1239763D03*
X275984Y1250984D03*
X279724Y1243503D03*
X268503Y1254724D03*
X275984D03*
X294684Y1082677D03*
Y1090157D03*
X294685Y1086417D03*
X290944Y1078936D03*
X287204Y1082677D03*
X283464Y1093897D03*
X290944Y1097637D03*
X294685Y1247243D03*
Y1243503D03*
X283464Y1250984D03*
X287204Y1247243D03*
Y1243503D03*
Y1239763D03*
X290944Y1250984D03*
X283464Y1254724D03*
X290944D03*
X302164Y1082677D03*
X302165Y1086417D03*
X309644Y1082677D03*
X309645Y1086417D03*
X298425Y1097637D03*
X305905D03*
X300295Y1155610D03*
X309645Y1247243D03*
Y1243503D03*
X298425Y1250984D03*
X302165Y1247243D03*
Y1243503D03*
Y1239763D03*
X305905Y1250984D03*
X298425Y1254724D03*
X305905D03*
X320866Y1086417D03*
X317126D03*
X317125Y1082677D03*
X324606Y1086417D03*
X320866Y1093897D03*
X324606D03*
Y1105117D03*
Y1097637D03*
X320866Y1105117D03*
Y1097637D03*
X313385D03*
X324606Y1112598D03*
Y1120078D03*
X320866Y1112598D03*
Y1120078D03*
X317125Y1108858D03*
X320866Y1127558D03*
Y1135039D03*
X322736Y1140649D03*
X324606Y1127558D03*
Y1135039D03*
X326476Y1140649D03*
X322736Y1155610D03*
X326476Y1148129D03*
Y1155610D03*
X322736Y1148129D03*
X326476Y1170570D03*
Y1178051D03*
Y1185531D03*
X320866Y1250984D03*
X313385D03*
X317125Y1247243D03*
Y1243503D03*
X313385Y1254724D03*
X317125Y1239763D03*
X320866Y1254724D03*
X333286Y1728583D03*
Y1738583D03*
X333212Y1774624D03*
Y1784624D03*
X438162Y1348187D03*
Y1360099D03*
Y1384297D03*
Y1372385D03*
X450402Y1348187D03*
Y1360099D03*
Y1384297D03*
Y1372385D03*
Y1396583D03*
Y1408495D03*
X462642Y1348187D03*
X474882D03*
X462642Y1360099D03*
X474882D03*
X462642Y1384297D03*
X474882D03*
X462642Y1372385D03*
X474882D03*
Y1396583D03*
X462642D03*
X474882Y1408495D03*
X462642D03*
X487122Y1348187D03*
Y1360099D03*
Y1372385D03*
Y1384297D03*
Y1396583D03*
Y1408495D03*
X499362Y1348187D03*
Y1360099D03*
Y1372385D03*
Y1384297D03*
Y1396583D03*
Y1408495D03*
X511602Y1348187D03*
Y1360099D03*
Y1372385D03*
Y1384297D03*
Y1396583D03*
Y1408495D03*
X536082Y1348187D03*
X523842D03*
X536082Y1360099D03*
X523842D03*
Y1384297D03*
Y1372385D03*
X536082Y1384297D03*
Y1372385D03*
Y1396583D03*
X523842D03*
X536082Y1408495D03*
X523842D03*
X548322Y1348187D03*
Y1360099D03*
Y1384297D03*
Y1372385D03*
Y1396583D03*
Y1408495D03*
X560562Y1348187D03*
Y1360099D03*
Y1384297D03*
Y1372385D03*
Y1396583D03*
Y1408495D03*
X600295Y1084547D03*
Y1092027D03*
X604035Y1077066D03*
Y1084547D03*
Y1092027D03*
X600295Y1095767D03*
X604035D03*
X600295Y1110728D03*
Y1118208D03*
X604035Y1110728D03*
Y1118208D03*
X604036Y1166830D03*
X611516Y1073326D03*
X618996D03*
Y1088287D03*
Y1092027D03*
X611516Y1077066D03*
X615256Y1080807D03*
X607776D03*
X615256Y1084547D03*
X607776D03*
X615256Y1088287D03*
X611516D03*
X607776D03*
X611516Y1092027D03*
X618996Y1077066D03*
X611516Y1106988D03*
X607776D03*
X611516Y1095767D03*
X615256Y1099507D03*
X607776D03*
X615256Y1103247D03*
X607776D03*
X618996Y1095767D03*
X615256Y1110728D03*
Y1114468D03*
X611516D03*
X607776D03*
X615256Y1129429D03*
X617126Y1213582D03*
X620866D03*
X620083Y1728286D03*
Y1738286D03*
X619711Y1775438D03*
Y1785438D03*
X626476Y1088287D03*
X622736Y1080807D03*
Y1084547D03*
Y1088287D03*
Y1099507D03*
Y1103247D03*
Y1166830D03*
Y1170570D03*
Y1174310D03*
Y1178050D03*
X636288Y1372385D03*
Y1384297D03*
Y1396583D03*
X624048D03*
X636288Y1408495D03*
X624048D03*
X648528Y1348187D03*
Y1360099D03*
Y1372385D03*
Y1384297D03*
Y1396583D03*
Y1408495D03*
X660768Y1348187D03*
Y1360099D03*
Y1372385D03*
Y1384297D03*
Y1396583D03*
Y1408495D03*
X671358Y1114468D03*
X673008Y1348187D03*
X685248D03*
X673008Y1360099D03*
X685248D03*
Y1372385D03*
Y1384297D03*
X673008Y1372385D03*
Y1384297D03*
X685248Y1396583D03*
X673008D03*
X685248Y1408495D03*
X673008D03*
X695669Y1078936D03*
X699409Y1082677D03*
X695669Y1097637D03*
X699409Y1247243D03*
Y1243503D03*
X691929Y1247243D03*
X695669Y1250984D03*
Y1254724D03*
X697488Y1348187D03*
Y1360099D03*
Y1384297D03*
Y1372385D03*
Y1396583D03*
Y1408495D03*
X706890Y1082677D03*
X714370D03*
X706890Y1101377D03*
X703149Y1254724D03*
Y1250984D03*
X718110D03*
Y1239763D03*
X714370Y1247243D03*
X710630Y1254724D03*
Y1250984D03*
Y1239763D03*
X706890Y1247243D03*
Y1239763D03*
X718110Y1254724D03*
X709728Y1348187D03*
Y1360099D03*
Y1384297D03*
Y1372385D03*
Y1396583D03*
Y1408495D03*
X721850Y1082677D03*
X733071Y1078936D03*
Y1097637D03*
X731201Y1121948D03*
X734941Y1125688D03*
Y1133169D03*
X731201Y1204232D03*
X729331Y1243503D03*
X721850D03*
X729331Y1239763D03*
Y1247243D03*
X733071Y1250984D03*
Y1254724D03*
X725590D03*
Y1250984D03*
X721850Y1247243D03*
X734208Y1348187D03*
X721968D03*
X734208Y1360099D03*
X721968D03*
Y1384297D03*
Y1372385D03*
X734208D03*
Y1384297D03*
X721968Y1396489D03*
X734208D03*
X721968Y1408401D03*
X734208D03*
X744291Y1082677D03*
X748031Y1078936D03*
X736811Y1086417D03*
Y1082677D03*
X748031Y1097637D03*
X740551Y1093897D03*
X736811Y1243503D03*
Y1247243D03*
X744291Y1243503D03*
Y1239763D03*
X748031Y1254724D03*
Y1250984D03*
X744291Y1247243D03*
X740551Y1254724D03*
Y1250984D03*
X746448Y1348187D03*
Y1360099D03*
Y1372385D03*
Y1384297D03*
X759251Y1082677D03*
X751772Y1086417D03*
X751771Y1090157D03*
Y1082677D03*
X759252Y1086417D03*
X766732D03*
X766731Y1082677D03*
X762992Y1097637D03*
X755512D03*
X757382Y1155610D03*
X755512Y1250984D03*
Y1254724D03*
X759252Y1247243D03*
Y1243503D03*
X762992Y1250984D03*
Y1254724D03*
X766732Y1247243D03*
Y1243503D03*
X759252Y1239763D03*
X751772Y1247243D03*
Y1243503D03*
X758688Y1348187D03*
Y1360099D03*
Y1372385D03*
Y1384297D03*
X774213Y1086417D03*
X774212Y1082677D03*
X781693Y1086417D03*
X777953D03*
X770472Y1097637D03*
X777953Y1093897D03*
Y1105117D03*
X781693Y1093897D03*
Y1097637D03*
X777953D03*
X781693Y1105117D03*
Y1112598D03*
X777953Y1120078D03*
X781693D03*
X774212Y1108858D03*
X777953Y1112598D03*
X783563Y1140649D03*
X779823D03*
X781693Y1127558D03*
X777953D03*
Y1135039D03*
X781693D03*
X783563Y1155610D03*
Y1148129D03*
X779823Y1155610D03*
Y1148129D03*
X783563Y1170570D03*
Y1185531D03*
Y1178051D03*
X770472Y1250984D03*
Y1254724D03*
X777953Y1250984D03*
X774212Y1247243D03*
Y1243503D03*
Y1239763D03*
X777953Y1254724D03*
X770928Y1348187D03*
Y1360099D03*
X907279Y1738990D03*
Y1728990D03*
X907073Y1776014D03*
Y1786014D03*
X1057381Y1092027D03*
Y1084547D03*
Y1095767D03*
Y1118208D03*
Y1110728D03*
X1068602Y1073326D03*
X1072342Y1088287D03*
Y1084547D03*
Y1080807D03*
X1061121Y1092027D03*
X1068602D03*
X1064862Y1088287D03*
X1068602D03*
X1061121Y1084547D03*
X1064862D03*
Y1080807D03*
X1061121Y1077066D03*
X1068602D03*
X1072342Y1099507D03*
Y1103247D03*
X1061121Y1095767D03*
X1068602D03*
X1064862Y1106988D03*
X1068602D03*
X1064862Y1103247D03*
Y1099507D03*
X1072342Y1114468D03*
Y1110728D03*
X1061121Y1118208D03*
X1064862Y1114468D03*
X1068602D03*
X1061121Y1110728D03*
X1072342Y1129429D03*
X1061122Y1166830D03*
X1074212Y1213582D03*
X1076082Y1073326D03*
X1083562Y1088287D03*
X1079822D03*
Y1084547D03*
Y1080807D03*
X1076082Y1092027D03*
Y1088287D03*
Y1077066D03*
X1079822Y1103247D03*
Y1099507D03*
X1076082Y1095767D03*
X1079822Y1170570D03*
Y1166830D03*
Y1174310D03*
Y1178050D03*
X1077952Y1213582D03*
X1128444Y1114468D03*
X1152755Y1078936D03*
X1156495Y1082677D03*
X1152755Y1097637D03*
Y1254724D03*
Y1250984D03*
X1149015Y1247243D03*
X1156495Y1243503D03*
Y1247243D03*
X1163976Y1082677D03*
X1171456D03*
X1163976Y1101377D03*
Y1239763D03*
Y1247243D03*
X1167716Y1239763D03*
Y1250984D03*
Y1254724D03*
X1171456Y1247243D03*
X1160235Y1250984D03*
Y1254724D03*
X1178936Y1082677D03*
X1188287Y1121948D03*
Y1204232D03*
X1175196Y1254724D03*
Y1239763D03*
Y1250984D03*
X1178936Y1247243D03*
X1182676Y1250984D03*
Y1254724D03*
X1186417Y1247243D03*
Y1239763D03*
X1178936Y1243503D03*
X1186417D03*
X1190157Y1078936D03*
X1201377Y1082677D03*
X1205117Y1078936D03*
X1193897Y1082677D03*
Y1086417D03*
X1190157Y1097637D03*
X1197637Y1093897D03*
X1205117Y1097637D03*
X1192027Y1133169D03*
Y1125688D03*
X1190157Y1254724D03*
Y1250984D03*
X1197637D03*
Y1254724D03*
X1201377Y1247243D03*
X1205117Y1250984D03*
Y1254724D03*
X1201377Y1239763D03*
Y1243503D03*
X1193897Y1247243D03*
Y1243503D03*
X1216337Y1082677D03*
X1216338Y1086417D03*
X1208857Y1082677D03*
X1208858Y1086417D03*
X1208857Y1090157D03*
X1212598Y1097637D03*
X1220078D03*
X1214468Y1155610D03*
X1212598Y1250984D03*
Y1254724D03*
X1216338Y1247243D03*
Y1243503D03*
X1220078Y1250984D03*
Y1254724D03*
X1216338Y1239763D03*
X1208858Y1247243D03*
Y1243503D03*
X1223817Y1082677D03*
X1223818Y1086417D03*
X1231298Y1082677D03*
X1235039Y1086417D03*
X1231299D03*
X1227558Y1097637D03*
X1235039Y1093897D03*
Y1097637D03*
Y1105117D03*
X1231298Y1108858D03*
X1235039Y1112598D03*
Y1120078D03*
X1236909Y1140649D03*
X1235039Y1127558D03*
Y1135039D03*
X1236909Y1148129D03*
Y1155610D03*
X1223818Y1247243D03*
Y1243503D03*
X1227558Y1250984D03*
Y1254724D03*
X1235039Y1250984D03*
X1231298Y1247243D03*
Y1243503D03*
Y1239763D03*
X1235039Y1254724D03*
X1238779Y1086417D03*
Y1093897D03*
Y1097637D03*
Y1105117D03*
Y1112598D03*
Y1120078D03*
X1240649Y1140649D03*
X1238779Y1127558D03*
Y1135039D03*
X1240649Y1148129D03*
Y1155610D03*
Y1170570D03*
Y1178051D03*
Y1185531D03*
X1514468Y1084547D03*
Y1092027D03*
Y1095767D03*
Y1110728D03*
Y1118208D03*
X1525689Y1073326D03*
Y1077066D03*
X1518208D03*
X1529429Y1080807D03*
X1521949D03*
X1529429Y1084547D03*
X1521949D03*
X1518208D03*
X1529429Y1088287D03*
X1525689D03*
X1521949D03*
X1525689Y1092027D03*
X1518208D03*
X1521949Y1103247D03*
X1525689Y1106988D03*
X1521949D03*
X1525689Y1095767D03*
X1518208D03*
X1529429Y1099507D03*
X1521949D03*
X1529429Y1103247D03*
Y1110728D03*
X1518208D03*
X1529429Y1114468D03*
X1525689D03*
X1521949D03*
X1518208Y1118208D03*
X1529429Y1129429D03*
X1518209Y1166830D03*
X1533169Y1073326D03*
X1540649Y1088287D03*
X1533169Y1077066D03*
X1536909Y1080807D03*
Y1084547D03*
Y1088287D03*
X1533169D03*
Y1092027D03*
Y1095767D03*
X1536909Y1099507D03*
Y1103247D03*
Y1166830D03*
Y1170570D03*
Y1174310D03*
X1535039Y1176180D03*
Y1213582D03*
X1531299D03*
X1585531Y1114468D03*
X1609842Y1078936D03*
Y1097637D03*
Y1254724D03*
Y1250984D03*
X1606102Y1247243D03*
X1613582Y1082677D03*
X1621063D03*
Y1101377D03*
X1613582Y1243503D03*
Y1247243D03*
X1621063Y1239763D03*
Y1247243D03*
X1624803Y1239763D03*
Y1250984D03*
Y1254724D03*
X1617322Y1250984D03*
Y1254724D03*
X1636023Y1082677D03*
X1628543D03*
X1632283Y1254724D03*
X1628543Y1247243D03*
X1632283Y1239763D03*
Y1250984D03*
X1636023Y1247243D03*
X1639763Y1250984D03*
Y1254724D03*
X1643504Y1247243D03*
Y1239763D03*
X1636023Y1243503D03*
X1643504D03*
X1658464Y1082677D03*
X1650984D03*
Y1086417D03*
X1647244Y1078936D03*
Y1097637D03*
X1654724Y1093897D03*
X1645374Y1121948D03*
X1649114Y1133169D03*
Y1125688D03*
X1645374Y1204232D03*
X1647244Y1254724D03*
Y1250984D03*
X1654724D03*
Y1254724D03*
X1658464Y1247243D03*
Y1239763D03*
Y1243503D03*
X1650984Y1247243D03*
Y1243503D03*
X1662204Y1078936D03*
X1673424Y1082677D03*
X1673425Y1086417D03*
X1665944Y1082677D03*
X1665945Y1086417D03*
X1665944Y1090157D03*
X1662204Y1097637D03*
X1669685D03*
X1671555Y1155610D03*
X1665945Y1247243D03*
Y1243503D03*
X1662204Y1250984D03*
Y1254724D03*
X1669685Y1250984D03*
Y1254724D03*
X1673425Y1247243D03*
Y1243503D03*
Y1239763D03*
X1680904Y1082677D03*
X1680905Y1086417D03*
X1688385Y1082677D03*
X1692126Y1086417D03*
X1688386D03*
X1677165Y1097637D03*
X1684645D03*
X1692126Y1093897D03*
Y1097637D03*
Y1105117D03*
X1688385Y1108858D03*
X1692126Y1112598D03*
Y1120078D03*
Y1127558D03*
Y1135039D03*
X1684645Y1250984D03*
Y1254724D03*
X1692126Y1250984D03*
X1688385Y1247243D03*
Y1243503D03*
Y1239763D03*
X1692126Y1254724D03*
X1677165Y1250984D03*
Y1254724D03*
X1680905Y1247243D03*
Y1243503D03*
X1695866Y1086417D03*
Y1093897D03*
Y1097637D03*
Y1105117D03*
Y1112598D03*
Y1120078D03*
X1697736Y1140649D03*
X1693996D03*
X1695866Y1127558D03*
Y1135039D03*
X1697736Y1148129D03*
X1693996D03*
X1697736Y1155610D03*
X1693996D03*
X1697736Y1170570D03*
Y1178051D03*
Y1185531D03*
G54D36*
X145078Y1250984D03*
X148818Y1243503D03*
Y1250984D03*
X145078Y1243503D03*
X161909Y1125688D03*
X158169Y1151869D03*
X154429D03*
Y1166830D03*
X160039Y1194881D03*
Y1202362D03*
Y1209842D03*
Y1217322D03*
X156299Y1250984D03*
X160039Y1247243D03*
X152559D03*
X156299Y1239763D03*
X163779Y1250984D03*
X156299Y1254724D03*
X163779D03*
X178740Y1075196D03*
X171259D03*
X178740Y1078936D03*
X174999Y1086417D03*
Y1082677D03*
X171259Y1078936D03*
X182480Y1086417D03*
Y1082677D03*
X171259Y1097637D03*
X173129Y1129428D03*
X169389D03*
X180610Y1170570D03*
X174999Y1209842D03*
X167519Y1221062D03*
X182480Y1236023D03*
Y1232283D03*
X174999D03*
Y1236023D03*
X182480Y1239763D03*
Y1247243D03*
X178740Y1250984D03*
Y1239763D03*
X174999Y1243503D03*
X178740Y1254724D03*
X171259D03*
X167519Y1247243D03*
X186220Y1075196D03*
X193700D03*
X189960Y1086417D03*
Y1082677D03*
X193700Y1078936D03*
X186220D03*
X197440Y1086417D03*
Y1082677D03*
X188090Y1178051D03*
Y1193011D03*
X197440Y1236023D03*
Y1232283D03*
X189960Y1236023D03*
Y1232283D03*
X197440Y1247243D03*
X193700Y1254724D03*
X186220D03*
X189960Y1239763D03*
X186220Y1250984D03*
X189960Y1247243D03*
X193700Y1250984D03*
X201181Y1075196D03*
X208661D03*
Y1078936D03*
X212401Y1086417D03*
Y1082677D03*
X204921Y1086417D03*
Y1082677D03*
X201181Y1078936D03*
X204921Y1232283D03*
X212401D03*
Y1236023D03*
X204921D03*
X208661Y1250984D03*
X201181Y1239763D03*
X212401D03*
Y1247243D03*
X201181Y1254724D03*
X204921Y1239763D03*
X201181Y1250984D03*
X204921Y1247243D03*
X208661Y1254724D03*
X213969Y1445013D03*
Y1456013D03*
X223622Y1075196D03*
X231102D03*
X216141D03*
X227362Y1086417D03*
Y1082677D03*
X219881Y1086417D03*
Y1082677D03*
X223622Y1078936D03*
X231102D03*
X216141D03*
X219881Y1232283D03*
Y1236023D03*
X227362Y1232283D03*
Y1236023D03*
X223622Y1254724D03*
X231102D03*
X227362Y1247243D03*
X219881Y1239763D03*
X223622Y1250984D03*
X219881Y1247243D03*
X231102Y1250984D03*
X227362Y1239763D03*
X216141Y1250984D03*
Y1254724D03*
X227249Y1445013D03*
Y1456013D03*
X246062Y1221062D03*
X234842Y1239763D03*
Y1243503D03*
X242322Y1239763D03*
X257283Y1101377D03*
X249803Y1221062D03*
X253543D03*
X261023D03*
X257283D03*
X249803Y1243503D03*
X257283D03*
X272244Y1101377D03*
X279724D03*
X264763D03*
X277854Y1121948D03*
Y1129429D03*
X264763Y1221062D03*
X279724Y1239763D03*
X275984D03*
X264763D03*
X287204Y1086417D03*
X283464Y1097637D03*
X294684Y1101377D03*
X289074Y1144389D03*
X294685Y1239763D03*
X302164Y1090157D03*
X305904D03*
X309644D03*
X302165Y1101377D03*
X309645D03*
Y1123818D03*
X309644Y1108858D03*
X309645Y1116338D03*
Y1131299D03*
X307775Y1140649D03*
X298425Y1135039D03*
Y1127558D03*
X300295Y1151869D03*
Y1144389D03*
X307775Y1148129D03*
Y1155610D03*
Y1159350D03*
X305905Y1239763D03*
X317125Y1090157D03*
X317126Y1105117D03*
X317125Y1101377D03*
X318996Y1136909D03*
X317125Y1131299D03*
X318996Y1144389D03*
Y1151869D03*
X322736Y1166830D03*
X318996Y1159350D03*
Y1166830D03*
X326476D03*
X318996Y1189271D03*
Y1181791D03*
Y1174310D03*
X317125Y1198621D03*
X320866D03*
X313385Y1202362D03*
X324606Y1198621D03*
X317125Y1202362D03*
Y1206102D03*
Y1213582D03*
Y1217322D03*
Y1209842D03*
X324606Y1213582D03*
X313385Y1209842D03*
X320866Y1213582D03*
X324606Y1206102D03*
X313385Y1217322D03*
X320866Y1243503D03*
X313385Y1239763D03*
X320866Y1247243D03*
X324606D03*
X602165Y1243503D03*
Y1250984D03*
X618996Y1125688D03*
Y1133169D03*
X615256Y1151869D03*
X611516D03*
Y1166830D03*
X617126Y1202362D03*
Y1194881D03*
Y1209842D03*
Y1217322D03*
X613386Y1239763D03*
X620866Y1254724D03*
Y1250984D03*
X617126Y1247243D03*
X609646D03*
X613386Y1254724D03*
Y1250984D03*
X605905Y1243503D03*
Y1254724D03*
Y1250984D03*
X626476Y1073326D03*
X635827Y1075196D03*
X628346D03*
X626476Y1077066D03*
X628346Y1078936D03*
X635827D03*
X632086Y1082677D03*
Y1086417D03*
X626476Y1099507D03*
X628346Y1097637D03*
X630216Y1129428D03*
X626476D03*
X630216Y1136909D03*
X626476D03*
X632086Y1209842D03*
X624606Y1221062D03*
X632086Y1232283D03*
Y1236023D03*
Y1243503D03*
X635827Y1239763D03*
Y1254724D03*
Y1250984D03*
X628346Y1254724D03*
X624606Y1247243D03*
X643307Y1075196D03*
X650787D03*
Y1078936D03*
X647047Y1082677D03*
Y1086417D03*
X643307Y1078936D03*
X639567Y1086417D03*
Y1082677D03*
X637697Y1170570D03*
X645177Y1178051D03*
Y1193011D03*
X639567Y1236023D03*
X647047D03*
X639567Y1232283D03*
X647047D03*
X639567Y1239763D03*
Y1247243D03*
X647047Y1239763D03*
X650787Y1254724D03*
Y1250984D03*
X647047Y1247243D03*
X643307Y1254724D03*
Y1250984D03*
X658268Y1075196D03*
X665748D03*
X669488Y1086417D03*
X665748Y1078936D03*
X669488Y1082677D03*
X654527D03*
Y1086417D03*
X662008Y1082677D03*
Y1086417D03*
X658268Y1078936D03*
X654527Y1236023D03*
Y1232283D03*
Y1247243D03*
X662008Y1239763D03*
X658268D03*
X669488D03*
X665748Y1250984D03*
Y1254724D03*
X669488Y1247243D03*
X662008D03*
X658268Y1254724D03*
Y1250984D03*
X680709Y1075196D03*
X673228D03*
X684449Y1082677D03*
Y1086417D03*
X673228Y1078936D03*
X680709D03*
X676968Y1082677D03*
Y1086417D03*
Y1239763D03*
X680709Y1254724D03*
Y1250984D03*
X676968Y1247243D03*
X673228Y1254724D03*
Y1250984D03*
X684449Y1247243D03*
Y1239763D03*
X688189Y1075196D03*
Y1078936D03*
Y1254724D03*
Y1250984D03*
X699409Y1239763D03*
X691929D03*
Y1243503D03*
X714370Y1101377D03*
X718110Y1228543D03*
Y1224803D03*
X714370Y1243503D03*
X706890D03*
X729331Y1101377D03*
X721850D03*
X734941Y1121948D03*
Y1129429D03*
X725590Y1228543D03*
X733071D03*
X721850Y1236023D03*
X733071Y1224803D03*
X721850Y1232283D03*
X725590Y1224803D03*
X729331Y1236023D03*
Y1232283D03*
X733071Y1239763D03*
X721850D03*
X744291Y1086417D03*
X740551Y1097637D03*
X736811Y1101377D03*
X746161Y1144389D03*
X744291Y1236023D03*
X736811Y1232283D03*
X744291D03*
X736811Y1236023D03*
X740551Y1224803D03*
Y1228543D03*
X736811Y1239763D03*
X766731Y1090157D03*
X759251D03*
X762991D03*
X751771Y1101377D03*
X759252D03*
X766732D03*
X766731Y1108858D03*
X766732Y1116338D03*
Y1123818D03*
X764862Y1140649D03*
X766732Y1131299D03*
X755512Y1127558D03*
Y1135039D03*
X764862Y1155610D03*
Y1148129D03*
X757382Y1144389D03*
Y1151869D03*
X764862Y1159350D03*
X762992Y1239763D03*
X751772D03*
X774212Y1090157D03*
Y1101377D03*
X774213Y1105117D03*
X774212Y1131299D03*
X776083Y1151869D03*
Y1144389D03*
X783563Y1166830D03*
X776083D03*
Y1159350D03*
X779823Y1166830D03*
X776083Y1174310D03*
Y1181791D03*
Y1196751D03*
X774212Y1198621D03*
Y1213582D03*
Y1206102D03*
X777953Y1243503D03*
X770472Y1239763D03*
X1059251Y1243503D03*
Y1250984D03*
X1072342Y1151869D03*
X1068602D03*
Y1166830D03*
X1074212Y1194881D03*
Y1202362D03*
Y1217322D03*
Y1209842D03*
X1070472Y1250984D03*
Y1254724D03*
X1066732Y1247243D03*
X1074212D03*
X1070472Y1239763D03*
X1062991Y1250984D03*
Y1254724D03*
Y1243503D03*
X1083562Y1073326D03*
Y1077066D03*
X1089172Y1082677D03*
Y1086417D03*
X1083562Y1099507D03*
Y1136909D03*
X1087302D03*
X1083562Y1129428D03*
X1087302D03*
X1076082Y1133169D03*
Y1125688D03*
X1089172Y1209842D03*
X1081692Y1221062D03*
X1089172Y1232283D03*
Y1236023D03*
X1077952Y1250984D03*
Y1254724D03*
X1081692Y1247243D03*
X1085432Y1254724D03*
X1089172Y1243503D03*
X1092913Y1075196D03*
X1107873D03*
X1100393D03*
X1092913Y1078936D03*
X1104133Y1086417D03*
Y1082677D03*
X1107873Y1078936D03*
X1100393D03*
X1096653Y1082677D03*
Y1086417D03*
X1094783Y1170570D03*
X1102263Y1178051D03*
Y1193011D03*
X1104133Y1236023D03*
Y1232283D03*
X1096653Y1236023D03*
Y1232283D03*
X1092913Y1250984D03*
Y1254724D03*
Y1239763D03*
X1100393Y1250984D03*
Y1254724D03*
X1104133Y1247243D03*
X1107873Y1250984D03*
Y1254724D03*
X1104133Y1239763D03*
X1096653Y1247243D03*
Y1239763D03*
X1115354Y1075196D03*
X1122834D03*
X1115354Y1078936D03*
X1119094Y1082677D03*
Y1086417D03*
X1122834Y1078936D03*
X1111613Y1082677D03*
Y1086417D03*
X1119094Y1232283D03*
X1111613D03*
X1119094Y1236023D03*
X1111613D03*
X1115354Y1250984D03*
Y1254724D03*
X1119094Y1247243D03*
X1122834Y1254724D03*
Y1250984D03*
X1115354Y1239763D03*
X1119094D03*
X1111613Y1247243D03*
X1130314Y1075196D03*
X1137795D03*
X1126574Y1086417D03*
Y1082677D03*
X1130314Y1078936D03*
X1134054Y1082677D03*
Y1086417D03*
X1137795Y1078936D03*
X1134054Y1236023D03*
Y1232283D03*
X1126574D03*
Y1236023D03*
Y1247243D03*
Y1239763D03*
X1130314Y1250984D03*
Y1254724D03*
X1134054Y1247243D03*
X1137795Y1250984D03*
Y1254724D03*
X1134054Y1239763D03*
X1145275Y1075196D03*
X1141535Y1082677D03*
Y1086417D03*
X1145275Y1078936D03*
X1141535Y1236023D03*
Y1232283D03*
Y1239763D03*
Y1247243D03*
X1149015Y1243503D03*
Y1239763D03*
X1156495D03*
X1145275Y1250984D03*
Y1254724D03*
X1171456Y1101377D03*
X1163976Y1243503D03*
X1171456D03*
X1178936Y1101377D03*
X1186417D03*
X1178936Y1239763D03*
X1201377Y1086417D03*
X1197637Y1097637D03*
X1193897Y1101377D03*
X1192027Y1121948D03*
Y1129429D03*
X1203247Y1144389D03*
X1190157Y1239763D03*
X1193897D03*
X1216337Y1090157D03*
X1220077D03*
X1216338Y1101377D03*
X1208857D03*
X1221948Y1140649D03*
X1212598Y1127558D03*
Y1135039D03*
X1221948Y1155610D03*
X1214468Y1151869D03*
Y1144389D03*
X1221948Y1148129D03*
Y1159350D03*
X1220078Y1239763D03*
X1208858D03*
X1223817Y1090157D03*
X1231298D03*
X1223818Y1101377D03*
X1231298D03*
X1231299Y1105117D03*
X1223817Y1108858D03*
X1223818Y1116338D03*
Y1123818D03*
X1233169Y1136909D03*
X1223818Y1131299D03*
X1231298D03*
X1233169Y1144389D03*
Y1151869D03*
X1236909Y1166830D03*
X1233169Y1159350D03*
Y1166830D03*
Y1189271D03*
Y1181791D03*
Y1174310D03*
Y1196751D03*
X1231298Y1198621D03*
Y1202362D03*
X1235039Y1198621D03*
X1227558Y1202362D03*
X1231298Y1206102D03*
Y1213582D03*
X1235039D03*
X1231298Y1209842D03*
X1227558D03*
X1231298Y1217322D03*
X1227558D03*
X1235039Y1243503D03*
X1227558Y1239763D03*
X1235039Y1247243D03*
X1243149Y1136909D03*
X1240649Y1166830D03*
X1238779Y1198621D03*
Y1206102D03*
Y1213582D03*
Y1247243D03*
X1511968Y1170570D03*
Y1178050D03*
X1529429Y1151869D03*
X1525689D03*
Y1166830D03*
X1516338Y1243503D03*
Y1250984D03*
X1527559D03*
Y1254724D03*
X1523819Y1247243D03*
X1527559Y1239763D03*
X1520078Y1250984D03*
Y1254724D03*
Y1243503D03*
X1540649Y1073326D03*
Y1077066D03*
X1546259Y1082677D03*
Y1086417D03*
X1540649Y1099507D03*
X1533169Y1125688D03*
X1544389Y1129428D03*
X1540649D03*
X1544389Y1136909D03*
X1533169Y1133169D03*
X1540649Y1136909D03*
X1531299Y1194881D03*
Y1202362D03*
Y1217322D03*
Y1209842D03*
X1546259D03*
X1538779Y1221062D03*
X1546259Y1232283D03*
Y1236023D03*
X1531299Y1247243D03*
X1535039Y1250984D03*
Y1254724D03*
X1538779Y1247243D03*
X1542519Y1254724D03*
X1546259Y1243503D03*
X1557480Y1075196D03*
X1550000D03*
X1561220Y1086417D03*
Y1082677D03*
X1557480Y1078936D03*
X1553740Y1082677D03*
Y1086417D03*
X1550000Y1078936D03*
X1551870Y1170570D03*
X1559350Y1178051D03*
Y1193011D03*
X1553740Y1232283D03*
Y1236023D03*
X1561220D03*
Y1232283D03*
X1550000Y1250984D03*
Y1254724D03*
Y1239763D03*
X1557480Y1250984D03*
Y1254724D03*
X1561220Y1247243D03*
Y1239763D03*
X1553740Y1247243D03*
Y1239763D03*
X1572441Y1075196D03*
X1564960D03*
Y1078936D03*
X1572441D03*
X1576181Y1082677D03*
Y1086417D03*
X1568700Y1082677D03*
Y1086417D03*
Y1236023D03*
Y1232283D03*
X1564960Y1250984D03*
Y1254724D03*
X1572441Y1250984D03*
Y1254724D03*
X1576181Y1247243D03*
X1572441Y1239763D03*
X1576181D03*
X1568700Y1247243D03*
X1579921Y1075196D03*
X1587401D03*
X1594882D03*
X1583661Y1086417D03*
Y1082677D03*
X1579921Y1078936D03*
X1587401D03*
X1591141Y1082677D03*
Y1086417D03*
X1594882Y1078936D03*
X1583661Y1247243D03*
X1579921Y1254724D03*
Y1250984D03*
X1583661Y1239763D03*
X1587401Y1250984D03*
Y1254724D03*
X1591141Y1247243D03*
X1594882Y1250984D03*
Y1254724D03*
X1591141Y1239763D03*
X1602362Y1075196D03*
X1598622Y1082677D03*
Y1086417D03*
X1602362Y1078936D03*
X1598622Y1239763D03*
Y1247243D03*
X1606102Y1243503D03*
Y1239763D03*
X1602362Y1250984D03*
Y1254724D03*
X1613582Y1239763D03*
X1621063Y1243503D03*
X1636023Y1101377D03*
X1643504D03*
X1628543D03*
X1632283Y1228543D03*
X1639763Y1224803D03*
X1636023Y1236023D03*
X1643504Y1232283D03*
X1632283Y1224803D03*
X1643504Y1236023D03*
X1636023Y1232283D03*
X1639763Y1228543D03*
X1628543Y1243503D03*
X1636023Y1239763D03*
X1658464Y1086417D03*
X1654724Y1097637D03*
X1650984Y1101377D03*
X1649114Y1121948D03*
Y1129429D03*
X1660334Y1144389D03*
X1654724Y1228543D03*
X1647244D03*
X1658464Y1232283D03*
X1654724Y1224803D03*
X1658464Y1236023D03*
X1650984D03*
X1647244Y1224803D03*
X1650984Y1232283D03*
X1647244Y1239763D03*
X1650984D03*
X1673424Y1090157D03*
X1673425Y1101377D03*
X1665944D03*
X1671555Y1136909D03*
X1669685Y1127558D03*
Y1135039D03*
X1671555Y1151869D03*
Y1144389D03*
X1665945Y1239763D03*
X1677164Y1090157D03*
X1680904D03*
X1688385D03*
X1680905Y1101377D03*
X1688385D03*
X1688386Y1105117D03*
X1680904Y1108858D03*
X1680905Y1116338D03*
Y1123818D03*
X1690256Y1136909D03*
X1679035Y1140649D03*
X1680905Y1131299D03*
X1688385D03*
X1690256Y1144389D03*
X1679035Y1148129D03*
Y1155610D03*
X1690256Y1151869D03*
Y1159350D03*
X1679035D03*
X1690256Y1166830D03*
Y1174310D03*
Y1189271D03*
Y1181791D03*
X1688385Y1198621D03*
Y1213582D03*
Y1206102D03*
X1692126Y1243503D03*
X1684645Y1239763D03*
X1677165D03*
X1700236Y1136909D03*
X1693996Y1166830D03*
X1697736D03*
G54D46*
X718503Y-38525D03*
X718500Y-33320D03*
Y-30420D03*
X718488Y-36010D03*
X721756Y-38539D03*
X724781Y-37219D03*
X721741Y-36024D03*
X838503Y-77705D03*
X841756Y-77719D03*
X838500Y-72500D03*
X838488Y-75190D03*
X841741Y-75204D03*
X844781Y-76399D03*
X838500Y-69600D03*
X1005256Y-48539D03*
X1002003D03*
X1005241Y-46024D03*
X1001988D03*
X1008281Y-47219D03*
X1002000Y-40834D03*
X1005256Y-38239D03*
X1002003Y-38225D03*
X1002000Y-43334D03*
X1005241Y-35724D03*
X1002000Y-32720D03*
X1001988Y-35710D03*
X1002000Y-30120D03*
X1008281Y-36919D03*
X1075256Y-77419D03*
X1072003Y-77405D03*
X1071988Y-85290D03*
X1075241D03*
X1072000Y-82600D03*
X1072003Y-87805D03*
X1075256D03*
X1072000Y-80100D03*
Y-72000D03*
Y-69400D03*
X1075241Y-74904D03*
X1071988Y-74890D03*
X1078281Y-86399D03*
Y-76099D03*
X1291756Y-48669D03*
X1288503D03*
X1291741Y-46154D03*
X1288488D03*
X1294781Y-47349D03*
X1288500Y-40964D03*
X1291756Y-38369D03*
X1288503Y-38355D03*
X1288500Y-43464D03*
X1291741Y-35854D03*
X1288500Y-32950D03*
X1288488Y-35840D03*
X1288500Y-30350D03*
X1294781Y-37049D03*
X1328500Y-80100D03*
X1331756Y-77419D03*
X1328503Y-77405D03*
X1331756Y-87805D03*
X1328503D03*
X1328500Y-82600D03*
X1331741Y-85290D03*
X1328488D03*
X1334781Y-86499D03*
X1331741Y-74904D03*
X1328500Y-72000D03*
X1328488Y-74890D03*
X1328500Y-69400D03*
X1334781Y-76099D03*
X1576256Y-48799D03*
X1573003D03*
X1576241Y-46284D03*
X1572988D03*
X1579281Y-47479D03*
X1573000Y-41094D03*
X1576256Y-38499D03*
X1573003Y-38485D03*
X1573000Y-43594D03*
X1576241Y-35984D03*
X1573000Y-33080D03*
X1572988Y-35970D03*
X1573000Y-30480D03*
X1579281Y-37179D03*
X1583000Y-80014D03*
X1586256Y-77419D03*
X1583003Y-77405D03*
X1586256Y-87719D03*
X1583003D03*
X1583000Y-82514D03*
X1586241Y-85204D03*
X1582988D03*
X1589281Y-86399D03*
X1586241Y-74904D03*
X1583000Y-72000D03*
X1582988Y-74890D03*
X1583000Y-69400D03*
X1589281Y-76099D03*
G54D26*
X56348Y1727941D03*
Y1737941D03*
X56248Y1750941D03*
X56348Y1773941D03*
X56248Y1760941D03*
X56348Y1783941D03*
X56248Y1806941D03*
Y1796941D03*
X308448Y1737941D03*
Y1727941D03*
Y1750941D03*
Y1760941D03*
Y1773941D03*
Y1783941D03*
X308348Y1796941D03*
Y1806941D03*
X343286Y1738583D03*
Y1728583D03*
X343112Y1751624D03*
X343212Y1774624D03*
X343112Y1761624D03*
X343212Y1784624D03*
Y1797624D03*
Y1807624D03*
X595386Y1728583D03*
Y1738583D03*
X595312Y1751624D03*
Y1774624D03*
Y1761624D03*
Y1784624D03*
Y1807624D03*
Y1797624D03*
X630083Y1738286D03*
Y1728286D03*
X629861Y1751765D03*
X629711Y1775438D03*
X629861Y1761765D03*
X629711Y1785438D03*
X629475Y1798845D03*
Y1808845D03*
X882183Y1728286D03*
Y1738286D03*
X881911Y1751765D03*
X881761Y1775438D03*
X881911Y1761765D03*
X881761Y1785438D03*
X881525Y1798845D03*
Y1808845D03*
X917279Y1738990D03*
Y1728990D03*
X917163Y1752566D03*
Y1762566D03*
X917073Y1786014D03*
Y1776014D03*
X917166Y1800435D03*
Y1810435D03*
X1169329Y1728990D03*
Y1738990D03*
X1169263Y1752566D03*
Y1762566D03*
X1169123Y1776014D03*
Y1786014D03*
X1169216Y1800435D03*
Y1810435D03*
G54D42*
X318448Y1727941D03*
Y1737941D03*
Y1773941D03*
Y1783941D03*
X605312Y1751624D03*
Y1761624D03*
Y1807624D03*
Y1797624D03*
X891911Y1751765D03*
Y1761765D03*
X891525Y1808845D03*
Y1798845D03*
X1179263Y1752566D03*
Y1762566D03*
X1179216Y1800435D03*
Y1810435D03*
G54D34*
X145078Y1198621D03*
Y1191141D03*
X148818D03*
Y1198621D03*
X145078Y1221062D03*
X148818D03*
Y1213582D03*
X145078D03*
Y1206102D03*
X148818D03*
X145078Y1228543D03*
X148818D03*
Y1247243D03*
X145078D03*
X148818Y1239763D03*
X145078D03*
X156299Y1187401D03*
X163779D03*
X152559D03*
X156299Y1202362D03*
Y1194881D03*
X152559Y1202362D03*
Y1194881D03*
X163779D03*
Y1202362D03*
X156299Y1217322D03*
Y1209842D03*
X152559D03*
X163779D03*
Y1217322D03*
X152559D03*
X160039Y1236023D03*
X163779Y1224803D03*
X156299D03*
Y1228543D03*
X163779D03*
X160039Y1232283D03*
X152559Y1236023D03*
Y1232283D03*
Y1250984D03*
Y1254724D03*
X160039D03*
X156299Y1243503D03*
Y1247243D03*
X163779Y1243503D03*
X160039Y1250984D03*
X163779Y1247243D03*
X174999Y1075196D03*
X182480D03*
X174999Y1078936D03*
X182480D03*
X178740Y1082677D03*
Y1086417D03*
X174999Y1093897D03*
X182480D03*
Y1097637D03*
X174999D03*
X178740Y1101376D03*
Y1105117D03*
X167519Y1187401D03*
X174999Y1198621D03*
Y1191141D03*
X167519Y1194881D03*
X171259Y1198621D03*
Y1191141D03*
X167519Y1202362D03*
Y1209842D03*
X171259Y1213582D03*
Y1206102D03*
X174999D03*
X167519Y1217322D03*
X174999Y1213582D03*
X167519Y1232283D03*
Y1236023D03*
Y1254724D03*
Y1250984D03*
X178740Y1247243D03*
X182480Y1254724D03*
Y1250984D03*
X171259Y1247243D03*
X174999Y1250984D03*
X171259Y1243503D03*
X174999Y1254724D03*
X178740Y1243503D03*
X189960Y1075196D03*
X197440D03*
X186220Y1082677D03*
Y1086417D03*
X189960Y1078936D03*
X193700Y1086417D03*
Y1082677D03*
X197440Y1078936D03*
X193700Y1105117D03*
X197440Y1093897D03*
X189960Y1097637D03*
X186220Y1105117D03*
X197440Y1097637D03*
X193700Y1101376D03*
X186220D03*
X189960Y1093897D03*
X197440Y1254724D03*
Y1250984D03*
X193700Y1247243D03*
Y1243503D03*
X189960Y1254724D03*
Y1250984D03*
X186220Y1247243D03*
Y1243503D03*
X204921Y1075196D03*
X212401D03*
Y1078936D03*
X208661Y1082677D03*
X201181D03*
Y1086417D03*
X208661D03*
X204921Y1078936D03*
Y1097637D03*
X208661Y1101376D03*
X212401Y1097637D03*
X208661Y1105117D03*
X212401Y1093897D03*
X201181Y1101376D03*
X204921Y1093897D03*
X201181Y1105117D03*
X208661Y1243503D03*
X204921Y1250984D03*
X208661Y1247243D03*
X212401Y1254724D03*
X201181Y1243503D03*
X212401Y1250984D03*
X201181Y1247243D03*
X204921Y1254724D03*
X227362Y1075196D03*
X219881D03*
Y1078936D03*
X216141Y1086417D03*
X231102Y1082677D03*
Y1086417D03*
X223622Y1082677D03*
X227362Y1078936D03*
X216141Y1082677D03*
X223622Y1086417D03*
X216141Y1101376D03*
X231102D03*
X227362Y1093897D03*
X219881Y1097637D03*
X223621Y1101376D03*
Y1105117D03*
X216141D03*
X219881Y1093897D03*
X227362Y1097637D03*
X231102Y1105117D03*
Y1228543D03*
Y1224803D03*
Y1243503D03*
Y1247243D03*
X223622Y1243503D03*
X216141Y1247243D03*
X223622D03*
X216141Y1243503D03*
X219881Y1250984D03*
Y1254724D03*
X227362D03*
Y1250984D03*
X234841Y1075195D03*
X242321Y1075196D03*
Y1078936D03*
X246061Y1082677D03*
X238581Y1082676D03*
X234841Y1078935D03*
X246061Y1086417D03*
X238581Y1086416D03*
X234841Y1093897D03*
X246062Y1105117D03*
X242321Y1097637D03*
X234841D03*
X238582Y1101376D03*
X246062D03*
X238582Y1105117D03*
X242321Y1093897D03*
X238582Y1224803D03*
Y1228543D03*
X242322Y1236023D03*
Y1232283D03*
X246062Y1228543D03*
X234842Y1232283D03*
X246062Y1224803D03*
X234842Y1236023D03*
X238582Y1247243D03*
X246062Y1243503D03*
X242322Y1250984D03*
X234842D03*
X246062Y1247243D03*
X234842Y1254724D03*
X238582Y1243503D03*
X242322Y1254724D03*
X249802Y1075196D03*
X257282D03*
X249802Y1078936D03*
X261022Y1086417D03*
X253542Y1082676D03*
X257282Y1078936D03*
X253542Y1086416D03*
X261022Y1082677D03*
X249802Y1097637D03*
X257282D03*
X249802Y1093897D03*
X253543Y1105117D03*
Y1101376D03*
X257282Y1093897D03*
X261023Y1105117D03*
Y1101376D03*
Y1224803D03*
X253543Y1228543D03*
X249803Y1232283D03*
X257283D03*
Y1236023D03*
X261023Y1228543D03*
X253543Y1224803D03*
X249803Y1236023D03*
X261023Y1243503D03*
X249803Y1250984D03*
X261023Y1247243D03*
X257283Y1250984D03*
X253543Y1247243D03*
X257283Y1254724D03*
X249803D03*
X253543Y1243503D03*
X279723Y1075196D03*
X264762D03*
X272243D03*
X275982Y1082677D03*
Y1086417D03*
X268502Y1082676D03*
X272243Y1078936D03*
X268502Y1086416D03*
X279723Y1078936D03*
X264762D03*
Y1097637D03*
X268503Y1105117D03*
X272243Y1097637D03*
X275984Y1105117D03*
X279723Y1093897D03*
X272243D03*
X279723Y1097637D03*
X268503Y1101376D03*
X275984D03*
X264762Y1093897D03*
X264763Y1232283D03*
X268503Y1224803D03*
X275984D03*
X272244Y1236023D03*
X279724Y1232283D03*
Y1236023D03*
X275984Y1228543D03*
X272244Y1232283D03*
X268503Y1228543D03*
X264763Y1236023D03*
Y1254724D03*
Y1250984D03*
X268503Y1243503D03*
Y1247243D03*
X272244Y1254724D03*
Y1250984D03*
X275984Y1243503D03*
Y1247243D03*
X279724Y1250984D03*
Y1254724D03*
X287203Y1075196D03*
X294684D03*
X290943Y1086417D03*
X287203Y1078936D03*
X290943Y1082677D03*
X283463Y1082676D03*
Y1086416D03*
X294684Y1078936D03*
X283464Y1101376D03*
X294684Y1093897D03*
X287203D03*
X294684Y1097637D03*
X283464Y1105117D03*
X290944Y1101376D03*
Y1105117D03*
X287203Y1097637D03*
X294684Y1123818D03*
Y1116338D03*
Y1131299D03*
X294685Y1198621D03*
Y1213582D03*
Y1206102D03*
X287204Y1232283D03*
X283464Y1224803D03*
Y1228543D03*
X287204Y1236023D03*
X294685D03*
X290944Y1224803D03*
X294685Y1232283D03*
X290944Y1228543D03*
X287204Y1254724D03*
X283464Y1243503D03*
Y1247243D03*
X287204Y1250984D03*
X302164Y1075196D03*
X309644D03*
X305904Y1082677D03*
X302164Y1078936D03*
X305904Y1086417D03*
X309644Y1078936D03*
X298424Y1086416D03*
Y1082676D03*
X298425Y1105117D03*
Y1101376D03*
X309644Y1097637D03*
X302164D03*
X305905Y1105117D03*
X309644Y1093897D03*
X305905Y1101376D03*
X302164Y1093897D03*
X302165Y1120078D03*
X305905Y1112598D03*
X298425Y1116338D03*
X305905Y1120078D03*
X302165Y1112598D03*
X298425Y1123818D03*
X305905Y1127559D03*
Y1135039D03*
X302165D03*
Y1127559D03*
X298425Y1131299D03*
Y1198621D03*
X305905Y1202362D03*
X302165D03*
X298425Y1213582D03*
X305905Y1209842D03*
Y1217322D03*
X302165Y1209842D03*
X298425Y1206102D03*
X302165Y1217322D03*
Y1232283D03*
X309645D03*
X298425Y1224803D03*
Y1228543D03*
X309645Y1236023D03*
X305905Y1228543D03*
Y1224803D03*
X302165Y1236023D03*
X317124Y1075196D03*
X320866Y1090157D03*
X324606D03*
Y1082676D03*
X317124Y1078936D03*
X313384Y1082677D03*
Y1086417D03*
X320866Y1082676D03*
X313385Y1101377D03*
X317125Y1093897D03*
X320866Y1101377D03*
X313385Y1105117D03*
X324606Y1101377D03*
X317125Y1097637D03*
X313385Y1120078D03*
X324606Y1123818D03*
Y1108858D03*
X320866D03*
X317125Y1112598D03*
X324606Y1116338D03*
X313385Y1112598D03*
X317125Y1120078D03*
X320866Y1116338D03*
Y1123818D03*
X313385Y1127558D03*
X317125Y1135039D03*
X313385D03*
X324606Y1131299D03*
X317125Y1127558D03*
X320866Y1131299D03*
X317125Y1236023D03*
X313385Y1224803D03*
X324606Y1228543D03*
X317125Y1232283D03*
X313385Y1228543D03*
X320866D03*
X324606Y1239763D03*
X320866D03*
X602165Y1191141D03*
Y1198621D03*
Y1221062D03*
Y1206102D03*
Y1213582D03*
Y1228543D03*
Y1247243D03*
Y1239763D03*
X613386Y1187401D03*
X609646D03*
X620866D03*
X605905Y1191141D03*
X613386Y1194881D03*
X605905Y1198621D03*
X609646Y1194881D03*
Y1202362D03*
X613386D03*
X620866D03*
Y1194881D03*
X613386Y1217322D03*
X605905Y1221062D03*
X609646Y1217322D03*
Y1209842D03*
X605905Y1206102D03*
Y1213582D03*
X620866Y1209842D03*
X613386D03*
X620866Y1217322D03*
X605905Y1228543D03*
X620866D03*
Y1224803D03*
X609646Y1232283D03*
X617126Y1236023D03*
X613386Y1228543D03*
X617126Y1232283D03*
X609646Y1236023D03*
X613386Y1224803D03*
X605905Y1247243D03*
X617126Y1250984D03*
X620866Y1243503D03*
Y1247243D03*
X609646Y1254724D03*
X613386Y1247243D03*
X617126Y1254724D03*
X613386Y1243503D03*
X609646Y1250984D03*
X605905Y1239763D03*
X632086Y1075196D03*
Y1078936D03*
X635827Y1086417D03*
Y1082677D03*
X632086Y1097637D03*
X635827Y1105117D03*
X632086Y1093897D03*
X635827Y1101376D03*
X624606Y1187401D03*
X628346Y1191141D03*
X624606Y1194881D03*
X632086Y1191141D03*
X628346Y1198621D03*
X624606Y1202362D03*
X632086Y1198621D03*
X628346Y1206102D03*
X632086D03*
X624606Y1217322D03*
X628346Y1213582D03*
X632086D03*
X624606Y1209842D03*
Y1232283D03*
Y1236023D03*
Y1254724D03*
Y1250984D03*
X639567Y1075196D03*
X647047D03*
X643307Y1086417D03*
Y1082677D03*
X647047Y1078936D03*
X639567D03*
X650787Y1082677D03*
Y1086417D03*
Y1105117D03*
X647047Y1093897D03*
X639567Y1097637D03*
X643307Y1105117D03*
X647047Y1097637D03*
X639567Y1093897D03*
X643307Y1101376D03*
X650787D03*
X662008Y1075196D03*
X654527D03*
X669488D03*
X662008Y1078936D03*
X665748Y1082677D03*
X658268D03*
X654527Y1078936D03*
X665748Y1086417D03*
X658268D03*
X669488Y1078936D03*
X662008Y1097637D03*
X654527Y1093897D03*
X669488D03*
X665748Y1105117D03*
X654527Y1097637D03*
X662008Y1093897D03*
X669488Y1097637D03*
X665748Y1101376D03*
X658268Y1105117D03*
Y1101376D03*
X669488Y1232283D03*
X662008D03*
X665748Y1224803D03*
X662008Y1236023D03*
X658268Y1224803D03*
X665748Y1228543D03*
X658268D03*
X669488Y1236023D03*
X662008Y1254724D03*
X665748Y1247243D03*
X669488Y1250984D03*
X658268Y1247243D03*
X662008Y1250984D03*
X665748Y1243503D03*
X669488Y1254724D03*
X658268Y1243503D03*
X676968Y1075196D03*
X684449D03*
X676968Y1078936D03*
X680709Y1086417D03*
X684449Y1078936D03*
X673228Y1086417D03*
Y1082677D03*
X680709D03*
X673228Y1105117D03*
X684449Y1093897D03*
X676968D03*
X684449Y1097637D03*
X676968D03*
X680708Y1105117D03*
X673228Y1101376D03*
X680708D03*
X676968Y1236023D03*
X684449Y1232283D03*
X673228Y1228543D03*
X680709Y1224803D03*
X684449Y1236023D03*
X676968Y1232283D03*
X673228Y1224803D03*
X680709Y1228543D03*
X673228Y1243503D03*
X680709Y1247243D03*
X673228D03*
X684449Y1254724D03*
Y1250984D03*
X676968Y1254724D03*
Y1250984D03*
X680709Y1243503D03*
X699408Y1075196D03*
X691928Y1075195D03*
X688189Y1086417D03*
Y1082677D03*
X691928Y1078935D03*
X699408Y1078936D03*
X695668Y1086416D03*
Y1082676D03*
X688189Y1105117D03*
X695669Y1101376D03*
X699408Y1097637D03*
X695669Y1105117D03*
X691928Y1093897D03*
Y1097637D03*
X699408Y1093897D03*
X688189Y1101376D03*
Y1228543D03*
X691929Y1236023D03*
X699409Y1232283D03*
X688189Y1224803D03*
X699409Y1236023D03*
X691929Y1232283D03*
X695669Y1228543D03*
Y1224803D03*
X699409Y1254724D03*
X691929Y1250984D03*
X688189Y1247243D03*
Y1243503D03*
X691929Y1254724D03*
X695669Y1247243D03*
X699409Y1250984D03*
X695669Y1243503D03*
X706889Y1075196D03*
X714369D03*
X706889Y1078936D03*
X718109Y1086417D03*
X714369Y1078936D03*
X703148Y1082677D03*
X710629Y1086416D03*
X703148Y1086417D03*
X718109Y1082677D03*
X710629Y1082676D03*
X714369Y1097637D03*
X706889Y1093897D03*
X703149Y1105117D03*
X718110D03*
Y1101376D03*
X710630Y1105117D03*
X714369Y1093897D03*
X706889Y1097637D03*
X703149Y1101376D03*
X710630D03*
X706890Y1236023D03*
X714370D03*
X710630Y1228543D03*
X703149D03*
X714370Y1232283D03*
X703149Y1224803D03*
X710630D03*
X706890Y1232283D03*
Y1250984D03*
X703149Y1243503D03*
X714370Y1254724D03*
Y1250984D03*
X710630Y1247243D03*
X706890Y1254724D03*
X710630Y1243503D03*
X703149Y1247243D03*
X721849Y1075196D03*
X729330D03*
X725589Y1086416D03*
X733069Y1086417D03*
X721849Y1078936D03*
X729330D03*
X733069Y1082677D03*
X725589Y1082676D03*
X725590Y1101376D03*
X733071Y1105117D03*
X725590D03*
X721849Y1097637D03*
Y1093897D03*
X729330Y1097637D03*
X733071Y1101376D03*
X729330Y1093897D03*
X736810Y1075196D03*
X744290D03*
Y1078936D03*
X748030Y1086417D03*
X740550Y1086416D03*
Y1082676D03*
X736810Y1078936D03*
X748030Y1082677D03*
X736810Y1097637D03*
X748031Y1105117D03*
X744290Y1093897D03*
X740551Y1105117D03*
X744290Y1097637D03*
X736810Y1093897D03*
X740551Y1101376D03*
X748031D03*
Y1224803D03*
Y1228543D03*
Y1247243D03*
Y1243503D03*
X751771Y1075196D03*
X766731D03*
X759251D03*
X762991Y1086417D03*
X766731Y1078936D03*
X755511Y1086416D03*
X759251Y1078936D03*
X755511Y1082676D03*
X762991Y1082677D03*
X751771Y1078936D03*
Y1097637D03*
X762992Y1101376D03*
Y1105117D03*
X755512D03*
X759251Y1097637D03*
Y1093897D03*
X766731Y1097637D03*
X755512Y1101376D03*
X766731Y1093897D03*
X751771D03*
X755512Y1123818D03*
X759252Y1112598D03*
X751771Y1123818D03*
X762992Y1112598D03*
X755512Y1116338D03*
X751771D03*
X759252Y1120078D03*
X762992D03*
X751771Y1131299D03*
X762992Y1135039D03*
X755512Y1131299D03*
X762992Y1127559D03*
X759252Y1135039D03*
Y1127559D03*
X762992Y1202362D03*
X755512Y1198621D03*
X759252Y1202362D03*
X751772Y1198621D03*
X762992Y1217322D03*
X751772Y1213582D03*
X762992Y1209842D03*
X755512Y1213582D03*
X751772Y1206102D03*
X759252Y1217322D03*
Y1209842D03*
X755512Y1206102D03*
Y1228543D03*
X751772Y1236023D03*
X762992Y1228543D03*
X751772Y1232283D03*
X766732D03*
Y1236023D03*
X759252Y1232283D03*
X762992Y1224803D03*
X759252Y1236023D03*
X755512Y1224803D03*
X766732Y1250984D03*
X755512Y1243503D03*
X762992D03*
Y1247243D03*
X751772Y1250984D03*
Y1254724D03*
X759252D03*
X766732D03*
X759252Y1250984D03*
X755512Y1247243D03*
X774211Y1075196D03*
X781693Y1090157D03*
X777953D03*
X781693Y1082676D03*
X774211Y1078936D03*
X770471Y1086417D03*
Y1082677D03*
X777953Y1082676D03*
X770472Y1101377D03*
X781693D03*
X777953D03*
X774212Y1097637D03*
X770472Y1105117D03*
X774212Y1093897D03*
Y1112598D03*
X770472D03*
X781693Y1123818D03*
X777953D03*
X781693Y1116338D03*
X777953Y1108858D03*
X770472Y1120078D03*
X781693Y1108858D03*
X777953Y1116338D03*
X774212Y1120078D03*
X770472Y1127558D03*
Y1135039D03*
X781693Y1131299D03*
X774212Y1127558D03*
Y1135039D03*
X777953Y1131299D03*
X781693Y1198621D03*
X774212Y1202362D03*
X770472D03*
X777953Y1198621D03*
Y1206102D03*
X770472Y1209842D03*
X781693Y1213582D03*
X774212Y1209842D03*
X777953Y1221062D03*
X781693D03*
Y1206102D03*
X770472Y1217322D03*
X774212D03*
X777953Y1213582D03*
X770472Y1228543D03*
X781693D03*
X770472Y1224803D03*
X777953Y1228543D03*
X774212Y1232283D03*
Y1236023D03*
X777953Y1239763D03*
X781693D03*
X777953Y1247243D03*
X770472Y1243503D03*
X781693Y1247243D03*
X770472D03*
X774212Y1250984D03*
Y1254724D03*
X1059251Y1198621D03*
Y1191141D03*
Y1221062D03*
Y1206102D03*
Y1213582D03*
Y1228543D03*
Y1247243D03*
Y1239763D03*
X1070472Y1187401D03*
X1066732D03*
X1062991Y1198621D03*
X1066732Y1194881D03*
X1062991Y1191141D03*
X1070472Y1194881D03*
Y1202362D03*
X1066732D03*
X1070472Y1217322D03*
X1066732D03*
X1062991Y1221062D03*
Y1206102D03*
X1070472Y1209842D03*
X1062991Y1213582D03*
X1066732Y1209842D03*
X1070472Y1228543D03*
X1066732Y1236023D03*
Y1232283D03*
X1074212Y1236023D03*
Y1232283D03*
X1070472Y1224803D03*
X1062991Y1228543D03*
X1074212Y1250984D03*
X1066732Y1254724D03*
X1070472Y1247243D03*
X1074212Y1254724D03*
X1062991Y1247243D03*
X1070472Y1243503D03*
X1062991Y1239763D03*
X1066732Y1250984D03*
X1089172Y1075196D03*
Y1078936D03*
Y1097637D03*
Y1093897D03*
X1077952Y1187401D03*
X1081692D03*
X1077952Y1194881D03*
Y1202362D03*
X1089172Y1191141D03*
Y1198621D03*
X1081692Y1202362D03*
X1085432Y1198621D03*
X1081692Y1194881D03*
X1085432Y1191141D03*
X1089172Y1206102D03*
X1077952Y1209842D03*
X1081692D03*
Y1217322D03*
X1089172Y1213582D03*
X1077952Y1217322D03*
X1085432Y1206102D03*
Y1213582D03*
X1081692Y1232283D03*
Y1236023D03*
X1077952Y1224803D03*
Y1228543D03*
Y1243503D03*
X1081692Y1250984D03*
X1077952Y1247243D03*
X1081692Y1254724D03*
X1085432Y1243503D03*
X1089172Y1254724D03*
Y1250984D03*
X1085432Y1247243D03*
X1096653Y1075196D03*
X1104133D03*
X1100393Y1082677D03*
X1104133Y1078936D03*
X1107873Y1082677D03*
Y1086417D03*
X1092913Y1082677D03*
X1100393Y1086417D03*
X1092913D03*
X1096653Y1078936D03*
X1092913Y1105117D03*
X1104133Y1097637D03*
X1096653D03*
X1100393Y1105117D03*
X1104133Y1093897D03*
X1100393Y1101376D03*
X1096653Y1093897D03*
X1092913Y1101376D03*
X1107873Y1105117D03*
Y1101376D03*
X1096653Y1254724D03*
X1104133D03*
X1092913Y1247243D03*
X1096653Y1250984D03*
X1092913Y1243503D03*
X1107873D03*
X1100393D03*
X1107873Y1247243D03*
X1100393D03*
X1104133Y1250984D03*
X1111613Y1075196D03*
X1119094D03*
X1122834Y1086417D03*
X1119094Y1078936D03*
X1115354Y1082677D03*
X1111613Y1078936D03*
X1115354Y1086417D03*
X1122834Y1082677D03*
X1119094Y1097637D03*
X1115354Y1101376D03*
X1111613Y1093897D03*
Y1097637D03*
X1122834Y1105117D03*
X1119094Y1093897D03*
X1122834Y1101376D03*
X1115354Y1105117D03*
X1122834Y1243503D03*
X1119094Y1250984D03*
X1111613Y1254724D03*
X1119094D03*
X1122834Y1247243D03*
X1115354Y1243503D03*
Y1247243D03*
X1111613Y1250984D03*
X1126574Y1075196D03*
X1134054D03*
Y1078936D03*
X1126574D03*
X1130314Y1086417D03*
Y1082677D03*
X1137795Y1086417D03*
Y1082677D03*
X1126574Y1093897D03*
X1130314Y1105117D03*
X1134054Y1093897D03*
X1130314Y1101376D03*
X1134054Y1097637D03*
X1137794Y1105117D03*
X1126574Y1097637D03*
X1137794Y1101376D03*
X1126574Y1254724D03*
X1137795Y1243503D03*
X1130314Y1247243D03*
X1126574Y1250984D03*
X1137795Y1247243D03*
X1130314Y1243503D03*
X1134054Y1250984D03*
Y1254724D03*
X1141535Y1075196D03*
X1156494D03*
X1149014Y1075195D03*
X1145275Y1086417D03*
Y1082677D03*
X1141535Y1078936D03*
X1149014Y1078935D03*
X1156494Y1078936D03*
X1152754Y1086416D03*
Y1082676D03*
X1145275Y1105117D03*
X1141535Y1093897D03*
X1145275Y1101376D03*
X1141535Y1097637D03*
X1149014D03*
X1156494Y1093897D03*
X1152755Y1101376D03*
X1156494Y1097637D03*
X1149014Y1093897D03*
X1152755Y1105117D03*
X1149015Y1236023D03*
Y1232283D03*
X1152755Y1228543D03*
X1145275Y1224803D03*
X1156495Y1232283D03*
Y1236023D03*
X1145275Y1228543D03*
X1152755Y1224803D03*
X1141535Y1254724D03*
Y1250984D03*
X1149015Y1254724D03*
X1145275Y1247243D03*
X1152755Y1243503D03*
X1156495Y1254724D03*
X1145275Y1243503D03*
X1152755Y1247243D03*
X1149015Y1250984D03*
X1156495D03*
X1163975Y1075196D03*
X1171455D03*
X1160234Y1086417D03*
X1167715Y1086416D03*
X1163975Y1078936D03*
X1160234Y1082677D03*
X1171455Y1078936D03*
X1167715Y1082676D03*
X1160235Y1105117D03*
Y1101376D03*
X1171455Y1093897D03*
X1167716Y1105117D03*
X1171455Y1097637D03*
X1163975Y1093897D03*
Y1097637D03*
X1167716Y1101376D03*
X1160235Y1224803D03*
X1163976Y1232283D03*
X1167716Y1224803D03*
X1160235Y1228543D03*
X1171456Y1232283D03*
X1163976Y1236023D03*
X1171456D03*
X1167716Y1228543D03*
X1171456Y1250984D03*
X1167716Y1247243D03*
X1163976Y1250984D03*
X1160235Y1247243D03*
Y1243503D03*
X1167716D03*
X1171456Y1254724D03*
X1163976D03*
X1178935Y1075196D03*
X1186416D03*
X1175195Y1086417D03*
X1182675Y1086416D03*
X1175195Y1082677D03*
X1178935Y1078936D03*
X1182675Y1082676D03*
X1186416Y1078936D03*
X1178935Y1097637D03*
X1186416Y1093897D03*
X1182676Y1105117D03*
X1175196D03*
X1178935Y1093897D03*
X1182676Y1101376D03*
X1175196D03*
X1186416Y1097637D03*
X1182676Y1228543D03*
X1186417Y1236023D03*
X1178936D03*
X1186417Y1232283D03*
X1175196Y1228543D03*
X1178936Y1232283D03*
X1182676Y1224803D03*
X1175196D03*
X1178936Y1254724D03*
X1175196Y1243503D03*
X1182676Y1247243D03*
X1178936Y1250984D03*
X1186417D03*
X1182676Y1243503D03*
X1186417Y1254724D03*
X1175196Y1247243D03*
X1193896Y1075196D03*
X1201376D03*
X1190155Y1086417D03*
X1205116Y1082677D03*
X1190155D03*
X1197636Y1082676D03*
X1193896Y1078936D03*
X1205116Y1086417D03*
X1201376Y1078936D03*
X1197636Y1086416D03*
X1201376Y1093897D03*
X1193896Y1097637D03*
X1197637Y1105117D03*
X1205117D03*
X1197637Y1101376D03*
X1205117D03*
X1190157D03*
X1193896Y1093897D03*
X1201376Y1097637D03*
X1190157Y1105117D03*
X1197637Y1224803D03*
X1193897Y1236023D03*
X1190157Y1228543D03*
X1201377Y1236023D03*
X1190157Y1224803D03*
X1193897Y1232283D03*
X1197637Y1228543D03*
X1201377Y1232283D03*
X1205117Y1228543D03*
Y1224803D03*
X1190157Y1243503D03*
X1201377Y1250984D03*
X1197637Y1247243D03*
X1193897Y1250984D03*
X1201377Y1254724D03*
X1197637Y1243503D03*
X1193897Y1254724D03*
X1190157Y1247243D03*
X1216337Y1075196D03*
X1208857D03*
X1212597Y1082676D03*
Y1086416D03*
X1220077Y1086417D03*
X1208857Y1078936D03*
X1216337D03*
X1220077Y1082677D03*
X1220078Y1105117D03*
X1216337Y1093897D03*
X1212598Y1101376D03*
Y1105117D03*
X1208857Y1093897D03*
X1216337Y1097637D03*
X1220078Y1101376D03*
X1208857Y1097637D03*
X1212598Y1123818D03*
X1208857Y1116338D03*
X1212598D03*
X1216338Y1120078D03*
Y1112598D03*
X1208857Y1123818D03*
X1220078Y1112598D03*
Y1120078D03*
X1216338Y1127559D03*
Y1135039D03*
X1212598Y1131299D03*
X1208857D03*
X1220078Y1135039D03*
Y1127559D03*
X1212598Y1198621D03*
X1208858D03*
X1216338Y1202362D03*
X1220078D03*
Y1217322D03*
Y1209842D03*
X1212598Y1206102D03*
X1216338Y1217322D03*
X1212598Y1213582D03*
X1208858Y1206102D03*
Y1213582D03*
X1216338Y1209842D03*
X1220078Y1224803D03*
X1212598Y1228543D03*
X1208858Y1232283D03*
X1216338Y1236023D03*
Y1232283D03*
X1212598Y1224803D03*
X1220078Y1228543D03*
X1208858Y1236023D03*
X1231297Y1075196D03*
X1223817D03*
X1235039Y1090157D03*
X1231297Y1078936D03*
X1235039Y1082676D03*
X1227557Y1086417D03*
X1223817Y1078936D03*
X1227557Y1082677D03*
X1227558Y1101377D03*
X1231298Y1093897D03*
X1235039Y1101377D03*
X1227558Y1105117D03*
X1223817Y1093897D03*
Y1097637D03*
X1231298D03*
X1227558Y1112598D03*
X1235039Y1123818D03*
X1231298Y1120078D03*
Y1112598D03*
X1235039Y1108858D03*
Y1116338D03*
X1227558Y1120078D03*
X1231298Y1135039D03*
X1227558Y1127558D03*
X1235039Y1131299D03*
X1231298Y1127558D03*
X1227558Y1135039D03*
X1231298Y1232283D03*
X1227558Y1228543D03*
Y1224803D03*
X1223818Y1236023D03*
X1231298D03*
X1235039Y1228543D03*
X1223818Y1232283D03*
X1235039Y1239763D03*
X1238779Y1090157D03*
Y1082676D03*
Y1101377D03*
Y1108858D03*
Y1116338D03*
Y1123818D03*
Y1131299D03*
Y1228543D03*
Y1239763D03*
X1523819Y1187401D03*
X1527559D03*
X1516338Y1198621D03*
X1523819Y1194881D03*
X1520078Y1198621D03*
X1523819Y1202362D03*
X1516338Y1191141D03*
X1527559Y1202362D03*
Y1194881D03*
X1520078Y1191141D03*
Y1221062D03*
X1516338Y1213582D03*
Y1206102D03*
X1520078D03*
X1527559Y1217322D03*
X1523819Y1209842D03*
X1516338Y1221062D03*
X1527559Y1209842D03*
X1523819Y1217322D03*
X1520078Y1213582D03*
X1527559Y1228543D03*
X1516338D03*
X1523819Y1232283D03*
X1520078Y1228543D03*
X1523819Y1236023D03*
X1527559Y1224803D03*
X1516338Y1239763D03*
X1520078D03*
Y1247243D03*
X1516338D03*
X1527559Y1243503D03*
Y1247243D03*
X1523819Y1250984D03*
Y1254724D03*
X1546259Y1075196D03*
Y1078936D03*
Y1097637D03*
Y1093897D03*
X1535039Y1187401D03*
X1538779D03*
X1542519Y1191141D03*
X1538779Y1202362D03*
X1535039Y1194881D03*
X1542519Y1198621D03*
X1546259D03*
Y1191141D03*
X1535039Y1202362D03*
X1538779Y1194881D03*
X1542519Y1213582D03*
Y1206102D03*
X1546259Y1213582D03*
X1535039Y1209842D03*
Y1217322D03*
X1546259Y1206102D03*
X1538779Y1209842D03*
Y1217322D03*
X1535039Y1224803D03*
X1538779Y1236023D03*
X1531299Y1232283D03*
X1535039Y1228543D03*
X1531299Y1236023D03*
X1538779Y1232283D03*
Y1250984D03*
Y1254724D03*
X1535039Y1243503D03*
X1531299Y1250984D03*
X1535039Y1247243D03*
X1531299Y1254724D03*
X1553740Y1075196D03*
X1561220D03*
X1557480Y1082677D03*
X1553740Y1078936D03*
X1561220D03*
X1550000Y1086417D03*
Y1082677D03*
X1557480Y1086417D03*
Y1101376D03*
X1561220Y1093897D03*
X1557480Y1105117D03*
X1561220Y1097637D03*
X1550000Y1101376D03*
Y1105117D03*
X1553740Y1093897D03*
Y1097637D03*
X1576181Y1075196D03*
X1568700D03*
Y1078936D03*
X1572441Y1086417D03*
X1564960Y1082677D03*
Y1086417D03*
X1572441Y1082677D03*
X1576181Y1078936D03*
X1564960Y1105117D03*
X1576181Y1097637D03*
X1568700D03*
X1576181Y1093897D03*
X1568700D03*
X1572441Y1101376D03*
Y1105117D03*
X1564960Y1101376D03*
X1572441Y1228543D03*
X1576181Y1236023D03*
X1572441Y1224803D03*
X1576181Y1232283D03*
X1572441Y1247243D03*
X1576181Y1254724D03*
Y1250984D03*
X1572441Y1243503D03*
X1583661Y1075196D03*
X1591141D03*
X1594882Y1082677D03*
X1579921D03*
X1583661Y1078936D03*
X1594882Y1086417D03*
X1587401Y1082677D03*
X1579921Y1086417D03*
X1587401D03*
X1591141Y1078936D03*
X1594881Y1105117D03*
X1591141Y1097637D03*
X1583661Y1093897D03*
X1594881Y1101376D03*
X1583661Y1097637D03*
X1587401Y1105117D03*
X1579921Y1101376D03*
X1591141Y1093897D03*
X1587401Y1101376D03*
X1579921Y1105117D03*
X1594882Y1224803D03*
X1591141Y1232283D03*
X1583661Y1236023D03*
X1579921Y1228543D03*
X1583661Y1232283D03*
X1594882Y1228543D03*
X1579921Y1224803D03*
X1587401Y1228543D03*
Y1224803D03*
X1591141Y1236023D03*
X1583661Y1254724D03*
X1579921Y1247243D03*
X1591141Y1254724D03*
X1587401Y1247243D03*
Y1243503D03*
X1594882D03*
X1579921D03*
X1594882Y1247243D03*
X1583661Y1250984D03*
X1591141D03*
X1606101Y1075195D03*
X1598622Y1075196D03*
X1609841Y1086416D03*
X1606101Y1078935D03*
X1609841Y1082676D03*
X1602362Y1082677D03*
Y1086417D03*
X1598622Y1078936D03*
X1606101Y1093897D03*
X1602362Y1101376D03*
X1598622Y1097637D03*
Y1093897D03*
X1602362Y1105117D03*
X1609842Y1101376D03*
Y1105117D03*
X1606101Y1097637D03*
X1598622Y1236023D03*
X1606102D03*
X1609842Y1228543D03*
X1606102Y1232283D03*
X1602362Y1224803D03*
X1609842D03*
X1602362Y1228543D03*
X1598622Y1232283D03*
Y1254724D03*
Y1250984D03*
X1609842Y1247243D03*
X1606102Y1250984D03*
Y1254724D03*
X1609842Y1243503D03*
X1602362Y1247243D03*
Y1243503D03*
X1613581Y1075196D03*
X1621062D03*
X1613581Y1078936D03*
X1624802Y1082676D03*
X1617321Y1082677D03*
X1621062Y1078936D03*
X1617321Y1086417D03*
X1624802Y1086416D03*
X1621062Y1093897D03*
X1617322Y1105117D03*
Y1101376D03*
X1613581Y1093897D03*
Y1097637D03*
X1624803Y1101376D03*
Y1105117D03*
X1621062Y1097637D03*
X1617322Y1228543D03*
X1624803Y1224803D03*
X1617322D03*
X1621063Y1236023D03*
X1613582D03*
X1621063Y1232283D03*
X1624803Y1228543D03*
X1613582Y1232283D03*
X1624803Y1247243D03*
Y1243503D03*
X1621063Y1254724D03*
X1613582Y1250984D03*
X1617322Y1243503D03*
Y1247243D03*
X1613582Y1254724D03*
X1621063Y1250984D03*
X1636022Y1075196D03*
X1643503D03*
X1628542D03*
X1632282Y1082677D03*
X1643503Y1078936D03*
X1628542D03*
X1639762Y1086416D03*
X1632282Y1086417D03*
X1636022Y1078936D03*
X1639762Y1082676D03*
X1639763Y1101376D03*
X1628542Y1093897D03*
X1636022D03*
X1639763Y1105117D03*
X1632283D03*
Y1101376D03*
X1636022Y1097637D03*
X1643503D03*
Y1093897D03*
X1628542Y1097637D03*
X1628543Y1236023D03*
Y1232283D03*
Y1250984D03*
Y1254724D03*
X1650983Y1075196D03*
X1658463D03*
X1654723Y1086416D03*
Y1082676D03*
X1650983Y1078936D03*
X1647242Y1082677D03*
Y1086417D03*
X1658463Y1078936D03*
Y1097637D03*
X1647244Y1101376D03*
X1658463Y1093897D03*
X1654724Y1105117D03*
X1650983Y1093897D03*
X1647244Y1105117D03*
X1654724Y1101376D03*
X1650983Y1097637D03*
X1673424Y1075196D03*
X1665944D03*
X1662203Y1086417D03*
Y1082677D03*
X1669684Y1086416D03*
X1665944Y1078936D03*
X1673424D03*
X1669684Y1082676D03*
X1665944Y1093897D03*
X1662204Y1105117D03*
X1669685D03*
X1673424Y1097637D03*
X1669685Y1101376D03*
X1673424Y1093897D03*
X1665944Y1097637D03*
X1662204Y1101376D03*
X1673425Y1112598D03*
X1665944Y1123818D03*
X1673425Y1120078D03*
X1669685Y1123818D03*
X1665944Y1116338D03*
X1669685D03*
X1665944Y1131299D03*
X1669685D03*
X1673425Y1127559D03*
Y1135039D03*
Y1202362D03*
X1665945Y1198621D03*
X1669685D03*
X1665945Y1206102D03*
X1669685Y1213582D03*
X1673425Y1209842D03*
X1669685Y1206102D03*
X1665945Y1213582D03*
X1673425Y1217322D03*
Y1236023D03*
X1662204Y1228543D03*
X1669685D03*
X1673425Y1232283D03*
X1665945D03*
Y1236023D03*
X1662204Y1224803D03*
X1669685D03*
X1673425Y1250984D03*
X1662204Y1247243D03*
X1665945Y1254724D03*
X1673425D03*
X1662204Y1243503D03*
X1665945Y1250984D03*
X1669685Y1247243D03*
Y1243503D03*
X1680904Y1075196D03*
X1688384D03*
X1692126Y1090157D03*
Y1082676D03*
X1684644Y1082677D03*
Y1086417D03*
X1680904Y1078936D03*
X1688384D03*
X1677164Y1086417D03*
Y1082677D03*
X1692126Y1101377D03*
X1684645D03*
X1677165Y1105117D03*
X1680904Y1097637D03*
X1677165Y1101376D03*
X1688385Y1097637D03*
X1684645Y1105117D03*
X1680904Y1093897D03*
X1688385D03*
X1677165Y1120078D03*
Y1112598D03*
X1692126Y1116338D03*
Y1108858D03*
X1684645Y1120078D03*
X1688385D03*
X1684645Y1112598D03*
X1692126Y1123818D03*
X1688385Y1112598D03*
X1677165Y1135039D03*
Y1127559D03*
X1684645Y1135039D03*
Y1127558D03*
X1692126Y1131299D03*
X1688385Y1127558D03*
Y1135039D03*
X1684645Y1202362D03*
X1692126Y1198621D03*
X1688385Y1202362D03*
X1677165D03*
X1692126Y1213582D03*
X1684645Y1217322D03*
Y1209842D03*
X1692126Y1206102D03*
X1677165Y1209842D03*
X1692126Y1221062D03*
X1688385Y1209842D03*
X1677165Y1217322D03*
X1688385D03*
X1677165Y1228543D03*
X1680905Y1236023D03*
Y1232283D03*
X1692126Y1228543D03*
X1684645Y1224803D03*
Y1228543D03*
X1677165Y1224803D03*
X1688385Y1232283D03*
Y1236023D03*
X1684645Y1243503D03*
X1677165D03*
X1692126Y1247243D03*
X1684645D03*
X1677165D03*
X1688385Y1254724D03*
Y1250984D03*
X1692126Y1239763D03*
X1680905Y1254724D03*
Y1250984D03*
X1695866Y1090157D03*
Y1082676D03*
Y1101377D03*
Y1123818D03*
Y1116338D03*
Y1108858D03*
Y1131299D03*
Y1198621D03*
Y1221062D03*
Y1213582D03*
Y1206102D03*
Y1228543D03*
Y1239763D03*
Y1247243D03*
G54D58*
X1250055Y1710189D03*
Y1720189D03*
Y1739208D03*
Y1749208D03*
X1250048Y1768377D03*
Y1778377D03*
X1248555Y1797909D03*
Y1807909D03*
X1734069Y1710189D03*
Y1720189D03*
Y1739208D03*
Y1749208D03*
X1734062Y1768377D03*
Y1778377D03*
X1734069Y1797909D03*
Y1807909D03*
G54D18*
X7983Y1529035D03*
Y1525635D03*
X35688Y111255D03*
Y114655D03*
X28388Y121742D03*
X35688Y125428D03*
X28388Y132515D03*
Y118342D03*
X35688Y128828D03*
X28388Y135915D03*
X35825Y1464845D03*
X39225D03*
X76005Y114623D03*
Y111223D03*
Y125396D03*
Y128796D03*
X76112Y1348187D03*
X79512D03*
X76112Y1360099D03*
X79512D03*
Y1372385D03*
X76112D03*
Y1384297D03*
X79512D03*
X86407Y132509D03*
Y118335D03*
Y121735D03*
Y135909D03*
X88352Y1348187D03*
X91752D03*
X100592D03*
X91752Y1360099D03*
X88352D03*
X100592D03*
Y1384297D03*
Y1372385D03*
X91752D03*
X88352D03*
Y1384297D03*
X91752D03*
Y1396583D03*
X88352D03*
X100592D03*
X91752Y1408495D03*
X88352D03*
X100592D03*
X116232Y1348187D03*
X112832D03*
X103992D03*
X112832Y1360099D03*
X116232D03*
X103992D03*
Y1372385D03*
Y1384297D03*
X112832D03*
X116232Y1372385D03*
Y1384297D03*
X112832Y1372385D03*
X116232Y1396583D03*
X112832D03*
X103992D03*
X112832Y1408495D03*
X116232D03*
X103992D03*
X130750Y132515D03*
Y121742D03*
Y118342D03*
Y135915D03*
X125072Y1348187D03*
X128472D03*
Y1360099D03*
X125072D03*
Y1384297D03*
X128472D03*
X125072Y1372385D03*
X128472D03*
X125072Y1396583D03*
X128472D03*
X125072Y1408495D03*
X128472D03*
X138050Y111255D03*
Y114655D03*
Y128828D03*
Y125428D03*
X148692Y391001D03*
Y394401D03*
Y405174D03*
X140690Y401513D03*
Y398113D03*
X148692Y408574D03*
X138290Y412287D03*
X148692Y419347D03*
Y422747D03*
X138290Y415687D03*
Y426460D03*
X148692Y433521D03*
X138290Y429860D03*
X148692Y436921D03*
X138290Y440633D03*
Y444033D03*
Y469387D03*
Y472787D03*
X148692Y476499D03*
X138290Y483560D03*
X148692Y490673D03*
X138290Y486960D03*
X148692Y479899D03*
Y494073D03*
Y524033D03*
Y520633D03*
X138290Y516921D03*
Y513521D03*
Y531094D03*
X148692Y538206D03*
Y534806D03*
X138290Y527694D03*
X140712Y1348187D03*
X137312D03*
X149552D03*
X137312Y1360099D03*
X140712D03*
X149552D03*
Y1384297D03*
Y1372385D03*
X140712D03*
Y1384297D03*
X137312D03*
Y1372385D03*
X140712Y1396583D03*
X137312D03*
X149552D03*
X140712Y1408495D03*
X137312D03*
X149552D03*
X165192Y1348187D03*
X161792D03*
X152952D03*
X165192Y1360099D03*
X161792D03*
X152952D03*
Y1384297D03*
Y1372385D03*
X161792Y1384297D03*
X165192Y1372385D03*
Y1384297D03*
X161792Y1372385D03*
X165192Y1396583D03*
X161792D03*
X152952D03*
X165192Y1408495D03*
X161792D03*
X152952D03*
X178367Y111223D03*
Y114623D03*
Y128796D03*
Y125396D03*
X177432Y1348187D03*
X174032D03*
Y1360099D03*
X177432D03*
Y1384297D03*
X174032D03*
Y1372385D03*
X177432D03*
Y1396583D03*
X174032D03*
X177432Y1408495D03*
X174032D03*
X188769Y118335D03*
Y121735D03*
Y132509D03*
Y135909D03*
X189672Y1348187D03*
X186272D03*
X198512D03*
X189672Y1360099D03*
X186272D03*
X198512D03*
Y1384297D03*
Y1372385D03*
X186272Y1384297D03*
X189672D03*
Y1372385D03*
X186272D03*
Y1396583D03*
X189672D03*
X198512D03*
X189672Y1408495D03*
X186272D03*
X198512D03*
X212980Y390995D03*
Y405168D03*
Y394395D03*
X205680Y401482D03*
Y398082D03*
X212980Y408568D03*
Y419341D03*
Y422741D03*
X205680Y415655D03*
Y412255D03*
Y426428D03*
Y440602D03*
Y429828D03*
X212980Y433515D03*
Y436915D03*
X205680Y444002D03*
X212980Y469381D03*
Y472781D03*
X205680Y490641D03*
Y479868D03*
X212980Y483554D03*
X205680Y476468D03*
X212980Y486954D03*
X205680Y494041D03*
Y524002D03*
X212980Y516915D03*
Y513515D03*
X205680Y520602D03*
Y534775D03*
X212980Y527688D03*
X205680Y538175D03*
X212980Y531088D03*
X201912Y1348187D03*
Y1360099D03*
Y1384297D03*
Y1372385D03*
Y1396583D03*
Y1408495D03*
X240412Y114655D03*
Y111255D03*
X233112Y132515D03*
Y121742D03*
X240412Y125428D03*
X233112Y118342D03*
X240412Y128828D03*
X233112Y135915D03*
X245023Y1372385D03*
X241623D03*
Y1384297D03*
X245023D03*
X264005Y467337D03*
Y470737D03*
X256705Y474424D03*
X264005Y484910D03*
X256705Y488597D03*
X264005Y481510D03*
X256705Y477824D03*
Y491997D03*
X264005Y514871D03*
X256705Y518558D03*
X264005Y511471D03*
X256705Y521958D03*
Y532731D03*
Y536131D03*
X264005Y525644D03*
Y529044D03*
Y561510D03*
X256705Y571997D03*
Y568597D03*
X264005Y564910D03*
X256705Y586171D03*
X264005Y575684D03*
Y579084D03*
X256705Y582771D03*
X264005Y589857D03*
X256705Y600344D03*
X264005Y593257D03*
Y604030D03*
X256705Y596944D03*
Y611117D03*
Y614517D03*
X264005Y607430D03*
X253863Y1348187D03*
X257263D03*
X253863Y1360099D03*
X257263D03*
X253863Y1396583D03*
X257263D03*
Y1408495D03*
X253863D03*
X278343Y1348187D03*
Y1360099D03*
X269503Y1372385D03*
X266103D03*
Y1384297D03*
X269503D03*
X278343Y1396583D03*
Y1408495D03*
X280729Y111223D03*
Y114623D03*
Y125396D03*
X291131Y121735D03*
X280729Y128796D03*
X291131Y118335D03*
Y132509D03*
Y135909D03*
X281743Y1348187D03*
Y1360099D03*
X293983Y1372385D03*
X290583Y1384297D03*
X293983D03*
X290583Y1372385D03*
X281743Y1396583D03*
Y1408495D03*
X302823Y1348187D03*
X306223D03*
Y1360099D03*
X302823D03*
Y1396583D03*
X306223D03*
X302823Y1408495D03*
X306223D03*
X320993Y467306D03*
Y470706D03*
Y481479D03*
Y484879D03*
Y514839D03*
Y511439D03*
Y525613D03*
Y529013D03*
Y564879D03*
Y561479D03*
Y575652D03*
Y579052D03*
Y603999D03*
Y593225D03*
Y589825D03*
Y607399D03*
X327303Y1348187D03*
Y1360099D03*
X315063Y1372385D03*
X318463Y1384297D03*
X315063D03*
X318463Y1372385D03*
X327303Y1396583D03*
Y1408495D03*
X342774Y111255D03*
Y114655D03*
X335474Y118342D03*
Y132515D03*
X342774Y125428D03*
X335474Y121742D03*
X342774Y128828D03*
X335474Y135915D03*
X331395Y474418D03*
Y488591D03*
Y477818D03*
Y491991D03*
Y518552D03*
Y521952D03*
Y536125D03*
Y532725D03*
Y568591D03*
Y571991D03*
Y586165D03*
Y582765D03*
Y600338D03*
Y596938D03*
Y611111D03*
Y614511D03*
X330703Y1348187D03*
Y1360099D03*
X339543Y1372385D03*
X342943D03*
Y1384297D03*
X339543D03*
X330703Y1396583D03*
Y1408495D03*
X351783Y1348187D03*
X355183D03*
Y1360099D03*
X351783D03*
Y1396583D03*
X355183D03*
X351783Y1408495D03*
X355183D03*
X364023Y1372385D03*
X367423Y1384297D03*
X364023D03*
X367423Y1372385D03*
X383091Y111223D03*
Y114623D03*
X393493Y118335D03*
X383091Y125396D03*
Y128796D03*
X393493Y132509D03*
Y121735D03*
Y135909D03*
X392415Y792725D03*
X389015D03*
X440402Y1372385D03*
Y1384297D03*
X452642Y1348187D03*
X456042D03*
Y1360099D03*
X452642D03*
X443802Y1372385D03*
Y1384297D03*
X452642Y1396583D03*
X456042D03*
X452642Y1408495D03*
X456042D03*
X464882Y1372385D03*
X468282D03*
X464882Y1384297D03*
X468282D03*
X485475Y118342D03*
Y121742D03*
Y132515D03*
Y135915D03*
X480522Y1348187D03*
X477122D03*
X480522Y1360099D03*
X477122D03*
X489362Y1372385D03*
Y1384297D03*
X480522Y1396583D03*
X477122D03*
Y1408495D03*
X480522D03*
X492775Y114655D03*
Y111255D03*
Y128828D03*
Y125428D03*
X501602Y1348187D03*
X505002D03*
X501602Y1360099D03*
X505002D03*
X492762Y1372385D03*
Y1384297D03*
X505002Y1396583D03*
X501602D03*
X505002Y1408495D03*
X501602D03*
X517242Y1372385D03*
X513842D03*
X517242Y1384297D03*
X513842D03*
X533092Y114623D03*
Y111223D03*
Y128796D03*
Y125396D03*
X529482Y1348187D03*
X526082D03*
X529482Y1360099D03*
X526082D03*
X538322Y1384297D03*
Y1372385D03*
X526082Y1396583D03*
X529482D03*
Y1408495D03*
X526082D03*
X543494Y121735D03*
Y132509D03*
Y118335D03*
Y135909D03*
X549168Y781600D03*
X545768D03*
X553962Y1348187D03*
X550562D03*
X553962Y1360099D03*
X550562D03*
X541722Y1372385D03*
Y1384297D03*
X553962Y1396583D03*
X550562D03*
X553962Y1408495D03*
X550562D03*
X566202Y1372385D03*
Y1384297D03*
X562802D03*
Y1372385D03*
X587837Y118342D03*
Y121742D03*
Y132515D03*
Y135915D03*
X595137Y111255D03*
Y114655D03*
Y125428D03*
Y128828D03*
X597776Y401513D03*
Y398113D03*
X595376Y412287D03*
Y426460D03*
Y415687D03*
Y440633D03*
Y429860D03*
Y444033D03*
Y469387D03*
Y472787D03*
Y483560D03*
Y486960D03*
Y513521D03*
Y516921D03*
Y531094D03*
Y527694D03*
X605778Y391001D03*
Y405174D03*
Y394401D03*
Y408574D03*
Y422747D03*
Y419347D03*
Y433521D03*
Y436921D03*
Y479899D03*
Y490673D03*
Y476499D03*
Y494073D03*
Y520633D03*
Y524033D03*
Y534806D03*
Y538206D03*
X635454Y114623D03*
Y111223D03*
Y128796D03*
Y125396D03*
X629688Y1396583D03*
X626288D03*
Y1408495D03*
X629688D03*
X645856Y118335D03*
Y132509D03*
Y121735D03*
Y135909D03*
X650768Y1348187D03*
Y1360099D03*
Y1384297D03*
Y1372385D03*
X638528D03*
X641928D03*
X638528Y1384297D03*
X641928D03*
Y1396583D03*
X638528D03*
X650768D03*
X638528Y1408495D03*
X641928D03*
X650768D03*
X670066Y390995D03*
Y405168D03*
X662766Y398082D03*
X670066Y408568D03*
Y394395D03*
X662766Y401482D03*
X670066Y422741D03*
Y419341D03*
X662766Y415655D03*
Y426428D03*
Y412255D03*
Y440602D03*
X670066Y433515D03*
X662766Y429828D03*
X670066Y436915D03*
X662766Y444002D03*
X670066Y469381D03*
Y472781D03*
X662766Y476468D03*
Y490641D03*
X670066Y483554D03*
Y486954D03*
X662766Y479868D03*
Y494041D03*
X670066Y516915D03*
X662766Y520602D03*
Y524002D03*
X670066Y513515D03*
Y527688D03*
X662766Y534775D03*
X670066Y531088D03*
X662766Y538175D03*
X666408Y1348187D03*
X663008D03*
X654168D03*
X666408Y1360099D03*
X663008D03*
X654168D03*
Y1384297D03*
Y1372385D03*
X663008D03*
X666408D03*
X663008Y1384297D03*
X666408D03*
Y1396583D03*
X663008D03*
X654168D03*
X666408Y1408495D03*
X663008D03*
X654168D03*
X678648Y1348187D03*
X675248D03*
X678648Y1360099D03*
X675248D03*
Y1384297D03*
X678648D03*
Y1372385D03*
X675248D03*
Y1396583D03*
X678648D03*
Y1408495D03*
X675248D03*
X697499Y114655D03*
Y111255D03*
X690199Y132515D03*
X697499Y125428D03*
Y128828D03*
X690199Y121742D03*
Y118342D03*
Y135915D03*
X690888Y1348187D03*
X687488D03*
X699728D03*
X687488Y1360099D03*
X690888D03*
X699728D03*
Y1372385D03*
Y1384297D03*
X690888Y1372385D03*
X687488D03*
Y1384297D03*
X690888D03*
Y1396583D03*
X687488D03*
X699728D03*
X687488Y1408495D03*
X690888D03*
X699728D03*
X713791Y474424D03*
Y488597D03*
Y477824D03*
Y491997D03*
Y518558D03*
Y521958D03*
Y536131D03*
Y532731D03*
Y571997D03*
Y568597D03*
Y582771D03*
Y586171D03*
Y596944D03*
Y600344D03*
Y611117D03*
Y614517D03*
X715368Y1348187D03*
X711968D03*
X703128D03*
X715368Y1360099D03*
X711968D03*
X703128D03*
Y1372385D03*
Y1384297D03*
X715368Y1372385D03*
X711968D03*
X715368Y1384297D03*
X711968D03*
X715368Y1396583D03*
X711968D03*
X703128D03*
X715368Y1408495D03*
X711968D03*
X703128D03*
X721091Y470737D03*
Y467337D03*
Y484910D03*
Y481510D03*
Y514871D03*
Y511471D03*
Y525644D03*
Y529044D03*
Y561510D03*
Y564910D03*
Y579084D03*
Y575684D03*
Y593257D03*
Y604030D03*
Y589857D03*
Y607430D03*
X727608Y1348187D03*
X724208D03*
Y1360099D03*
X727608D03*
X724208Y1372385D03*
Y1384297D03*
X727608D03*
Y1372385D03*
X724208Y1396489D03*
X727608D03*
X724208Y1408401D03*
X727608D03*
X737816Y114623D03*
Y111223D03*
X748218Y118335D03*
X737816Y128796D03*
X748218Y132509D03*
Y121735D03*
X737816Y125396D03*
X748218Y135909D03*
X739848Y1348187D03*
X736448D03*
X748688D03*
X736448Y1360099D03*
X739848D03*
X748688D03*
Y1372385D03*
Y1384297D03*
X739848Y1372385D03*
X736448D03*
X739848Y1384297D03*
X736448D03*
X739848Y1396489D03*
X736448D03*
X739848Y1408401D03*
X736448D03*
X760928Y1348187D03*
X764328D03*
X752088D03*
X764328Y1360099D03*
X760928D03*
X752088D03*
Y1372385D03*
Y1384297D03*
X764328Y1372385D03*
X760928D03*
X764328Y1384297D03*
X760928D03*
X778079Y467306D03*
Y470706D03*
Y481479D03*
Y484879D03*
Y514839D03*
Y511439D03*
Y529013D03*
Y525613D03*
Y561479D03*
Y564879D03*
Y575652D03*
Y579052D03*
Y589825D03*
Y593225D03*
Y603999D03*
Y607399D03*
X776568Y1348187D03*
X773168D03*
Y1360099D03*
X776568D03*
X799861Y114655D03*
Y111255D03*
X792561Y132515D03*
Y118342D03*
X799861Y128828D03*
X792561Y121742D03*
X799861Y125428D03*
X792561Y135915D03*
X788481Y474418D03*
Y477818D03*
Y488591D03*
Y491991D03*
Y518552D03*
Y521952D03*
Y532725D03*
Y536125D03*
Y571991D03*
Y568591D03*
Y586165D03*
Y582765D03*
Y600338D03*
Y596938D03*
Y614511D03*
Y611111D03*
X840178Y114623D03*
Y111223D03*
Y128796D03*
Y125396D03*
X850580Y118335D03*
Y132509D03*
Y121735D03*
Y135909D03*
X919163Y848442D03*
Y851592D03*
X942561Y118342D03*
Y132515D03*
Y121742D03*
Y135915D03*
X942731Y324044D03*
X939331D03*
X942700Y346363D03*
X939300D03*
X945982Y886737D03*
X949861Y111255D03*
Y114655D03*
Y125428D03*
Y128828D03*
X949382Y886737D03*
X990178Y114623D03*
Y111223D03*
Y128796D03*
Y125396D03*
X1011187Y-33526D03*
Y-30126D03*
Y-43526D03*
Y-40126D03*
X1000580Y121735D03*
Y118335D03*
Y132509D03*
Y135909D03*
X1052223Y111255D03*
Y114655D03*
X1044923Y118342D03*
X1052223Y125428D03*
Y128828D03*
X1044923Y132515D03*
Y121742D03*
Y135915D03*
X1054863Y401513D03*
Y398113D03*
X1052463Y412287D03*
Y415687D03*
Y426460D03*
Y440633D03*
Y429860D03*
Y444033D03*
Y469387D03*
Y472787D03*
Y486960D03*
Y483560D03*
Y513521D03*
Y516921D03*
Y531094D03*
Y527694D03*
X1058113Y1348187D03*
X1054713D03*
X1058113Y1360099D03*
X1054713D03*
X1058113Y1372385D03*
X1054713D03*
Y1384297D03*
X1058113D03*
X1062865Y391001D03*
Y408574D03*
Y405174D03*
Y394401D03*
Y422747D03*
Y419347D03*
Y436921D03*
Y433521D03*
Y476499D03*
Y479899D03*
Y490673D03*
Y494073D03*
Y520633D03*
Y524033D03*
Y534806D03*
Y538206D03*
X1066953Y1348187D03*
X1070353D03*
X1066953Y1360099D03*
X1070353D03*
X1066953Y1384297D03*
Y1372385D03*
X1070353D03*
Y1384297D03*
Y1396583D03*
X1066953D03*
Y1408495D03*
X1070353D03*
X1081187Y-79306D03*
Y-82706D03*
Y-72706D03*
Y-69306D03*
X1092540Y111223D03*
Y114623D03*
Y128796D03*
Y125396D03*
X1091433Y1348187D03*
X1082593D03*
X1079193D03*
X1091433Y1360099D03*
X1082593D03*
X1079193D03*
Y1372385D03*
X1082593D03*
Y1384297D03*
X1079193D03*
X1091433D03*
Y1372385D03*
Y1396583D03*
X1082593D03*
X1079193D03*
X1091433Y1408495D03*
X1082593D03*
X1079193D03*
X1102942Y118335D03*
Y132509D03*
Y121735D03*
Y135909D03*
X1094833Y1348187D03*
X1107073D03*
X1103673D03*
X1094833Y1360099D03*
X1103673D03*
X1107073D03*
Y1372385D03*
X1103673D03*
X1107073Y1384297D03*
X1103673D03*
X1094833D03*
Y1372385D03*
Y1396583D03*
X1107073D03*
X1103673D03*
X1094833Y1408495D03*
X1107073D03*
X1103673D03*
X1119853Y398082D03*
Y401482D03*
Y412255D03*
Y426428D03*
Y415655D03*
Y440602D03*
Y429828D03*
Y444002D03*
Y490641D03*
Y476468D03*
Y479868D03*
Y494041D03*
Y524002D03*
Y520602D03*
Y538175D03*
Y534775D03*
X1115913Y1348187D03*
X1119313D03*
X1115913Y1360099D03*
X1119313D03*
Y1384297D03*
X1115913Y1372385D03*
X1119313D03*
X1115913Y1384297D03*
Y1396583D03*
X1119313D03*
X1115913Y1408495D03*
X1119313D03*
X1127153Y390995D03*
Y408568D03*
Y405168D03*
Y394395D03*
Y422741D03*
Y419341D03*
Y436915D03*
Y433515D03*
Y472781D03*
Y469381D03*
Y486954D03*
Y483554D03*
Y516915D03*
Y513515D03*
Y527688D03*
Y531088D03*
X1140393Y1348187D03*
X1131553D03*
X1128153D03*
X1140393Y1360099D03*
X1131553D03*
X1128153D03*
Y1384297D03*
X1131553D03*
X1128153Y1372385D03*
X1131553D03*
X1140393Y1384297D03*
Y1372385D03*
Y1396583D03*
X1131553D03*
X1128153D03*
X1140393Y1408495D03*
X1128153D03*
X1131553D03*
X1154585Y114655D03*
Y111255D03*
Y128828D03*
X1147285Y118342D03*
Y121742D03*
Y132515D03*
X1154585Y125428D03*
X1147285Y135915D03*
X1143793Y1348187D03*
X1156033D03*
X1152633D03*
X1143793Y1360099D03*
X1152633D03*
X1156033D03*
Y1384297D03*
X1152633D03*
X1156033Y1372385D03*
X1152633D03*
X1143793D03*
Y1384297D03*
Y1396583D03*
X1156033D03*
X1152633D03*
X1143793Y1408495D03*
X1152633D03*
X1156033D03*
X1170878Y474424D03*
Y477824D03*
Y488597D03*
Y491997D03*
Y518558D03*
Y521958D03*
Y532731D03*
Y536131D03*
Y571997D03*
Y568597D03*
Y586171D03*
Y582771D03*
Y596944D03*
Y600344D03*
Y614517D03*
Y611117D03*
X1168273Y1348187D03*
X1164873D03*
Y1360099D03*
X1168273D03*
Y1384297D03*
X1164873D03*
X1168273Y1372385D03*
X1164873D03*
Y1396583D03*
X1168273D03*
Y1408495D03*
X1164873D03*
X1178178Y467337D03*
Y470737D03*
Y484910D03*
Y481510D03*
Y511471D03*
Y514871D03*
Y529044D03*
Y525644D03*
Y564910D03*
Y561510D03*
Y579084D03*
Y575684D03*
Y604030D03*
Y593257D03*
Y589857D03*
Y607430D03*
X1177113Y1348187D03*
X1180513D03*
X1177113Y1360099D03*
X1180513D03*
X1177113Y1384297D03*
X1180513D03*
X1177113Y1372385D03*
X1180513D03*
Y1396583D03*
X1177113D03*
Y1408495D03*
X1180513D03*
X1194902Y114623D03*
Y111223D03*
X1205304Y118335D03*
Y121735D03*
X1194902Y128796D03*
X1205304Y132509D03*
X1194902Y125396D03*
X1205304Y135909D03*
X1225405Y-79278D03*
Y-82678D03*
Y-72678D03*
Y-69278D03*
X1230761Y-33628D03*
Y-30228D03*
Y-43628D03*
Y-40228D03*
X1235166Y470706D03*
Y467306D03*
Y484879D03*
Y481479D03*
Y514839D03*
Y511439D03*
Y529013D03*
Y525613D03*
Y564879D03*
Y561479D03*
Y575652D03*
Y579052D03*
Y593225D03*
Y603999D03*
Y589825D03*
Y607399D03*
X1230326Y1372385D03*
X1233726D03*
X1230326Y1384297D03*
X1233726D03*
X1249647Y118342D03*
Y132515D03*
Y121742D03*
Y135915D03*
X1245568Y474418D03*
Y488591D03*
Y477818D03*
Y491991D03*
Y521952D03*
Y518552D03*
Y536125D03*
Y532725D03*
Y568591D03*
Y571991D03*
Y582765D03*
Y586165D03*
Y596938D03*
Y600338D03*
Y611111D03*
Y614511D03*
X1245966Y1348187D03*
X1242566D03*
Y1360099D03*
X1245966D03*
X1254806Y1372385D03*
Y1384297D03*
X1245966Y1396583D03*
X1242566D03*
Y1408495D03*
X1245966D03*
X1256947Y114655D03*
Y111255D03*
Y128828D03*
Y125428D03*
X1267046Y1348187D03*
X1270446D03*
Y1360099D03*
X1267046D03*
X1258206Y1372385D03*
Y1384297D03*
X1267046Y1396583D03*
X1270446D03*
Y1408495D03*
X1267046D03*
X1279286Y1372385D03*
X1282686D03*
Y1384297D03*
X1279286D03*
X1297687Y-33656D03*
Y-30256D03*
X1297264Y114623D03*
Y111223D03*
Y128796D03*
Y125396D03*
X1291526Y1348187D03*
X1294926D03*
X1291526Y1360099D03*
X1294926D03*
Y1396583D03*
X1291526D03*
Y1408495D03*
X1294926D03*
X1307666Y118335D03*
Y132509D03*
Y121735D03*
Y135909D03*
X1319406Y1348187D03*
X1316006D03*
X1319406Y1360099D03*
X1316006D03*
X1307166Y1372385D03*
X1303766D03*
Y1384297D03*
X1307166D03*
X1319406Y1396583D03*
X1316006D03*
Y1408495D03*
X1319406D03*
X1331646Y1384297D03*
Y1372385D03*
X1328246D03*
Y1384297D03*
X1337687Y-69306D03*
Y-72706D03*
X1343886Y1348187D03*
X1340486D03*
X1343886Y1360099D03*
X1340486D03*
Y1396583D03*
X1343886D03*
Y1408495D03*
X1340486D03*
X1352726Y1384297D03*
X1356126Y1372385D03*
Y1384297D03*
X1352726Y1372385D03*
X1399648Y132515D03*
Y121742D03*
Y118342D03*
Y135915D03*
X1406948Y111255D03*
Y114655D03*
Y128828D03*
Y125428D03*
X1447265Y111223D03*
Y114623D03*
Y125396D03*
Y128796D03*
X1457667Y118335D03*
Y121735D03*
Y132509D03*
Y135909D03*
X1464770Y1372385D03*
X1461370D03*
X1464770Y1384297D03*
X1461370D03*
X1481905Y-69278D03*
Y-72678D03*
X1477010Y1348187D03*
X1473610D03*
Y1360099D03*
X1477010D03*
Y1396583D03*
X1473610D03*
Y1408495D03*
X1477010D03*
X1498090Y1348187D03*
Y1360099D03*
X1489250Y1372385D03*
X1485850D03*
Y1384297D03*
X1489250D03*
X1498090Y1396583D03*
Y1408495D03*
X1509310Y114655D03*
Y111255D03*
X1502010Y121742D03*
X1509310Y125428D03*
Y128828D03*
X1502010Y118342D03*
Y132515D03*
Y135915D03*
X1511950Y401513D03*
Y398113D03*
X1509550Y412287D03*
Y415687D03*
Y426460D03*
Y440633D03*
Y429860D03*
Y444033D03*
Y472787D03*
Y469387D03*
Y483560D03*
Y486960D03*
Y516921D03*
Y513521D03*
Y527694D03*
Y531094D03*
X1501490Y1348187D03*
Y1360099D03*
X1510330Y1372385D03*
X1513730D03*
Y1384297D03*
X1510330D03*
X1501490Y1396583D03*
Y1408495D03*
X1517261Y-33758D03*
Y-30358D03*
X1519952Y391001D03*
Y394401D03*
Y408574D03*
Y405174D03*
Y422747D03*
Y419347D03*
Y436921D03*
Y433521D03*
Y479899D03*
Y476499D03*
Y490673D03*
Y494073D03*
Y520633D03*
Y524033D03*
Y534806D03*
Y538206D03*
X1525970Y1348187D03*
X1522570D03*
Y1360099D03*
X1525970D03*
X1522570Y1396583D03*
X1525970D03*
Y1408495D03*
X1522570D03*
X1547050Y1348187D03*
Y1360099D03*
X1538210Y1372385D03*
X1534810D03*
Y1384297D03*
X1538210D03*
X1547050Y1396583D03*
Y1408495D03*
X1549627Y111223D03*
Y114623D03*
Y128796D03*
X1560029Y132509D03*
Y121735D03*
Y118335D03*
X1549627Y125396D03*
X1560029Y135909D03*
X1550450Y1348187D03*
Y1360099D03*
X1562690Y1372385D03*
X1559290D03*
X1562690Y1384297D03*
X1559290D03*
X1550450Y1396583D03*
Y1408495D03*
X1576940Y398082D03*
Y401482D03*
Y415655D03*
Y412255D03*
Y426428D03*
Y440602D03*
Y429828D03*
Y444002D03*
Y476468D03*
Y490641D03*
Y479868D03*
Y494041D03*
Y520602D03*
Y524002D03*
Y534775D03*
Y538175D03*
X1574930Y1348187D03*
X1571530D03*
X1574930Y1360099D03*
X1571530D03*
Y1396583D03*
X1574930D03*
X1571530Y1408495D03*
X1574930D03*
X1592187Y-79306D03*
Y-82706D03*
Y-69306D03*
Y-72706D03*
X1582187Y-33786D03*
Y-43786D03*
Y-30386D03*
Y-40386D03*
X1584240Y390995D03*
Y408568D03*
Y405168D03*
Y394395D03*
Y419341D03*
Y422741D03*
Y433515D03*
Y436915D03*
Y472781D03*
Y469381D03*
Y483554D03*
Y486954D03*
Y516915D03*
Y513515D03*
Y531088D03*
Y527688D03*
X1587170Y1372385D03*
X1583770D03*
Y1384297D03*
X1587170D03*
X1611672Y111255D03*
Y114655D03*
X1604372Y118342D03*
X1611672Y125428D03*
X1604372Y121742D03*
X1611672Y128828D03*
X1604372Y132515D03*
Y135915D03*
X1611398Y1348187D03*
Y1360099D03*
Y1384297D03*
Y1372385D03*
X1627965Y474424D03*
Y488597D03*
Y477824D03*
Y491997D03*
Y521958D03*
Y518558D03*
Y536131D03*
Y532731D03*
Y571997D03*
Y568597D03*
Y582771D03*
Y586171D03*
Y596944D03*
Y600344D03*
Y614517D03*
Y611117D03*
X1614798Y1348187D03*
X1623638D03*
X1627038D03*
X1614798Y1360099D03*
X1623638D03*
X1627038D03*
Y1372385D03*
X1623638D03*
X1627038Y1384297D03*
X1623638D03*
X1614798Y1372385D03*
Y1384297D03*
X1627038Y1396583D03*
X1623638D03*
X1627038Y1408495D03*
X1623638D03*
X1635265Y470737D03*
Y467337D03*
Y484910D03*
Y481510D03*
Y514871D03*
Y511471D03*
Y529044D03*
Y525644D03*
Y564910D03*
Y561510D03*
Y575684D03*
Y579084D03*
Y593257D03*
Y604030D03*
Y589857D03*
Y607430D03*
X1639278Y1348187D03*
X1635878D03*
X1639278Y1360099D03*
X1635878D03*
Y1384297D03*
X1639278D03*
Y1372385D03*
X1635878D03*
X1639278Y1396583D03*
X1635878D03*
Y1408495D03*
X1639278D03*
X1651989Y114623D03*
Y111223D03*
Y125396D03*
Y128796D03*
X1660358Y1348187D03*
X1651518D03*
X1648118D03*
X1660358Y1360099D03*
X1651518D03*
X1648118D03*
Y1372385D03*
X1651518D03*
X1648118Y1384297D03*
X1651518D03*
X1660358D03*
Y1372385D03*
Y1396583D03*
X1651518D03*
X1648118D03*
X1660358Y1408495D03*
X1648118D03*
X1651518D03*
X1662391Y118335D03*
Y121735D03*
Y132509D03*
Y135909D03*
X1663758Y1348187D03*
X1672598D03*
X1675998D03*
X1663758Y1360099D03*
X1675998D03*
X1672598D03*
X1675998Y1372385D03*
X1672598D03*
Y1384297D03*
X1675998D03*
X1663758D03*
Y1372385D03*
Y1396583D03*
X1675998D03*
X1672598D03*
X1663758Y1408495D03*
X1675998D03*
X1672598D03*
X1692253Y467306D03*
Y470706D03*
Y484879D03*
Y481479D03*
Y511439D03*
Y514839D03*
Y529013D03*
Y525613D03*
Y561479D03*
Y564879D03*
Y575652D03*
Y579052D03*
Y593225D03*
Y603999D03*
Y589825D03*
Y607399D03*
X1688238Y1348187D03*
X1684838D03*
X1688238Y1360099D03*
X1684838D03*
Y1384297D03*
X1688238D03*
X1684838Y1372385D03*
X1688238D03*
X1684838Y1396583D03*
X1688238D03*
Y1408495D03*
X1684838D03*
X1706734Y118342D03*
Y132515D03*
Y121742D03*
Y135915D03*
X1702655Y474418D03*
Y477818D03*
Y488591D03*
Y491991D03*
Y521952D03*
Y518552D03*
Y536125D03*
Y532725D03*
Y571991D03*
Y568591D03*
Y586165D03*
Y582765D03*
Y600338D03*
Y596938D03*
Y611111D03*
Y614511D03*
X1709318Y1348187D03*
X1700478D03*
X1697078D03*
X1709318Y1360099D03*
X1697078D03*
X1700478D03*
X1697078Y1372385D03*
X1700478D03*
X1697078Y1384297D03*
X1700478D03*
X1709318D03*
Y1372385D03*
Y1396583D03*
X1700478D03*
X1697078D03*
X1709318Y1408495D03*
X1697078D03*
X1700478D03*
X1714034Y111255D03*
Y114655D03*
Y125428D03*
Y128828D03*
X1712718Y1348187D03*
X1721558D03*
X1724958D03*
X1712718Y1360099D03*
X1724958D03*
X1721558D03*
Y1372385D03*
X1724958D03*
Y1384297D03*
X1721558D03*
X1712718Y1372385D03*
Y1384297D03*
Y1396583D03*
X1721558D03*
X1724958D03*
X1712718Y1408495D03*
X1721558D03*
X1724958D03*
X1736405Y-79278D03*
Y-82678D03*
Y-69278D03*
Y-72678D03*
X1733798Y1348187D03*
X1737198D03*
X1733798Y1360099D03*
X1737198D03*
Y1384297D03*
X1733798D03*
Y1372385D03*
X1737198D03*
Y1396583D03*
X1733798D03*
X1737198Y1408495D03*
X1733798D03*
X1754351Y111223D03*
Y114623D03*
Y128796D03*
Y125396D03*
X1764753Y121735D03*
Y118335D03*
Y132509D03*
Y135909D03*
X1801761Y-33888D03*
Y-43888D03*
Y-30488D03*
Y-40488D03*
G54D11*
X13780Y1226024D03*
X79331Y1186654D03*
X390354Y1141024D03*
X536418Y1086654D03*
X854291Y1225118D03*
X993504Y1170748D03*
X1304528Y1141024D03*
X1450591Y1086654D03*
X1761614Y1215000D03*
X1827165Y1235630D03*
G54D44*
X661674Y23622D03*
G54D19*
X23622Y1604724D03*
X62205Y765197D03*
X74016Y333464D03*
X102224Y70866D03*
X409488Y1604724D03*
X433130Y70866D03*
X463387Y286221D03*
X463386Y765197D03*
X785039Y1547638D03*
X890217Y23622D03*
X920473Y765196D03*
X1055905Y1547637D03*
X1118760Y23622D03*
X1347303Y70866D03*
X1377559Y286220D03*
Y765197D03*
X1431457Y1604724D03*
X1575846Y23622D03*
X1766929Y333464D03*
X1778740Y765197D03*
X1795010Y23622D03*
X1817323Y1604724D03*
G54D20*
X28819Y81575D03*
X73307Y61614D03*
X131181Y81575D03*
X175669Y61614D03*
X233543Y81575D03*
X278032Y61614D03*
X335906Y81575D03*
X380394Y61614D03*
X485886Y81595D03*
X530394Y61614D03*
X588248Y81594D03*
X632756Y61614D03*
X690611Y81595D03*
X735118Y61614D03*
X792973Y81595D03*
X837480Y61614D03*
X942973Y81595D03*
X987480Y61614D03*
X1045335Y81595D03*
X1089843Y61614D03*
X1147697Y81595D03*
X1192205Y61614D03*
X1250060Y81595D03*
X1294567Y61614D03*
X1400060Y81595D03*
X1444567Y61614D03*
X1502441Y81575D03*
X1546929Y61614D03*
X1604784Y81595D03*
X1649291Y61614D03*
X1707146Y81595D03*
X1751654Y61614D03*
G54D32*
X109882Y1458622D03*
Y1463741D03*
Y1473977D03*
Y1479095D03*
Y1504685D03*
Y1509804D03*
Y1560985D03*
Y1566103D03*
Y1576339D03*
Y1581457D03*
Y1607048D03*
Y1612166D03*
X127205Y1458622D03*
Y1463741D03*
X118543Y1462953D03*
X127205Y1473977D03*
Y1479095D03*
X118543Y1468071D03*
Y1478308D03*
Y1483426D03*
X127205Y1504685D03*
Y1509804D03*
X118543Y1509016D03*
Y1514134D03*
X127205Y1560985D03*
Y1566103D03*
Y1576339D03*
X118543Y1565315D03*
Y1570434D03*
X127205Y1581457D03*
X118543Y1580670D03*
Y1585788D03*
X127205Y1607048D03*
Y1612166D03*
X118543Y1611378D03*
Y1616496D03*
X144528Y1458622D03*
Y1463741D03*
X135866Y1462953D03*
X144528Y1473977D03*
Y1479095D03*
X135866Y1468071D03*
Y1478308D03*
Y1483426D03*
X144528Y1504685D03*
Y1509804D03*
X135866Y1509016D03*
Y1514134D03*
X144528Y1560985D03*
Y1566103D03*
Y1576339D03*
X135866Y1565315D03*
Y1570434D03*
X144528Y1581457D03*
X135866Y1580670D03*
Y1585788D03*
X144528Y1607048D03*
Y1612166D03*
X135866Y1611378D03*
Y1616496D03*
X161850Y1458622D03*
Y1463741D03*
X153189Y1462953D03*
X161850Y1473977D03*
Y1479095D03*
X153189Y1468071D03*
Y1478308D03*
Y1483426D03*
X161850Y1504685D03*
Y1509804D03*
X153189Y1509016D03*
Y1514134D03*
X161850Y1560985D03*
Y1566103D03*
Y1576339D03*
X153189Y1565315D03*
Y1570434D03*
X161850Y1581457D03*
X153189Y1580670D03*
Y1585788D03*
X161850Y1607048D03*
Y1612166D03*
X153189Y1611378D03*
Y1616496D03*
X170512Y1462953D03*
Y1468071D03*
Y1478308D03*
Y1483426D03*
Y1509016D03*
Y1514134D03*
Y1565315D03*
Y1570434D03*
Y1580670D03*
Y1585788D03*
Y1611378D03*
Y1616496D03*
X187835Y1596024D03*
Y1601142D03*
Y1611378D03*
Y1616496D03*
X283110Y1458622D03*
X291771Y1462953D03*
X283110Y1463741D03*
X291771Y1468071D03*
X283110Y1473977D03*
X291771Y1478308D03*
X283110Y1479095D03*
X291771Y1483426D03*
X283110Y1489331D03*
X291771Y1493662D03*
X283110Y1494449D03*
X291771Y1498780D03*
X283110Y1560985D03*
X291771Y1565315D03*
X283110Y1566103D03*
X291771Y1570434D03*
X283110Y1576339D03*
X291771Y1580670D03*
X283110Y1581457D03*
X291771Y1585788D03*
X283110Y1591693D03*
X291771Y1596024D03*
X283110Y1596811D03*
X291771Y1601142D03*
X300433Y1458622D03*
X309094Y1462953D03*
X300433Y1463741D03*
X309094Y1468071D03*
X300433Y1473977D03*
X309094Y1478308D03*
X300433Y1479095D03*
X309094Y1483426D03*
X300433Y1489331D03*
X309094Y1493662D03*
X300433Y1494449D03*
X309094Y1498780D03*
X300433Y1560985D03*
X309094Y1565315D03*
X300433Y1566103D03*
X309094Y1570434D03*
X300433Y1576339D03*
X309094Y1580670D03*
X300433Y1581457D03*
X309094Y1585788D03*
X300433Y1591693D03*
X309094Y1596024D03*
X300433Y1596811D03*
X309094Y1601142D03*
X317756Y1458622D03*
X326417Y1462953D03*
X317756Y1463741D03*
X326417Y1468071D03*
X317756Y1473977D03*
X326417Y1478308D03*
X317756Y1479095D03*
X326417Y1483426D03*
X317756Y1489331D03*
X326417Y1493662D03*
X317756Y1494449D03*
X326417Y1498780D03*
X317756Y1560985D03*
X326417Y1565315D03*
X317756Y1566103D03*
X326417Y1570434D03*
X317756Y1576339D03*
X326417Y1580670D03*
X317756Y1581457D03*
X326417Y1585788D03*
X317756Y1591693D03*
X326417Y1596024D03*
X317756Y1596811D03*
X326417Y1601142D03*
X335078Y1458622D03*
X343740Y1462953D03*
X335078Y1463741D03*
X343740Y1468071D03*
X335078Y1473977D03*
X343740Y1478308D03*
X335078Y1479095D03*
X343740Y1483426D03*
X335078Y1489331D03*
X343740Y1493662D03*
X335078Y1494449D03*
X343740Y1498780D03*
X335078Y1560985D03*
X343740Y1565315D03*
X335078Y1566103D03*
X343740Y1570434D03*
X335078Y1576339D03*
X343740Y1580670D03*
X335078Y1581457D03*
X343740Y1585788D03*
X335078Y1591693D03*
X343740Y1596024D03*
X335078Y1596811D03*
X343740Y1601142D03*
X361063Y1596024D03*
Y1601142D03*
Y1611378D03*
Y1616496D03*
X456339Y1473977D03*
Y1479095D03*
Y1504685D03*
Y1509804D03*
Y1560985D03*
Y1566103D03*
Y1591693D03*
Y1596811D03*
X473662Y1473977D03*
Y1479095D03*
X465000Y1478308D03*
Y1483426D03*
X473662Y1504685D03*
Y1509804D03*
X465000Y1509016D03*
Y1514134D03*
X473662Y1560985D03*
Y1566103D03*
X465000Y1565315D03*
Y1570434D03*
X473662Y1591693D03*
X465000Y1596024D03*
X473662Y1596811D03*
X465000Y1601142D03*
X490985Y1473977D03*
Y1479095D03*
X482323Y1478308D03*
Y1483426D03*
X490985Y1504685D03*
Y1509804D03*
X482323Y1509016D03*
Y1514134D03*
X490985Y1560985D03*
Y1566103D03*
X482323Y1565315D03*
Y1570434D03*
X490985Y1591693D03*
X482323Y1596024D03*
X490985Y1596811D03*
X482323Y1601142D03*
X499646Y1478308D03*
Y1483426D03*
Y1509016D03*
Y1514134D03*
Y1565315D03*
Y1570434D03*
Y1596024D03*
Y1601142D03*
X508307Y1473977D03*
X516969Y1478308D03*
X508307Y1479095D03*
X516969Y1483426D03*
X508307Y1504685D03*
X516969Y1509016D03*
X508307Y1509804D03*
X516969Y1514134D03*
X508307Y1560985D03*
X516969Y1565315D03*
X508307Y1566103D03*
X516969Y1570434D03*
X508307Y1591693D03*
X516969Y1596024D03*
X508307Y1596811D03*
X516969Y1601142D03*
X629567Y1458622D03*
Y1463741D03*
Y1473977D03*
Y1479095D03*
Y1489331D03*
Y1494449D03*
Y1504685D03*
Y1509804D03*
Y1560985D03*
Y1566103D03*
Y1576339D03*
Y1581457D03*
Y1591693D03*
Y1596811D03*
Y1607048D03*
Y1612166D03*
X646890Y1458622D03*
Y1463741D03*
X638228Y1462953D03*
X646890Y1473977D03*
Y1479095D03*
X638228Y1468071D03*
Y1478308D03*
X646890Y1489331D03*
Y1494449D03*
X638228Y1483426D03*
Y1493662D03*
Y1498780D03*
X646890Y1504685D03*
Y1509804D03*
X638228Y1509016D03*
Y1514134D03*
X646890Y1560985D03*
Y1566103D03*
Y1576339D03*
X638228Y1565315D03*
Y1570434D03*
X646890Y1581457D03*
Y1591693D03*
X638228Y1580670D03*
Y1585788D03*
Y1596024D03*
X646890Y1596811D03*
Y1607048D03*
Y1612166D03*
X638228Y1601142D03*
Y1611378D03*
Y1616496D03*
X664213Y1458622D03*
Y1463741D03*
X655551Y1462953D03*
X664213Y1473977D03*
Y1479095D03*
X655551Y1468071D03*
Y1478308D03*
X664213Y1489331D03*
Y1494449D03*
X655551Y1483426D03*
Y1493662D03*
Y1498780D03*
X664213Y1504685D03*
Y1509804D03*
X655551Y1509016D03*
Y1514134D03*
X664213Y1560985D03*
Y1566103D03*
Y1576339D03*
X655551Y1565315D03*
Y1570434D03*
X664213Y1581457D03*
Y1591693D03*
X655551Y1580670D03*
Y1585788D03*
Y1596024D03*
X664213Y1596811D03*
Y1607048D03*
Y1612166D03*
X655551Y1601142D03*
Y1611378D03*
Y1616496D03*
X681535Y1458622D03*
Y1463741D03*
X672874Y1462953D03*
X681535Y1473977D03*
Y1479095D03*
X672874Y1468071D03*
Y1478308D03*
X681535Y1489331D03*
Y1494449D03*
X672874Y1483426D03*
Y1493662D03*
Y1498780D03*
X681535Y1504685D03*
Y1509804D03*
X672874Y1509016D03*
Y1514134D03*
X681535Y1560985D03*
Y1566103D03*
Y1576339D03*
X672874Y1565315D03*
Y1570434D03*
X681535Y1581457D03*
Y1591693D03*
X672874Y1580670D03*
Y1585788D03*
Y1596024D03*
X681535Y1596811D03*
Y1607048D03*
Y1612166D03*
X672874Y1601142D03*
Y1611378D03*
Y1616496D03*
X690197Y1462953D03*
Y1468071D03*
Y1478308D03*
Y1483426D03*
Y1493662D03*
Y1498780D03*
Y1509016D03*
Y1514134D03*
Y1565315D03*
Y1570434D03*
Y1580670D03*
Y1585788D03*
Y1596024D03*
Y1601142D03*
Y1611378D03*
Y1616496D03*
X1131850Y1458622D03*
X1140511Y1462953D03*
X1131850Y1463741D03*
X1140511Y1468071D03*
X1131850Y1473977D03*
X1140511Y1478308D03*
X1131850Y1479095D03*
X1140511Y1483426D03*
X1131850Y1504685D03*
X1140511Y1509016D03*
X1131850Y1509804D03*
X1140511Y1514134D03*
X1131850Y1560985D03*
X1140511Y1565315D03*
X1131850Y1566103D03*
X1140511Y1570434D03*
X1131850Y1576339D03*
X1140511Y1580670D03*
X1131850Y1581457D03*
X1140511Y1585788D03*
X1131850Y1607048D03*
X1140511Y1611378D03*
X1131850Y1612166D03*
X1140511Y1616496D03*
X1149173Y1458622D03*
Y1463741D03*
Y1473977D03*
Y1479095D03*
Y1504685D03*
Y1509804D03*
Y1560985D03*
Y1566103D03*
Y1576339D03*
Y1581457D03*
Y1607048D03*
Y1612166D03*
X1166496Y1458622D03*
Y1463741D03*
X1157834Y1462953D03*
X1166496Y1473977D03*
Y1479095D03*
X1157834Y1468071D03*
Y1478308D03*
Y1483426D03*
X1166496Y1504685D03*
Y1509804D03*
X1157834Y1509016D03*
Y1514134D03*
X1166496Y1560985D03*
Y1566103D03*
Y1576339D03*
X1157834Y1565315D03*
Y1570434D03*
X1166496Y1581457D03*
X1157834Y1580670D03*
Y1585788D03*
X1166496Y1607048D03*
Y1612166D03*
X1157834Y1611378D03*
Y1616496D03*
X1183818Y1458622D03*
Y1463741D03*
X1175157Y1462953D03*
X1183818Y1473977D03*
Y1479095D03*
X1175157Y1468071D03*
Y1478308D03*
Y1483426D03*
X1183818Y1504685D03*
Y1509804D03*
X1175157Y1509016D03*
Y1514134D03*
X1183818Y1560985D03*
Y1566103D03*
Y1576339D03*
X1175157Y1565315D03*
Y1570434D03*
X1183818Y1581457D03*
X1175157Y1580670D03*
Y1585788D03*
X1183818Y1607048D03*
Y1612166D03*
X1175157Y1611378D03*
Y1616496D03*
X1192480Y1462953D03*
Y1468071D03*
Y1478308D03*
Y1483426D03*
Y1509016D03*
Y1514134D03*
Y1565315D03*
Y1570434D03*
Y1580670D03*
Y1585788D03*
Y1611378D03*
Y1616496D03*
X1305079Y1458622D03*
X1313740Y1462953D03*
X1305079Y1463741D03*
X1313740Y1468071D03*
X1305079Y1473977D03*
X1313740Y1478308D03*
X1305079Y1479095D03*
X1313740Y1483426D03*
X1305079Y1489331D03*
X1313740Y1493662D03*
X1305079Y1494449D03*
X1313740Y1498780D03*
X1305079Y1560985D03*
X1313740Y1565315D03*
X1305079Y1566103D03*
X1313740Y1570434D03*
X1305079Y1576339D03*
X1313740Y1580670D03*
X1305079Y1581457D03*
X1313740Y1585788D03*
X1305079Y1591693D03*
X1313740Y1596024D03*
X1305079Y1596811D03*
X1313740Y1601142D03*
X1322402Y1458622D03*
X1331063Y1462953D03*
X1322402Y1463741D03*
X1331063Y1468071D03*
X1322402Y1473977D03*
X1331063Y1478308D03*
X1322402Y1479095D03*
X1331063Y1483426D03*
X1322402Y1489331D03*
X1331063Y1493662D03*
X1322402Y1494449D03*
X1331063Y1498780D03*
X1322402Y1560985D03*
X1331063Y1565315D03*
X1322402Y1566103D03*
X1331063Y1570434D03*
X1322402Y1576339D03*
X1331063Y1580670D03*
X1322402Y1581457D03*
X1331063Y1585788D03*
X1322402Y1591693D03*
X1331063Y1596024D03*
X1322402Y1596811D03*
X1331063Y1601142D03*
X1339725Y1458622D03*
X1348386Y1462953D03*
X1339725Y1463741D03*
X1348386Y1468071D03*
X1339725Y1473977D03*
X1348386Y1478308D03*
X1339725Y1479095D03*
X1348386Y1483426D03*
X1339725Y1489331D03*
X1348386Y1493662D03*
X1339725Y1494449D03*
X1348386Y1498780D03*
X1339725Y1560985D03*
X1348386Y1565315D03*
X1339725Y1566103D03*
X1348386Y1570434D03*
X1339725Y1576339D03*
X1348386Y1580670D03*
X1339725Y1581457D03*
X1348386Y1585788D03*
X1339725Y1591693D03*
X1348386Y1596024D03*
X1339725Y1596811D03*
X1348386Y1601142D03*
X1357047Y1458622D03*
X1365709Y1462953D03*
X1357047Y1463741D03*
X1365709Y1468071D03*
X1357047Y1473977D03*
X1365709Y1478308D03*
X1357047Y1479095D03*
X1365709Y1483426D03*
X1357047Y1489331D03*
X1365709Y1493662D03*
X1357047Y1494449D03*
X1365709Y1498780D03*
X1357047Y1560985D03*
X1365709Y1565315D03*
X1357047Y1566103D03*
X1365709Y1570434D03*
X1357047Y1576339D03*
X1365709Y1580670D03*
X1357047Y1581457D03*
X1365709Y1585788D03*
X1357047Y1591693D03*
X1365709Y1596024D03*
X1357047Y1596811D03*
X1365709Y1601142D03*
X1478307Y1473977D03*
Y1479095D03*
Y1504685D03*
Y1509804D03*
Y1560985D03*
Y1566103D03*
Y1591693D03*
Y1596811D03*
X1495630Y1473977D03*
Y1479095D03*
X1486968Y1478308D03*
Y1483426D03*
X1495630Y1504685D03*
Y1509804D03*
X1486968Y1509016D03*
Y1514134D03*
X1495630Y1560985D03*
Y1566103D03*
X1486968Y1565315D03*
Y1570434D03*
X1495630Y1591693D03*
X1486968Y1596024D03*
X1495630Y1596811D03*
X1486968Y1601142D03*
X1512953Y1473977D03*
Y1479095D03*
X1504291Y1478308D03*
Y1483426D03*
X1512953Y1504685D03*
Y1509804D03*
X1504291Y1509016D03*
Y1514134D03*
X1512953Y1560985D03*
Y1566103D03*
X1504291Y1565315D03*
Y1570434D03*
X1512953Y1591693D03*
X1504291Y1596024D03*
X1512953Y1596811D03*
X1504291Y1601142D03*
X1530275Y1473977D03*
Y1479095D03*
X1521614Y1478308D03*
Y1483426D03*
X1530275Y1504685D03*
Y1509804D03*
X1521614Y1509016D03*
Y1514134D03*
X1530275Y1560985D03*
Y1566103D03*
X1521614Y1565315D03*
Y1570434D03*
X1530275Y1591693D03*
X1521614Y1596024D03*
X1530275Y1596811D03*
X1521614Y1601142D03*
X1538937Y1478308D03*
Y1483426D03*
Y1509016D03*
Y1514134D03*
Y1565315D03*
Y1570434D03*
Y1596024D03*
Y1601142D03*
X1651535Y1458622D03*
X1660196Y1462953D03*
X1651535Y1463741D03*
X1660196Y1468071D03*
X1651535Y1473977D03*
X1660196Y1478308D03*
X1651535Y1479095D03*
X1660196Y1483426D03*
X1651535Y1489331D03*
X1660196Y1493662D03*
X1651535Y1494449D03*
X1660196Y1498780D03*
X1651535Y1504685D03*
X1660196Y1509016D03*
X1651535Y1509804D03*
X1660196Y1514134D03*
X1651535Y1560985D03*
X1660196Y1565315D03*
X1651535Y1566103D03*
X1660196Y1570434D03*
X1651535Y1576339D03*
X1660196Y1580670D03*
X1651535Y1581457D03*
X1660196Y1585788D03*
X1651535Y1591693D03*
X1660196Y1596024D03*
X1651535Y1596811D03*
X1660196Y1601142D03*
X1651535Y1607048D03*
X1660196Y1611378D03*
X1651535Y1612166D03*
X1660196Y1616496D03*
X1668858Y1458622D03*
Y1463741D03*
Y1473977D03*
Y1479095D03*
Y1489331D03*
Y1494449D03*
Y1504685D03*
Y1509804D03*
Y1560985D03*
Y1566103D03*
Y1576339D03*
Y1581457D03*
Y1591693D03*
Y1596811D03*
Y1607048D03*
Y1612166D03*
X1686181Y1458622D03*
Y1463741D03*
X1677519Y1462953D03*
X1686181Y1473977D03*
Y1479095D03*
X1677519Y1468071D03*
Y1478308D03*
X1686181Y1489331D03*
Y1494449D03*
X1677519Y1483426D03*
Y1493662D03*
Y1498780D03*
X1686181Y1504685D03*
Y1509804D03*
X1677519Y1509016D03*
Y1514134D03*
X1686181Y1560985D03*
Y1566103D03*
Y1576339D03*
X1677519Y1565315D03*
Y1570434D03*
X1686181Y1581457D03*
Y1591693D03*
X1677519Y1580670D03*
Y1585788D03*
Y1596024D03*
X1686181Y1596811D03*
Y1607048D03*
Y1612166D03*
X1677519Y1601142D03*
Y1611378D03*
Y1616496D03*
X1703503Y1458622D03*
Y1463741D03*
X1694842Y1462953D03*
X1703503Y1473977D03*
Y1479095D03*
X1694842Y1468071D03*
Y1478308D03*
X1703503Y1489331D03*
Y1494449D03*
X1694842Y1483426D03*
Y1493662D03*
Y1498780D03*
X1703503Y1504685D03*
Y1509804D03*
X1694842Y1509016D03*
Y1514134D03*
X1703503Y1560985D03*
Y1566103D03*
Y1576339D03*
X1694842Y1565315D03*
Y1570434D03*
X1703503Y1581457D03*
Y1591693D03*
X1694842Y1580670D03*
Y1585788D03*
Y1596024D03*
X1703503Y1596811D03*
Y1607048D03*
Y1612166D03*
X1694842Y1601142D03*
Y1611378D03*
Y1616496D03*
X1712165Y1462953D03*
Y1468071D03*
Y1478308D03*
Y1483426D03*
Y1493662D03*
Y1498780D03*
Y1509016D03*
Y1514134D03*
Y1565315D03*
Y1570434D03*
Y1580670D03*
Y1585788D03*
Y1596024D03*
Y1601142D03*
Y1611378D03*
Y1616496D03*
G54D37*
X173829Y455492D03*
Y583957D03*
X202844Y455492D03*
Y583957D03*
X630915Y455492D03*
Y583957D03*
X659930Y455492D03*
Y583957D03*
X1088002Y455492D03*
Y583957D03*
X1117017Y455492D03*
Y583957D03*
X1545089Y455492D03*
Y583957D03*
X1574104Y455492D03*
Y583957D03*
G54D61*
X1795453Y812874D03*
Y834922D03*
G54D48*
X849441Y1367717D03*
G54D50*
X895384Y228740D03*
Y276772D03*
X923336Y226772D03*
Y278740D03*
G54D55*
X1030635Y764546D03*
G54D62*
X1803917Y823898D03*
G54D59*
X1747253Y1715189D03*
Y1744208D03*
X1747246Y1773377D03*
G54D60*
X1747253Y1802909D03*
G54D63*
X1817323Y1567323D03*
G54D13*
X19685Y-83298D03*
Y1801195D03*
X1821260Y-83298D03*
Y1801195D03*
G54D29*
X116731Y1066535D03*
Y1263386D03*
X352952Y1066535D03*
Y1263386D03*
X573818Y1066535D03*
Y1263386D03*
X810038Y1066535D03*
Y1263386D03*
X1030905Y1066535D03*
Y1263386D03*
X1267125Y1066535D03*
Y1263386D03*
X1487991Y1066535D03*
Y1263386D03*
X1724212Y1066535D03*
Y1263386D03*
G54D17*
X26789Y1373669D03*
X184851Y334492D03*
X235433Y1580079D03*
Y1626339D03*
X581890Y1580079D03*
Y1626339D03*
X1259055Y1580079D03*
Y1626339D03*
X1605512Y1580079D03*
Y1626339D03*
X1796847Y1517889D03*
X1809883Y120792D03*
G54D47*
X770472Y1490945D03*
X820079Y388583D03*
X1020866D03*
X1070472Y1490945D03*
G54D31*
X109882Y1453504D03*
Y1468859D03*
Y1484213D03*
Y1499567D03*
Y1514922D03*
Y1555867D03*
Y1571221D03*
Y1586575D03*
Y1601930D03*
Y1617284D03*
X127205Y1453504D03*
X118543Y1457835D03*
X127205Y1468859D03*
X118543Y1473189D03*
X127205Y1484213D03*
X118543Y1488544D03*
X127205Y1499567D03*
Y1514922D03*
X118543Y1503898D03*
Y1519252D03*
X127205Y1555867D03*
X118543Y1560197D03*
X127205Y1571221D03*
X118543Y1575552D03*
X127205Y1586575D03*
X118543Y1590906D03*
X127205Y1601930D03*
X118543Y1606260D03*
X127205Y1617284D03*
X118543Y1621615D03*
X144528Y1453504D03*
X135866Y1457835D03*
X144528Y1468859D03*
X135866Y1473189D03*
X144528Y1484213D03*
X135866Y1488544D03*
X144528Y1499567D03*
Y1514922D03*
X135866Y1503898D03*
Y1519252D03*
X144528Y1555867D03*
X135866Y1560197D03*
X144528Y1571221D03*
X135866Y1575552D03*
X144528Y1586575D03*
X135866Y1590906D03*
X144528Y1601930D03*
X135866Y1606260D03*
X144528Y1617284D03*
X135866Y1621615D03*
X161850Y1453504D03*
X153189Y1457835D03*
X161850Y1468859D03*
X153189Y1473189D03*
X161850Y1484213D03*
X153189Y1488544D03*
X161850Y1499567D03*
Y1514922D03*
X153189Y1503898D03*
Y1519252D03*
X161850Y1555867D03*
X153189Y1560197D03*
X161850Y1571221D03*
X153189Y1575552D03*
X161850Y1586575D03*
X153189Y1590906D03*
X161850Y1601930D03*
X153189Y1606260D03*
X161850Y1617284D03*
X153189Y1621615D03*
X179173Y1453504D03*
X170512Y1457835D03*
X179173Y1468859D03*
X170512Y1473189D03*
X179173Y1484213D03*
X170512Y1488544D03*
X179173Y1499567D03*
Y1514922D03*
X170512Y1503898D03*
Y1519252D03*
X179173Y1555867D03*
X170512Y1560197D03*
X179173Y1571221D03*
X170512Y1575552D03*
X179173Y1586575D03*
X170512Y1590906D03*
X179173Y1601930D03*
X170512Y1606260D03*
X179173Y1617284D03*
X170512Y1621615D03*
X187835Y1457835D03*
Y1473189D03*
Y1488544D03*
Y1503898D03*
Y1519252D03*
Y1560197D03*
Y1575552D03*
Y1590906D03*
Y1606260D03*
Y1621615D03*
X283110Y1453504D03*
X291771Y1457835D03*
X283110Y1468859D03*
X291771Y1473189D03*
X283110Y1484213D03*
X291771Y1488544D03*
X283110Y1499567D03*
X291771Y1503898D03*
X283110Y1514922D03*
X291771Y1519252D03*
X283110Y1555867D03*
X291771Y1560197D03*
X283110Y1571221D03*
X291771Y1575552D03*
X283110Y1586575D03*
X291771Y1590906D03*
X283110Y1601930D03*
X291771Y1606260D03*
X283110Y1617284D03*
X291771Y1621615D03*
X300433Y1453504D03*
X309094Y1457835D03*
X300433Y1468859D03*
X309094Y1473189D03*
X300433Y1484213D03*
X309094Y1488544D03*
X300433Y1499567D03*
X309094Y1503898D03*
X300433Y1514922D03*
X309094Y1519252D03*
X300433Y1555867D03*
X309094Y1560197D03*
X300433Y1571221D03*
X309094Y1575552D03*
X300433Y1586575D03*
X309094Y1590906D03*
X300433Y1601930D03*
X309094Y1606260D03*
X300433Y1617284D03*
X309094Y1621615D03*
X317756Y1453504D03*
X326417Y1457835D03*
X317756Y1468859D03*
X326417Y1473189D03*
X317756Y1484213D03*
X326417Y1488544D03*
X317756Y1499567D03*
X326417Y1503898D03*
X317756Y1514922D03*
X326417Y1519252D03*
X317756Y1555867D03*
X326417Y1560197D03*
X317756Y1571221D03*
X326417Y1575552D03*
X317756Y1586575D03*
X326417Y1590906D03*
X317756Y1601930D03*
X326417Y1606260D03*
X317756Y1617284D03*
X326417Y1621615D03*
X335078Y1453504D03*
X343740Y1457835D03*
X335078Y1468859D03*
X343740Y1473189D03*
X335078Y1484213D03*
X343740Y1488544D03*
X335078Y1499567D03*
X343740Y1503898D03*
X335078Y1514922D03*
X343740Y1519252D03*
X335078Y1555867D03*
X343740Y1560197D03*
X335078Y1571221D03*
X343740Y1575552D03*
X335078Y1586575D03*
X343740Y1590906D03*
X335078Y1601930D03*
X343740Y1606260D03*
X335078Y1617284D03*
X343740Y1621615D03*
X352401Y1453504D03*
X361063Y1457835D03*
X352401Y1468859D03*
X361063Y1473189D03*
X352401Y1484213D03*
X361063Y1488544D03*
X352401Y1499567D03*
X361063Y1503898D03*
X352401Y1514922D03*
X361063Y1519252D03*
X352401Y1555867D03*
X361063Y1560197D03*
X352401Y1571221D03*
X361063Y1575552D03*
X352401Y1586575D03*
X361063Y1590906D03*
X352401Y1601930D03*
X361063Y1606260D03*
X352401Y1617284D03*
X361063Y1621615D03*
X456339Y1453504D03*
Y1468859D03*
Y1484213D03*
Y1499567D03*
Y1514922D03*
Y1555867D03*
Y1571221D03*
Y1586575D03*
Y1601930D03*
Y1617284D03*
X473662Y1453504D03*
X465000Y1457835D03*
X473662Y1468859D03*
X465000Y1473189D03*
X473662Y1484213D03*
X465000Y1488544D03*
X473662Y1499567D03*
Y1514922D03*
X465000Y1503898D03*
Y1519252D03*
X473662Y1555867D03*
X465000Y1560197D03*
X473662Y1571221D03*
X465000Y1575552D03*
X473662Y1586575D03*
X465000Y1590906D03*
X473662Y1601930D03*
X465000Y1606260D03*
X473662Y1617284D03*
X465000Y1621615D03*
X490985Y1453504D03*
X482323Y1457835D03*
X490985Y1468859D03*
X482323Y1473189D03*
X490985Y1484213D03*
X482323Y1488544D03*
X490985Y1499567D03*
Y1514922D03*
X482323Y1503898D03*
Y1519252D03*
X490985Y1555867D03*
X482323Y1560197D03*
X490985Y1571221D03*
X482323Y1575552D03*
X490985Y1586575D03*
X482323Y1590906D03*
X490985Y1601930D03*
X482323Y1606260D03*
X490985Y1617284D03*
X482323Y1621615D03*
X508307Y1453504D03*
X499646Y1457835D03*
X508307Y1468859D03*
X499646Y1473189D03*
X508307Y1484213D03*
X499646Y1488544D03*
X508307Y1499567D03*
Y1514922D03*
X499646Y1503898D03*
Y1519252D03*
X508307Y1555867D03*
X499646Y1560197D03*
X508307Y1571221D03*
X499646Y1575552D03*
X508307Y1586575D03*
X499646Y1590906D03*
X508307Y1601930D03*
X499646Y1606260D03*
X508307Y1617284D03*
X499646Y1621615D03*
X516969Y1457835D03*
Y1473189D03*
Y1488544D03*
Y1503898D03*
Y1519252D03*
Y1560197D03*
Y1575552D03*
Y1590906D03*
Y1606260D03*
Y1621615D03*
X525630Y1453504D03*
X534292Y1457835D03*
X525630Y1468859D03*
X534292Y1473189D03*
X525630Y1484213D03*
X534292Y1488544D03*
X525630Y1499567D03*
X534292Y1503898D03*
X525630Y1514922D03*
X534292Y1519252D03*
X525630Y1555867D03*
X534292Y1560197D03*
X525630Y1571221D03*
X534292Y1575552D03*
X525630Y1586575D03*
X534292Y1590906D03*
X525630Y1601930D03*
X534292Y1606260D03*
X525630Y1617284D03*
X534292Y1621615D03*
X629567Y1453504D03*
X638228Y1457835D03*
X629567Y1468859D03*
X638228Y1473189D03*
X629567Y1484213D03*
X638228Y1488544D03*
X629567Y1499567D03*
X638228Y1503898D03*
X629567Y1514922D03*
X638228Y1519252D03*
X629567Y1555867D03*
X638228Y1560197D03*
X629567Y1571221D03*
X638228Y1575552D03*
X629567Y1586575D03*
X638228Y1590906D03*
X629567Y1601930D03*
X638228Y1606260D03*
X629567Y1617284D03*
X638228Y1621615D03*
X646890Y1453504D03*
Y1468859D03*
Y1484213D03*
Y1499567D03*
Y1514922D03*
Y1555867D03*
Y1571221D03*
Y1586575D03*
Y1601930D03*
Y1617284D03*
X664213Y1453504D03*
X655551Y1457835D03*
X664213Y1468859D03*
X655551Y1473189D03*
X664213Y1484213D03*
X655551Y1488544D03*
X664213Y1499567D03*
Y1514922D03*
X655551Y1503898D03*
Y1519252D03*
X664213Y1555867D03*
X655551Y1560197D03*
X664213Y1571221D03*
X655551Y1575552D03*
X664213Y1586575D03*
X655551Y1590906D03*
X664213Y1601930D03*
X655551Y1606260D03*
X664213Y1617284D03*
X655551Y1621615D03*
X681535Y1453504D03*
X672874Y1457835D03*
X681535Y1468859D03*
X672874Y1473189D03*
X681535Y1484213D03*
X672874Y1488544D03*
X681535Y1499567D03*
Y1514922D03*
X672874Y1503898D03*
Y1519252D03*
X681535Y1555867D03*
X672874Y1560197D03*
X681535Y1571221D03*
X672874Y1575552D03*
X681535Y1586575D03*
X672874Y1590906D03*
X681535Y1601930D03*
X672874Y1606260D03*
X681535Y1617284D03*
X672874Y1621615D03*
X698858Y1453504D03*
X690197Y1457835D03*
X698858Y1468859D03*
X690197Y1473189D03*
X698858Y1484213D03*
X690197Y1488544D03*
X698858Y1499567D03*
Y1514922D03*
X690197Y1503898D03*
Y1519252D03*
X698858Y1555867D03*
X690197Y1560197D03*
X698858Y1571221D03*
X690197Y1575552D03*
X698858Y1586575D03*
X690197Y1590906D03*
X698858Y1601930D03*
X690197Y1606260D03*
X698858Y1617284D03*
X690197Y1621615D03*
X707520Y1457835D03*
Y1473189D03*
Y1488544D03*
Y1503898D03*
Y1519252D03*
Y1560197D03*
Y1575552D03*
Y1590906D03*
Y1606260D03*
Y1621615D03*
X1131850Y1453504D03*
X1140511Y1457835D03*
X1131850Y1468859D03*
X1140511Y1473189D03*
X1131850Y1484213D03*
X1140511Y1488544D03*
X1131850Y1499567D03*
X1140511Y1503898D03*
X1131850Y1514922D03*
X1140511Y1519252D03*
X1131850Y1555867D03*
X1140511Y1560197D03*
X1131850Y1571221D03*
X1140511Y1575552D03*
X1131850Y1586575D03*
X1140511Y1590906D03*
X1131850Y1601930D03*
X1140511Y1606260D03*
X1131850Y1617284D03*
X1140511Y1621615D03*
X1149173Y1453504D03*
X1157834Y1457835D03*
X1149173Y1468859D03*
X1157834Y1473189D03*
X1149173Y1484213D03*
X1157834Y1488544D03*
X1149173Y1499567D03*
X1157834Y1503898D03*
X1149173Y1514922D03*
X1157834Y1519252D03*
X1149173Y1555867D03*
X1157834Y1560197D03*
X1149173Y1571221D03*
X1157834Y1575552D03*
X1149173Y1586575D03*
X1157834Y1590906D03*
X1149173Y1601930D03*
X1157834Y1606260D03*
X1149173Y1617284D03*
X1157834Y1621615D03*
X1166496Y1453504D03*
Y1468859D03*
Y1484213D03*
Y1499567D03*
Y1514922D03*
Y1555867D03*
Y1571221D03*
Y1586575D03*
Y1601930D03*
Y1617284D03*
X1183818Y1453504D03*
X1175157Y1457835D03*
X1183818Y1468859D03*
X1175157Y1473189D03*
X1183818Y1484213D03*
X1175157Y1488544D03*
X1183818Y1499567D03*
Y1514922D03*
X1175157Y1503898D03*
Y1519252D03*
X1183818Y1555867D03*
X1175157Y1560197D03*
X1183818Y1571221D03*
X1175157Y1575552D03*
X1183818Y1586575D03*
X1175157Y1590906D03*
X1183818Y1601930D03*
X1175157Y1606260D03*
X1183818Y1617284D03*
X1175157Y1621615D03*
X1201141Y1453504D03*
X1192480Y1457835D03*
X1201141Y1468859D03*
X1192480Y1473189D03*
X1201141Y1484213D03*
X1192480Y1488544D03*
X1201141Y1499567D03*
Y1514922D03*
X1192480Y1503898D03*
Y1519252D03*
X1201141Y1555867D03*
X1192480Y1560197D03*
X1201141Y1571221D03*
X1192480Y1575552D03*
X1201141Y1586575D03*
X1192480Y1590906D03*
X1201141Y1601930D03*
X1192480Y1606260D03*
X1201141Y1617284D03*
X1192480Y1621615D03*
X1209803Y1457835D03*
Y1473189D03*
Y1488544D03*
Y1503898D03*
Y1519252D03*
Y1560197D03*
Y1575552D03*
Y1590906D03*
Y1606260D03*
Y1621615D03*
X1305079Y1453504D03*
X1313740Y1457835D03*
X1305079Y1468859D03*
X1313740Y1473189D03*
X1305079Y1484213D03*
X1313740Y1488544D03*
X1305079Y1499567D03*
X1313740Y1503898D03*
X1305079Y1514922D03*
X1313740Y1519252D03*
X1305079Y1555867D03*
X1313740Y1560197D03*
X1305079Y1571221D03*
X1313740Y1575552D03*
X1305079Y1586575D03*
X1313740Y1590906D03*
X1305079Y1601930D03*
X1313740Y1606260D03*
X1305079Y1617284D03*
X1313740Y1621615D03*
X1322402Y1453504D03*
X1331063Y1457835D03*
X1322402Y1468859D03*
X1331063Y1473189D03*
X1322402Y1484213D03*
X1331063Y1488544D03*
X1322402Y1499567D03*
X1331063Y1503898D03*
X1322402Y1514922D03*
X1331063Y1519252D03*
X1322402Y1555867D03*
X1331063Y1560197D03*
X1322402Y1571221D03*
X1331063Y1575552D03*
X1322402Y1586575D03*
X1331063Y1590906D03*
X1322402Y1601930D03*
X1331063Y1606260D03*
X1322402Y1617284D03*
X1331063Y1621615D03*
X1339725Y1453504D03*
X1348386Y1457835D03*
X1339725Y1468859D03*
X1348386Y1473189D03*
X1339725Y1484213D03*
X1348386Y1488544D03*
X1339725Y1499567D03*
X1348386Y1503898D03*
X1339725Y1514922D03*
X1348386Y1519252D03*
X1339725Y1555867D03*
X1348386Y1560197D03*
X1339725Y1571221D03*
X1348386Y1575552D03*
X1339725Y1586575D03*
X1348386Y1590906D03*
X1339725Y1601930D03*
X1348386Y1606260D03*
X1339725Y1617284D03*
X1348386Y1621615D03*
X1357047Y1453504D03*
X1365709Y1457835D03*
X1357047Y1468859D03*
X1365709Y1473189D03*
X1357047Y1484213D03*
X1365709Y1488544D03*
X1357047Y1499567D03*
X1365709Y1503898D03*
X1357047Y1514922D03*
X1365709Y1519252D03*
X1357047Y1555867D03*
X1365709Y1560197D03*
X1357047Y1571221D03*
X1365709Y1575552D03*
X1357047Y1586575D03*
X1365709Y1590906D03*
X1357047Y1601930D03*
X1365709Y1606260D03*
X1357047Y1617284D03*
X1365709Y1621615D03*
X1374370Y1453504D03*
X1383032Y1457835D03*
X1374370Y1468859D03*
X1383032Y1473189D03*
X1374370Y1484213D03*
X1383032Y1488544D03*
X1374370Y1499567D03*
X1383032Y1503898D03*
X1374370Y1514922D03*
X1383032Y1519252D03*
X1374370Y1555867D03*
X1383032Y1560197D03*
X1374370Y1571221D03*
X1383032Y1575552D03*
X1374370Y1586575D03*
X1383032Y1590906D03*
X1374370Y1601930D03*
X1383032Y1606260D03*
X1374370Y1617284D03*
X1383032Y1621615D03*
X1478307Y1453504D03*
Y1468859D03*
Y1484213D03*
Y1499567D03*
Y1514922D03*
Y1555867D03*
Y1571221D03*
Y1586575D03*
Y1601930D03*
Y1617284D03*
X1495630Y1453504D03*
X1486968Y1457835D03*
X1495630Y1468859D03*
X1486968Y1473189D03*
X1495630Y1484213D03*
X1486968Y1488544D03*
X1495630Y1499567D03*
Y1514922D03*
X1486968Y1503898D03*
Y1519252D03*
X1495630Y1555867D03*
X1486968Y1560197D03*
X1495630Y1571221D03*
X1486968Y1575552D03*
X1495630Y1586575D03*
X1486968Y1590906D03*
X1495630Y1601930D03*
X1486968Y1606260D03*
X1495630Y1617284D03*
X1486968Y1621615D03*
X1512953Y1453504D03*
X1504291Y1457835D03*
X1512953Y1468859D03*
X1504291Y1473189D03*
X1512953Y1484213D03*
X1504291Y1488544D03*
X1512953Y1499567D03*
Y1514922D03*
X1504291Y1503898D03*
Y1519252D03*
X1512953Y1555867D03*
X1504291Y1560197D03*
X1512953Y1571221D03*
X1504291Y1575552D03*
X1512953Y1586575D03*
X1504291Y1590906D03*
X1512953Y1601930D03*
X1504291Y1606260D03*
X1512953Y1617284D03*
X1504291Y1621615D03*
X1530275Y1453504D03*
X1521614Y1457835D03*
X1530275Y1468859D03*
X1521614Y1473189D03*
X1530275Y1484213D03*
X1521614Y1488544D03*
X1530275Y1499567D03*
Y1514922D03*
X1521614Y1503898D03*
Y1519252D03*
X1530275Y1555867D03*
X1521614Y1560197D03*
X1530275Y1571221D03*
X1521614Y1575552D03*
X1530275Y1586575D03*
X1521614Y1590906D03*
X1530275Y1601930D03*
X1521614Y1606260D03*
X1530275Y1617284D03*
X1521614Y1621615D03*
X1547598Y1453504D03*
X1538937Y1457835D03*
X1547598Y1468859D03*
X1538937Y1473189D03*
X1547598Y1484213D03*
X1538937Y1488544D03*
X1547598Y1499567D03*
Y1514922D03*
X1538937Y1503898D03*
Y1519252D03*
X1547598Y1555867D03*
X1538937Y1560197D03*
X1547598Y1571221D03*
X1538937Y1575552D03*
X1547598Y1586575D03*
X1538937Y1590906D03*
X1547598Y1601930D03*
X1538937Y1606260D03*
X1547598Y1617284D03*
X1538937Y1621615D03*
X1556260Y1457835D03*
Y1473189D03*
Y1488544D03*
Y1503898D03*
Y1519252D03*
Y1560197D03*
Y1575552D03*
Y1590906D03*
Y1606260D03*
Y1621615D03*
X1651535Y1453504D03*
X1660196Y1457835D03*
X1651535Y1468859D03*
X1660196Y1473189D03*
X1651535Y1484213D03*
X1660196Y1488544D03*
X1651535Y1499567D03*
X1660196Y1503898D03*
X1651535Y1514922D03*
X1660196Y1519252D03*
X1651535Y1555867D03*
X1660196Y1560197D03*
X1651535Y1571221D03*
X1660196Y1575552D03*
X1651535Y1586575D03*
X1660196Y1590906D03*
X1651535Y1601930D03*
X1660196Y1606260D03*
X1651535Y1617284D03*
X1660196Y1621615D03*
X1668858Y1453504D03*
X1677519Y1457835D03*
X1668858Y1468859D03*
X1677519Y1473189D03*
X1668858Y1484213D03*
X1677519Y1488544D03*
X1668858Y1499567D03*
X1677519Y1503898D03*
X1668858Y1514922D03*
X1677519Y1519252D03*
X1668858Y1555867D03*
X1677519Y1560197D03*
X1668858Y1571221D03*
X1677519Y1575552D03*
X1668858Y1586575D03*
X1677519Y1590906D03*
X1668858Y1601930D03*
X1677519Y1606260D03*
X1668858Y1617284D03*
X1677519Y1621615D03*
X1686181Y1453504D03*
Y1468859D03*
Y1484213D03*
Y1499567D03*
Y1514922D03*
Y1555867D03*
Y1571221D03*
Y1586575D03*
Y1601930D03*
Y1617284D03*
X1703503Y1453504D03*
X1694842Y1457835D03*
X1703503Y1468859D03*
X1694842Y1473189D03*
X1703503Y1484213D03*
X1694842Y1488544D03*
X1703503Y1499567D03*
Y1514922D03*
X1694842Y1503898D03*
Y1519252D03*
X1703503Y1555867D03*
X1694842Y1560197D03*
X1703503Y1571221D03*
X1694842Y1575552D03*
X1703503Y1586575D03*
X1694842Y1590906D03*
X1703503Y1601930D03*
X1694842Y1606260D03*
X1703503Y1617284D03*
X1694842Y1621615D03*
X1720826Y1453504D03*
X1712165Y1457835D03*
X1720826Y1468859D03*
X1712165Y1473189D03*
X1720826Y1484213D03*
X1712165Y1488544D03*
X1720826Y1499567D03*
Y1514922D03*
X1712165Y1503898D03*
Y1519252D03*
X1720826Y1555867D03*
X1712165Y1560197D03*
X1720826Y1571221D03*
X1712165Y1575552D03*
X1720826Y1586575D03*
X1712165Y1590906D03*
X1720826Y1601930D03*
X1712165Y1606260D03*
X1720826Y1617284D03*
X1712165Y1621615D03*
X1729488Y1457835D03*
Y1473189D03*
Y1488544D03*
Y1503898D03*
Y1519252D03*
Y1560197D03*
Y1575552D03*
Y1590906D03*
Y1606260D03*
Y1621615D03*
G54D39*
X235433Y1606142D03*
X581890D03*
X1259055D03*
X1605512D03*
G54D16*
X15139Y198883D03*
Y201683D03*
X18564Y238589D03*
X6690Y1496782D03*
X34520Y213539D03*
X36201Y238714D03*
X21530Y236121D03*
X27966Y238689D03*
X27625Y663094D03*
X25818Y682139D03*
X28818D03*
X32079Y1517641D03*
X65189Y228961D03*
Y231461D03*
Y223661D03*
Y226461D03*
X54733Y231226D03*
Y228726D03*
Y223726D03*
Y226226D03*
X67622Y572842D03*
X64408Y572975D03*
X73110Y101701D03*
X78501Y110445D03*
Y115401D03*
Y129574D03*
Y124618D03*
X73158Y229286D03*
X76851Y222212D03*
Y224712D03*
X73158Y231786D03*
X75777Y585507D03*
X71184D03*
X71730Y579475D03*
X71228Y590145D03*
X75822Y590190D03*
X75684Y605443D03*
X83684D03*
X78129Y656900D03*
X72314Y680207D03*
Y683407D03*
X82714Y674707D03*
X71928Y873683D03*
X88903Y117557D03*
Y122513D03*
Y131731D03*
Y136687D03*
X94390Y293645D03*
Y290845D03*
Y288345D03*
X91890Y293645D03*
Y290845D03*
Y288345D03*
X93456Y649838D03*
X89432Y668293D03*
X92134D03*
X85614Y674707D03*
X87714Y684607D03*
X117501Y198883D03*
Y201683D03*
X111275Y1008262D03*
Y1011762D03*
X130328Y238689D03*
X123892Y236121D03*
X120926Y238589D03*
X136882Y213539D03*
X138563Y238714D03*
X143186Y402291D03*
Y397335D03*
X140786Y416465D03*
Y411509D03*
Y425682D03*
Y430638D03*
Y439855D03*
Y444811D03*
Y468609D03*
Y473565D03*
Y487738D03*
Y482782D03*
Y512743D03*
Y517699D03*
Y531872D03*
Y526916D03*
X157095Y228726D03*
Y231226D03*
X167551Y223661D03*
X157095Y226226D03*
Y223726D03*
X151188Y390223D03*
Y395179D03*
Y404396D03*
Y409352D03*
Y423525D03*
Y418569D03*
Y432743D03*
Y437699D03*
Y489895D03*
Y480677D03*
Y475721D03*
Y494851D03*
Y519855D03*
Y538984D03*
Y534028D03*
Y524811D03*
X175472Y101701D03*
X175520Y229286D03*
X179213Y224712D03*
Y222212D03*
X167551Y231461D03*
Y228961D03*
Y226461D03*
X175520Y231786D03*
X194189Y103621D03*
X196752Y293645D03*
Y290845D03*
Y288345D03*
X194252Y293645D03*
Y290845D03*
Y288345D03*
X203740Y567914D03*
Y565414D03*
Y570414D03*
Y575414D03*
Y572914D03*
X219863Y198883D03*
Y201683D03*
X226254Y236121D03*
X223288Y238589D03*
X239244Y213539D03*
X232690Y238689D03*
X240925Y238714D03*
X259457Y228726D03*
Y231226D03*
Y226226D03*
Y223726D03*
X251802Y824128D03*
X277834Y101701D03*
X269913Y228961D03*
Y226461D03*
Y223661D03*
X277882Y229286D03*
X269913Y231461D03*
X277882Y231786D03*
X286129Y36971D03*
X296551Y103621D03*
X281575Y224712D03*
Y222212D03*
X296614Y293645D03*
Y290845D03*
Y288345D03*
X309106Y37543D03*
X299114Y290845D03*
Y288345D03*
Y293645D03*
X302966Y324139D03*
X310013Y316731D03*
X301158Y380307D03*
X301308Y395346D03*
X301393Y400039D03*
X322225Y198883D03*
Y201683D03*
X325650Y238589D03*
X328616Y236121D03*
X321549Y445315D03*
Y448115D03*
X323489Y471484D03*
Y466528D03*
Y480701D03*
Y485657D03*
Y515617D03*
Y510661D03*
Y529791D03*
Y524835D03*
Y565657D03*
Y560701D03*
Y574874D03*
Y579830D03*
Y589047D03*
Y594003D03*
Y603221D03*
Y608177D03*
X330905Y11806D03*
Y23806D03*
Y31806D03*
X341606Y213539D03*
X335052Y238689D03*
X343287Y238714D03*
X345050Y458334D03*
X333891Y473640D03*
Y487813D03*
Y478596D03*
Y492769D03*
Y522730D03*
Y517774D03*
Y531947D03*
Y536903D03*
Y572769D03*
Y567813D03*
Y586943D03*
Y581987D03*
Y596160D03*
Y601116D03*
Y610333D03*
Y615289D03*
X347450Y447486D03*
X353670Y488618D03*
Y491118D03*
Y493618D03*
Y496118D03*
X372275Y226461D03*
X361819Y231226D03*
Y228726D03*
Y223726D03*
Y226226D03*
X372275Y228961D03*
Y231461D03*
Y223661D03*
X364954Y450091D03*
X367564Y452740D03*
X365332Y490070D03*
Y487570D03*
X361887Y493758D03*
Y496258D03*
X377020Y782535D03*
X368491Y815092D03*
X368273Y928100D03*
X380196Y101701D03*
X380244Y229286D03*
X383937Y222212D03*
Y224712D03*
X380244Y231786D03*
X393837Y466409D03*
X393823Y487382D03*
X398913Y103621D03*
X398976Y293645D03*
X401476D03*
Y288345D03*
Y290845D03*
X398976Y288345D03*
Y290845D03*
X406843Y399161D03*
Y401661D03*
Y396661D03*
X405603Y668060D03*
X408103D03*
X403103D03*
X400603D03*
Y678060D03*
X405603D03*
X408103D03*
X403103D03*
X406967Y878764D03*
X406415Y874840D03*
X399285Y1081599D03*
X398915Y1097278D03*
X396415D03*
X401711Y1419771D03*
X406667D03*
X400911Y1537902D03*
X407048D03*
X400911Y1544424D03*
X407048Y1549936D03*
X400911D03*
X420050Y33425D03*
X418876Y401661D03*
Y396661D03*
Y399161D03*
X411754Y474513D03*
X424731Y508152D03*
Y513452D03*
Y515952D03*
X414275Y508217D03*
Y510717D03*
Y515717D03*
Y513217D03*
X424731Y510952D03*
X410603Y668060D03*
Y678060D03*
X425759Y869921D03*
Y872721D03*
Y875521D03*
Y867121D03*
Y878321D03*
X411214Y892109D03*
X413012Y1537902D03*
Y1544098D03*
X426196Y1534087D03*
X413012Y1549936D03*
X421616Y1549885D03*
X442704Y506427D03*
X427693Y506520D03*
X438353Y508685D03*
X427693Y509020D03*
X432700Y516277D03*
X429210Y784833D03*
X428759Y869921D03*
Y867121D03*
Y872721D03*
Y875521D03*
Y878321D03*
X432332Y892049D03*
Y897649D03*
Y894849D03*
Y900449D03*
X453544Y461961D03*
X451144Y472809D03*
X447836Y711199D03*
X451889Y1301067D03*
X456832Y1299121D03*
X451889Y1306023D03*
X472226Y198883D03*
Y201683D03*
X473658Y467215D03*
X471048Y464566D03*
X469495Y1011303D03*
Y1023303D03*
Y1017303D03*
X491607Y213539D03*
X478617Y236121D03*
X475651Y238589D03*
X485053Y238689D03*
X481495Y1011303D03*
X475495D03*
X481495Y1023303D03*
Y1017303D03*
X475495Y1023303D03*
X484800Y1302000D03*
X493288Y238714D03*
X522276Y223661D03*
Y226461D03*
Y228961D03*
Y231461D03*
X511820Y231226D03*
Y228726D03*
Y223726D03*
Y226226D03*
X521494Y572975D03*
X524475Y952290D03*
X509471Y981608D03*
X517374Y1287222D03*
X514363Y1287370D03*
X520548Y1287181D03*
X530197Y101701D03*
X530245Y229286D03*
X533938Y222212D03*
Y224712D03*
X530245Y231786D03*
X524708Y572842D03*
X532863Y585507D03*
X528270D03*
X528816Y579475D03*
X532908Y590190D03*
X528314Y590145D03*
X532770Y605443D03*
X528868Y873683D03*
X548914Y103621D03*
X551477Y288345D03*
Y290845D03*
X548977Y288345D03*
Y290845D03*
Y293645D03*
X551477D03*
X540770Y605443D03*
X574588Y201683D03*
X568362Y1008262D03*
Y1011762D03*
X574588Y198883D03*
X587415Y238689D03*
X580979Y236121D03*
X578013Y238589D03*
X577249Y965445D03*
X593969Y213539D03*
X595650Y238714D03*
X600272Y397335D03*
Y402291D03*
X597872Y425682D03*
Y416465D03*
Y411509D03*
Y439855D03*
Y430638D03*
Y444811D03*
Y468609D03*
Y473565D03*
Y487738D03*
Y482782D03*
Y517699D03*
Y531872D03*
Y526916D03*
X606142Y965665D03*
X614182Y223726D03*
Y226226D03*
Y231226D03*
Y228726D03*
X608274Y390223D03*
Y395179D03*
Y404396D03*
Y409352D03*
Y418569D03*
Y423525D03*
Y432743D03*
Y437699D03*
Y489895D03*
Y480677D03*
Y475721D03*
Y494851D03*
Y519855D03*
Y538984D03*
Y534028D03*
Y524811D03*
X632559Y101701D03*
X624638Y231461D03*
X636300Y222212D03*
Y224712D03*
X632607Y229286D03*
X624638Y223661D03*
Y226461D03*
Y228961D03*
X632607Y231786D03*
X651276Y103621D03*
X651339Y290845D03*
Y293645D03*
X653839D03*
Y288345D03*
Y290845D03*
X651339Y288345D03*
X660826Y570414D03*
Y567914D03*
Y565414D03*
Y575414D03*
Y572914D03*
X676950Y201683D03*
X680375Y238589D03*
X683341Y236121D03*
X696331Y213539D03*
X698012Y238714D03*
X689777Y238689D03*
X716544Y228726D03*
Y231226D03*
Y226226D03*
Y223726D03*
X704446Y760611D03*
X713425Y786029D03*
X734921Y101701D03*
X727000Y228961D03*
Y226461D03*
Y223661D03*
X734969Y229286D03*
X727000Y231461D03*
X734969Y231786D03*
X721218Y742131D03*
X720271Y782481D03*
X738662Y224712D03*
Y222212D03*
X744069Y746617D03*
X735576Y861780D03*
X753638Y103621D03*
X760407Y324494D03*
X767099Y316731D03*
X767310Y1599164D03*
X756358Y1616917D03*
X779312Y198883D03*
Y201683D03*
X782737Y238589D03*
X780575Y471484D03*
Y466528D03*
Y480701D03*
Y485657D03*
Y510661D03*
Y515617D03*
Y524835D03*
Y529791D03*
Y560701D03*
Y565657D03*
Y579830D03*
Y574874D03*
Y589047D03*
Y594003D03*
Y603221D03*
Y608177D03*
X798693Y213539D03*
X792139Y238689D03*
X785703Y236121D03*
X790977Y473640D03*
Y487813D03*
Y478596D03*
Y492769D03*
Y517774D03*
Y522730D03*
Y531947D03*
Y536903D03*
Y567813D03*
Y572769D03*
Y581987D03*
Y586943D03*
Y601116D03*
Y596160D03*
Y615289D03*
Y610333D03*
X800374Y238714D03*
X804536Y441486D03*
X802136Y452334D03*
X810756Y491118D03*
Y488618D03*
Y483618D03*
Y486118D03*
X815492Y732917D03*
X829362Y231461D03*
Y228961D03*
Y226461D03*
Y223661D03*
X818906Y228726D03*
Y231226D03*
Y226226D03*
Y223726D03*
X829381Y348036D03*
X824650Y446740D03*
X822040Y444091D03*
X826262Y462326D03*
Y459326D03*
X818973Y491258D03*
Y488758D03*
X822418Y485070D03*
Y482570D03*
X823790Y713375D03*
X823843Y732109D03*
X819890Y736924D03*
X828423Y964731D03*
X837283Y101701D03*
X837331Y229286D03*
X841024Y224712D03*
Y222212D03*
X837331Y231786D03*
X839573Y325327D03*
X856000Y103621D03*
X858563Y293645D03*
Y290845D03*
X856063Y293645D03*
Y290845D03*
X858563Y288345D03*
X856063D03*
X854622Y359004D03*
X873885Y340892D03*
X873733Y357844D03*
X871382Y373971D03*
X875907Y486256D03*
X870137Y669461D03*
X875916Y808965D03*
X886026Y346584D03*
X896592Y362369D03*
Y366369D03*
Y370369D03*
X882907Y480350D03*
X892023Y570176D03*
X890959Y579788D03*
X890956Y588325D03*
X894015Y588253D03*
X895933Y618143D03*
X910076Y304843D03*
X905120D03*
X913206Y336489D03*
X910040Y353532D03*
X902169Y413002D03*
Y418002D03*
Y415502D03*
X913853Y561487D03*
X904393Y570176D03*
X908517D03*
X898815D03*
X898232Y588320D03*
X902635Y588305D03*
X906999Y588274D03*
X905313Y709259D03*
X905050Y720268D03*
X913716Y800815D03*
X899916D03*
X911053Y800510D03*
X901428Y1136426D03*
X904897Y1145169D03*
X902397D03*
X929978Y186854D03*
Y184054D03*
X917906Y321670D03*
X922629Y336609D03*
X922198Y342051D03*
X917858Y331453D03*
X927309Y357267D03*
X921389D03*
X915395D03*
Y363212D03*
X927309Y363239D03*
Y369210D03*
X921468D03*
X915395D03*
X927072Y386992D03*
X919072D03*
X923072D03*
X914202Y418002D03*
Y413002D03*
Y415502D03*
X916590Y800636D03*
X921790Y810965D03*
X926044Y1545370D03*
Y1542370D03*
X938125Y230891D03*
X942805Y223860D03*
X936369Y221292D03*
X940158Y245707D03*
X946064Y252998D03*
X941845Y278968D03*
X939606Y310521D03*
X939653Y317474D03*
X940924Y328959D03*
X936608Y326058D03*
X945120Y326441D03*
X930398Y342050D03*
X936453Y345336D03*
X945599Y345383D03*
X940972Y338238D03*
X943663Y355674D03*
X944900Y363700D03*
X938499Y362202D03*
X940600Y370600D03*
X939314Y707847D03*
X931244Y720471D03*
X936026Y730600D03*
X941916Y808965D03*
X949359Y198710D03*
X951040Y223885D03*
X956348Y356371D03*
X952170Y356131D03*
X958823Y362802D03*
X954888Y369513D03*
X948400Y370045D03*
X956035Y1545333D03*
X959035D03*
X953035D03*
X950035D03*
X959035Y1542333D03*
X956035D03*
X953035D03*
X950035D03*
X968906Y223726D03*
Y228726D03*
Y231226D03*
X979362Y223661D03*
X968906Y226226D03*
X973338Y345018D03*
X978581Y572975D03*
X971144Y908972D03*
X965405Y1136426D03*
X987283Y101701D03*
X987331Y229286D03*
X991024Y224712D03*
Y222212D03*
X979362Y231461D03*
Y228961D03*
Y226461D03*
X987331Y231786D03*
X992045Y366559D03*
X984045D03*
X988045D03*
X981795Y572842D03*
X985903Y579475D03*
X985357Y585507D03*
X989950D03*
X985401Y590145D03*
X989995Y590190D03*
X989857Y605443D03*
X983712Y722064D03*
X1006000Y103621D03*
X1008563Y293645D03*
X1006063D03*
Y290845D03*
Y288345D03*
X1008563Y290845D03*
Y288345D03*
X997857Y605443D03*
X1010606Y1547824D03*
X1010659Y1568771D03*
Y1565771D03*
X1010653Y1571669D03*
X1021451Y322879D03*
X1026032Y322906D03*
X1018238Y678647D03*
X1018155Y684132D03*
X1025116Y698332D03*
X1024932Y717856D03*
X1016320Y828481D03*
X1026340Y917761D03*
X1025448Y1008262D03*
Y1011762D03*
X1013606Y1547824D03*
X1016606D03*
X1019606D03*
X1013659Y1568771D03*
X1016659D03*
X1019659D03*
X1013659Y1565771D03*
X1016659D03*
X1019659D03*
X1013653Y1571669D03*
X1016653D03*
X1019653D03*
X1031674Y198883D03*
Y201683D03*
X1038065Y236121D03*
X1035099Y238589D03*
X1030184Y288709D03*
X1038068Y298789D03*
X1033112D03*
X1030753Y732213D03*
X1051055Y213539D03*
X1044501Y238689D03*
X1052736Y238714D03*
X1048695Y280161D03*
X1057359Y402291D03*
Y397335D03*
X1054959Y411509D03*
Y425682D03*
Y416465D03*
Y430638D03*
Y439855D03*
Y444811D03*
Y468609D03*
Y473565D03*
Y487738D03*
Y482782D03*
Y517699D03*
Y512743D03*
Y531872D03*
Y526916D03*
X1071268Y226226D03*
Y223726D03*
Y228726D03*
Y231226D03*
X1065361Y390223D03*
Y395179D03*
Y404396D03*
Y409352D03*
Y423525D03*
Y418569D03*
Y432743D03*
Y437699D03*
Y489895D03*
Y480677D03*
Y475721D03*
Y494851D03*
Y519855D03*
Y524811D03*
Y538984D03*
Y534028D03*
X1089645Y101701D03*
X1081724Y226461D03*
Y223661D03*
X1089693Y229286D03*
X1081724Y231461D03*
Y228961D03*
X1089693Y231786D03*
X1079863Y345660D03*
X1090747Y1617415D03*
X1108362Y103621D03*
X1093386Y224712D03*
Y222212D03*
X1108425Y293645D03*
Y290845D03*
Y288345D03*
X1096264Y1562285D03*
X1093713Y1585583D03*
X1110925Y293645D03*
Y290845D03*
Y288345D03*
X1117913Y565414D03*
Y567914D03*
Y570414D03*
Y572914D03*
Y575414D03*
X1122718Y598857D03*
X1121191Y612555D03*
X1120512Y617332D03*
X1121022Y607750D03*
X1134036Y198883D03*
Y201683D03*
X1137461Y238589D03*
X1140427Y236121D03*
X1138166Y534759D03*
X1153417Y213539D03*
X1146863Y238689D03*
X1155098Y238714D03*
X1149437Y728541D03*
X1152316Y746625D03*
X1173630Y226226D03*
Y223726D03*
Y228726D03*
Y231226D03*
X1161274Y550462D03*
X1170603Y715281D03*
X1163751Y719498D03*
X1168577Y733812D03*
X1169266Y800799D03*
X1184086Y231461D03*
Y228961D03*
Y226461D03*
Y223661D03*
X1176577Y885974D03*
X1188431Y936568D03*
X1192007Y101701D03*
X1192055Y229286D03*
X1195748Y224712D03*
Y222212D03*
X1192055Y231786D03*
X1192990Y914873D03*
X1195118Y936296D03*
X1210724Y103621D03*
X1213287Y293645D03*
Y290845D03*
Y288345D03*
X1210787Y293645D03*
Y290845D03*
Y288345D03*
X1217139Y324139D03*
X1222909Y-83456D03*
Y-78500D03*
Y-68500D03*
Y-73456D03*
X1228265Y-44406D03*
Y-39450D03*
Y-29450D03*
Y-34406D03*
X1236398Y198883D03*
Y201683D03*
X1224186Y316731D03*
X1237662Y466528D03*
Y471484D03*
Y480701D03*
Y485657D03*
Y515617D03*
Y510661D03*
Y524835D03*
Y529791D03*
Y565657D03*
Y560701D03*
Y589047D03*
Y574874D03*
Y579830D03*
Y603221D03*
Y594003D03*
Y608177D03*
X1239823Y238589D03*
X1242789Y236121D03*
X1248064Y473640D03*
Y487813D03*
Y478596D03*
Y492769D03*
Y517774D03*
Y522730D03*
Y531947D03*
Y536903D03*
X1255779Y213539D03*
X1257460Y238714D03*
X1264481Y300223D03*
X1261623Y447486D03*
X1259223Y458334D03*
X1267843Y488618D03*
Y491118D03*
Y493618D03*
X1275992Y223726D03*
Y226226D03*
Y231226D03*
Y228726D03*
X1286448Y223661D03*
Y226461D03*
Y228961D03*
Y231461D03*
X1279127Y450091D03*
X1281737Y452740D03*
X1279505Y487570D03*
Y490070D03*
X1276060Y496258D03*
Y493758D03*
X1294369Y101701D03*
X1294417Y229286D03*
X1298110Y222212D03*
Y224712D03*
X1294417Y231786D03*
X1313086Y103621D03*
X1313149Y288345D03*
Y290845D03*
Y293645D03*
X1315649Y288345D03*
Y290845D03*
Y293645D03*
X1308010Y466409D03*
X1307996Y487382D03*
X1313459Y1081599D03*
X1310589Y1097278D03*
X1313089D03*
X1334223Y33425D03*
X1333049Y399268D03*
Y401768D03*
Y396768D03*
X1321016Y399161D03*
Y401661D03*
Y396661D03*
X1325927Y474513D03*
X1386399Y201683D03*
X1383669Y1011303D03*
Y1017303D03*
Y1023303D03*
X1386399Y198883D03*
X1399226Y238689D03*
X1392790Y236121D03*
X1389824Y238589D03*
X1395669Y1011303D03*
X1389669D03*
X1395669Y1017303D03*
Y1023303D03*
X1389669D03*
X1405780Y213539D03*
X1407461Y238714D03*
X1425993Y231226D03*
Y228726D03*
Y226226D03*
Y223726D03*
X1444370Y101701D03*
X1436449Y228961D03*
X1444418Y229286D03*
X1436449Y226461D03*
Y223661D03*
X1448111Y222212D03*
Y224712D03*
X1436449Y231461D03*
X1444418Y231786D03*
X1438882Y572842D03*
X1447037Y585507D03*
X1442444D03*
X1442990Y579475D03*
X1435668Y572975D03*
X1442488Y590145D03*
X1447082Y590190D03*
X1446944Y605443D03*
X1443041Y873683D03*
X1463087Y103621D03*
X1465650Y293645D03*
Y288345D03*
Y290845D03*
X1463150Y288345D03*
Y290845D03*
Y293645D03*
X1454944Y605443D03*
X1479409Y-83456D03*
Y-78500D03*
Y-68500D03*
Y-73456D03*
X1476822Y40780D03*
X1498621Y15043D03*
Y35043D03*
Y27043D03*
X1488761Y198883D03*
Y201683D03*
X1492186Y238589D03*
X1495152Y236121D03*
X1483813Y368516D03*
X1482535Y1008262D03*
Y1002453D03*
Y1011762D03*
X1514765Y-44536D03*
Y-39580D03*
Y-29580D03*
Y-34536D03*
X1508142Y213539D03*
X1509823Y238714D03*
X1501588Y238689D03*
X1514446Y402291D03*
Y397335D03*
X1512046Y411509D03*
Y425682D03*
Y416465D03*
Y439855D03*
Y430638D03*
Y444811D03*
Y468609D03*
Y473565D03*
Y487738D03*
Y482782D03*
Y517699D03*
Y512743D03*
Y531872D03*
Y526916D03*
X1528355Y228726D03*
Y223726D03*
Y226226D03*
Y231226D03*
X1515779Y351594D03*
X1522448Y390223D03*
Y395179D03*
Y404396D03*
Y409352D03*
Y423525D03*
Y418569D03*
Y437699D03*
Y432743D03*
Y489895D03*
Y480677D03*
Y475721D03*
Y494851D03*
Y519855D03*
Y538984D03*
Y534028D03*
Y524811D03*
X1546732Y101701D03*
X1538811Y226461D03*
Y228961D03*
Y231461D03*
X1546780Y229286D03*
X1538811Y223661D03*
X1546780Y231786D03*
X1550473Y222212D03*
Y224712D03*
X1565449Y103621D03*
X1565512Y288345D03*
X1568012Y293645D03*
Y290845D03*
Y288345D03*
X1565512Y293645D03*
Y290845D03*
X1575000Y565414D03*
Y567914D03*
Y570414D03*
Y572914D03*
Y575414D03*
X1579753Y599100D03*
X1578679Y613047D03*
X1578114Y607563D03*
X1591123Y198883D03*
Y201683D03*
X1594548Y238589D03*
X1610504Y213539D03*
X1597514Y236121D03*
X1612185Y238714D03*
X1603950Y238689D03*
X1641173Y231461D03*
X1630717Y223726D03*
Y226226D03*
Y231226D03*
Y228726D03*
X1641173Y223661D03*
Y226461D03*
Y228961D03*
X1649094Y101701D03*
X1649142Y229286D03*
X1652835Y222212D03*
Y224712D03*
X1649142Y231786D03*
X1667811Y103621D03*
X1670374Y290845D03*
Y288345D03*
X1667874Y290845D03*
Y288345D03*
X1670374Y293645D03*
X1667874D03*
X1674226Y324139D03*
X1693485Y198883D03*
Y201683D03*
X1681273Y316731D03*
X1699876Y236121D03*
X1696910Y238589D03*
X1706312Y238689D03*
X1694749Y466528D03*
Y471484D03*
X1705151Y473640D03*
Y487813D03*
Y478596D03*
X1694749Y480701D03*
Y485657D03*
X1705151Y492769D03*
Y517774D03*
Y522730D03*
X1694749Y510661D03*
Y515617D03*
X1705151Y536903D03*
Y531947D03*
X1694749Y524835D03*
Y529791D03*
X1705151Y572769D03*
Y567813D03*
X1694749Y565657D03*
Y560701D03*
Y579830D03*
X1705151Y586943D03*
Y581987D03*
X1694749Y589047D03*
Y574874D03*
Y603221D03*
X1705151Y601116D03*
Y596160D03*
X1694749Y594003D03*
X1705151Y615289D03*
X1694749Y608177D03*
X1705151Y610333D03*
X1712866Y213539D03*
X1714547Y238714D03*
X1718710Y447486D03*
X1716310Y458334D03*
X1724930Y491118D03*
Y488618D03*
Y493618D03*
Y496118D03*
X1733909Y-83456D03*
Y-78500D03*
Y-68500D03*
Y-73456D03*
X1733079Y223726D03*
Y226226D03*
Y231226D03*
Y228726D03*
X1743535Y223661D03*
X1738824Y452740D03*
X1736214Y450091D03*
X1736592Y487570D03*
Y490070D03*
X1733147Y493758D03*
Y496258D03*
X1751456Y101701D03*
X1743535Y226461D03*
X1755197Y224712D03*
X1743535Y228961D03*
Y231461D03*
X1751504Y229286D03*
X1755197Y222212D03*
X1751504Y231786D03*
X1770173Y103621D03*
X1772736Y293645D03*
X1770236D03*
Y290845D03*
Y288345D03*
X1772736Y290845D03*
Y288345D03*
X1765097Y466409D03*
X1765083Y487382D03*
X1772768Y818696D03*
X1790136Y399161D03*
Y401661D03*
Y396661D03*
X1778103Y399161D03*
Y401661D03*
Y396661D03*
X1783014Y474513D03*
X1778801Y836469D03*
X1786256Y927626D03*
X1784306Y924601D03*
X1786256Y930626D03*
X1799265Y-44666D03*
Y-39710D03*
Y-29710D03*
Y-34666D03*
X1791302Y829031D03*
X1816385Y1136912D03*
X1813885D03*
Y1144912D03*
X1816385D03*
G54D21*
X51043Y60709D03*
Y150197D03*
X153405Y60709D03*
Y150197D03*
X255767Y60709D03*
Y150197D03*
X279360Y368760D03*
Y421555D03*
Y501752D03*
Y550020D03*
Y636752D03*
X358129Y60709D03*
Y150197D03*
X508130Y60709D03*
Y150197D03*
X610492Y60709D03*
Y150197D03*
X712854Y60709D03*
Y150197D03*
X736446Y368760D03*
Y421555D03*
Y501752D03*
Y550020D03*
Y636752D03*
X815216Y60709D03*
Y150197D03*
X965216Y60709D03*
Y150197D03*
X1067578Y60709D03*
Y150197D03*
X1169940Y60709D03*
Y150197D03*
X1193533Y368760D03*
Y421555D03*
Y501752D03*
Y550020D03*
Y636752D03*
X1272302Y60709D03*
Y150197D03*
X1422303Y60709D03*
Y150197D03*
X1524665Y60709D03*
Y150197D03*
X1627027Y60709D03*
Y150197D03*
X1650620Y368760D03*
Y421555D03*
Y501752D03*
Y550020D03*
Y636752D03*
X1729389Y60709D03*
Y150197D03*
G54D49*
X843012Y1592787D03*
Y1602787D03*
Y1612787D03*
Y1622787D03*
X853012Y1592787D03*
Y1602787D03*
Y1612787D03*
Y1622787D03*
X878012Y1592787D03*
Y1602787D03*
Y1612787D03*
Y1622787D03*
X888012Y1592787D03*
Y1602787D03*
Y1612787D03*
Y1622787D03*
X913012Y1592787D03*
Y1602787D03*
Y1612787D03*
Y1622787D03*
X923012Y1592787D03*
Y1602787D03*
Y1612787D03*
Y1622787D03*
X948012Y1592787D03*
Y1602787D03*
Y1612787D03*
Y1622787D03*
X958012Y1592787D03*
Y1602787D03*
Y1612787D03*
Y1622787D03*
X983012Y1592787D03*
X993012D03*
X983012Y1602787D03*
Y1612787D03*
X993012Y1602787D03*
Y1612787D03*
X983012Y1622787D03*
X993012D03*
X1018012Y1592787D03*
X1028012D03*
X1018012Y1602787D03*
Y1612787D03*
X1028012Y1602787D03*
Y1612787D03*
X1018012Y1622787D03*
X1028012D03*
G54D12*
X3035Y1578036D03*
X3017Y1639466D03*
X14751Y62381D03*
X12601Y92110D03*
X9364Y107501D03*
X16728Y107910D03*
X12652Y116894D03*
X13615Y153263D03*
X10966Y155873D03*
Y152873D03*
X12709Y175777D03*
X9745Y245784D03*
X19075Y278429D03*
X7036Y268371D03*
X14252Y1121333D03*
X11552D03*
X16752D03*
X8952D03*
X14152Y1111633D03*
X11452D03*
X8852D03*
X16652D03*
X14252Y1130333D03*
X16752D03*
X14306Y1138705D03*
X16806D03*
X20079Y1429347D03*
X12327Y1519202D03*
X11995Y1535134D03*
X6567Y1554215D03*
X14375Y1553121D03*
X18409Y1554202D03*
X12000Y1644980D03*
X33288Y109410D03*
Y116497D03*
X30788D03*
X25988D03*
X22439Y106495D03*
X30788Y123584D03*
X33288Y123583D03*
X25988Y123584D03*
X33288Y130670D03*
X30788D03*
X25988D03*
X30788Y137757D03*
X25988D03*
X29201Y151651D03*
X26201D03*
X20709Y175777D03*
X28740Y247292D03*
X21449Y253198D03*
X28740Y267292D03*
X21386Y273198D03*
X23479Y295619D03*
X32452Y581222D03*
X29652D03*
X35252D03*
Y591215D03*
X29652D03*
X32452D03*
X34254Y611091D03*
X29451Y633560D03*
X30369Y663048D03*
X27854Y671553D03*
X30414Y671508D03*
X26596Y874520D03*
X26844Y920354D03*
X24132Y958151D03*
X25371Y980696D03*
X34314Y1215403D03*
X22284Y1464612D03*
X32079Y1525641D03*
X35237Y1532096D03*
X35850Y1556096D03*
X32000Y1644980D03*
X46450Y82984D03*
Y77784D03*
Y75184D03*
Y80384D03*
X48364Y92473D03*
X46450Y85584D03*
X37988Y109410D03*
Y102323D03*
Y116496D03*
Y130670D03*
Y123583D03*
X52437Y137756D03*
X37988D03*
X45984Y163264D03*
X37284Y285272D03*
X42690Y451466D03*
X48596Y458466D03*
X39643Y555194D03*
X36843D03*
X39643Y563194D03*
X36843D03*
X39643Y571194D03*
X36843D03*
X49265Y886660D03*
X52922Y900295D03*
X47916Y947622D03*
X50366Y1086981D03*
Y1082388D03*
X38200Y1089721D03*
X44365Y1086404D03*
X38216Y1093757D03*
X49500Y1199066D03*
X51197Y1218206D03*
X39452Y1250932D03*
X48195Y1511279D03*
X48079Y1525641D03*
Y1529641D03*
Y1521641D03*
X52048Y1556062D03*
X52000Y1644980D03*
X56098Y109410D03*
Y116496D03*
X55964Y103037D03*
X56098Y123583D03*
Y130670D03*
X68896Y226141D03*
X58279Y293796D03*
X66293Y285690D03*
X68793D03*
X66293Y288190D03*
X68793D03*
X60779Y293796D03*
X65759Y437508D03*
X61759D03*
X57759D03*
X54936Y449352D03*
X59522Y448874D03*
X68619Y447269D03*
X68497Y450201D03*
X64550Y504699D03*
X62050D03*
X59550D03*
X68236Y519458D03*
X61752Y516979D03*
X64252D03*
X59252D03*
X55318Y629362D03*
X53129Y627948D03*
X55307Y688473D03*
X66342Y880067D03*
X67316Y865869D03*
X64175Y897500D03*
X67461Y912983D03*
X63303Y912835D03*
X57178Y981386D03*
X69263Y1053152D03*
X55049Y1082343D03*
X55004Y1086937D03*
X58981Y1105100D03*
X56381D03*
X61581D03*
X64281D03*
X61681Y1114800D03*
X56481D03*
X59081D03*
X64381D03*
X57218Y1123867D03*
X55397Y1133688D03*
X57897D03*
X58250Y1220896D03*
X65940Y1209382D03*
X58250Y1227796D03*
Y1230296D03*
Y1237196D03*
Y1234696D03*
Y1223396D03*
X57185Y1480808D03*
X57144Y1491047D03*
X56114Y1556061D03*
X68743Y1583498D03*
X73381Y94017D03*
X69381D03*
X71422Y151540D03*
X75072Y191941D03*
X81572Y184619D03*
X74939Y188727D03*
X83552Y206760D03*
X71696Y226141D03*
X76766Y256535D03*
X84766D03*
X71593Y285690D03*
Y288190D03*
X75819Y290755D03*
X79819D03*
X83819D03*
X71826Y480705D03*
X75736Y519458D03*
X73236D03*
X70736D03*
X81740Y636250D03*
X69670Y633205D03*
Y636005D03*
X81740Y633450D03*
X69670Y638805D03*
X81740Y639050D03*
X74414Y681907D03*
X76991Y946134D03*
X84679Y1018368D03*
X70059Y1071656D03*
X69373Y1063389D03*
X70059Y1079656D03*
X80290Y1345691D03*
Y1350683D03*
X75334Y1345691D03*
Y1350683D03*
X80290Y1357603D03*
Y1362595D03*
X75334Y1357603D03*
Y1362595D03*
X80290Y1381801D03*
Y1369889D03*
Y1374881D03*
X75334Y1381801D03*
Y1374881D03*
Y1369889D03*
X80290Y1386793D03*
X75334D03*
X87000Y1597855D03*
X76005Y1580680D03*
X82433Y1580590D03*
X72000Y1644980D03*
X88080Y103603D03*
X87002Y146461D03*
X85904Y152367D03*
X87604Y180572D03*
X92287Y180527D03*
X96010Y192421D03*
X92242Y185121D03*
X87604Y185165D03*
X85796Y279208D03*
X89900Y281307D03*
X90257Y445506D03*
X88875Y840940D03*
X91581Y877859D03*
Y874859D03*
X87853Y899220D03*
X91128Y1006487D03*
X99836Y997860D03*
X95836D03*
X100594Y1035088D03*
X97247Y1030568D03*
X103124Y1165091D03*
X87574Y1345691D03*
Y1350683D03*
X99814D03*
Y1345691D03*
X92530D03*
Y1350683D03*
X87574Y1362595D03*
Y1357603D03*
X99814Y1362595D03*
Y1357603D03*
X92530Y1362595D03*
Y1357603D03*
X87574Y1374881D03*
Y1369795D03*
Y1381801D03*
X99814D03*
Y1374881D03*
Y1369889D03*
X92530Y1374881D03*
Y1369795D03*
Y1381801D03*
X87574Y1399079D03*
Y1393993D03*
Y1386793D03*
X99814Y1399079D03*
Y1394087D03*
Y1386793D03*
X92530Y1393993D03*
Y1399079D03*
Y1386793D03*
X87574Y1410991D03*
Y1405999D03*
X99814Y1410991D03*
Y1405999D03*
X92530Y1410991D03*
Y1405999D03*
X92000Y1644980D03*
X107364Y113394D03*
Y110394D03*
X110013Y110784D03*
X110152Y130898D03*
X117607Y133298D03*
X111754Y134579D03*
X107540Y172665D03*
Y180665D03*
X107572Y200864D03*
Y212864D03*
Y216864D03*
Y221864D03*
X109329Y252371D03*
X112474Y716315D03*
X114397Y727974D03*
X113601Y881266D03*
X107641Y865224D03*
X103836Y997860D03*
X111836D03*
X114770Y1009354D03*
X107836Y997860D03*
X115836D03*
X108933Y1102091D03*
X112433D03*
X103124D03*
X112433Y1114691D03*
X103124D03*
X108933D03*
Y1127291D03*
X112433D03*
X103124D03*
X112433Y1139891D03*
X103124Y1152491D03*
X108933D03*
X112433D03*
X108933Y1165091D03*
X112433D03*
X103184Y1177691D03*
X108933D03*
X112433D03*
X109415Y1202103D03*
X112795Y1223749D03*
X104770Y1350683D03*
Y1345691D03*
X112054D03*
Y1350683D03*
X117010Y1345691D03*
Y1350683D03*
X104770Y1362595D03*
Y1357603D03*
X112054Y1362595D03*
Y1357603D03*
X117010Y1362595D03*
Y1357603D03*
Y1369889D03*
Y1374881D03*
Y1381801D03*
X104770D03*
Y1374881D03*
Y1369889D03*
X112054D03*
Y1374881D03*
Y1381801D03*
X104770Y1399079D03*
Y1394087D03*
Y1386793D03*
X112054Y1399079D03*
Y1394087D03*
Y1386793D03*
X117010Y1394087D03*
Y1399079D03*
Y1386793D03*
X104770Y1410991D03*
Y1405999D03*
X112054Y1410991D03*
Y1405999D03*
X117010Y1410991D03*
Y1405999D03*
X107669Y1456451D03*
Y1465913D03*
X116330Y1465513D03*
X107669Y1461182D03*
X116330Y1460782D03*
X107669Y1481267D03*
X116330Y1480867D03*
X107669Y1476536D03*
X116330Y1476136D03*
Y1470244D03*
X107669Y1471805D03*
X116330Y1491490D03*
Y1485598D03*
X107669Y1487159D03*
Y1496621D03*
X116330Y1496221D03*
X107669Y1491890D03*
X116330Y1506845D03*
Y1500952D03*
X107669Y1502514D03*
X116330Y1511576D03*
X107669Y1511976D03*
Y1507245D03*
X116330Y1516307D03*
X107669Y1563544D03*
X116330Y1563144D03*
X107669Y1558813D03*
Y1568275D03*
X116330Y1567875D03*
X107669Y1578898D03*
X116330Y1578498D03*
Y1572606D03*
X107669Y1574167D03*
Y1583629D03*
X116330Y1583229D03*
X107669Y1594253D03*
X116330Y1593853D03*
Y1587960D03*
X107669Y1589522D03*
Y1609607D03*
X116330Y1609207D03*
X107669Y1598984D03*
X116330Y1598584D03*
Y1603315D03*
X107669Y1604876D03*
X116330Y1613938D03*
Y1618669D03*
X107669Y1614338D03*
X112000Y1644980D03*
X128350Y116497D03*
X133150D03*
X124606Y106495D03*
X125599Y109172D03*
X122599D03*
X133150Y123584D03*
X128350D03*
X133150Y130670D03*
X128350D03*
Y137757D03*
X133150D03*
X126246Y141228D03*
X124340Y146012D03*
X129134Y150847D03*
X131102Y247292D03*
X123811Y253198D03*
X125125Y362403D03*
X118122Y747565D03*
X122887Y884000D03*
X127067Y891495D03*
X124079Y1009354D03*
X119836Y997860D03*
X131836D03*
X127836D03*
X123836D03*
X120579Y1009354D03*
Y1021954D03*
X124079D03*
X133870Y1105091D03*
Y1117691D03*
Y1130291D03*
Y1142891D03*
Y1155491D03*
Y1168091D03*
X121211Y1215195D03*
X126937Y1209607D03*
X124294Y1350683D03*
Y1345691D03*
X129250Y1350683D03*
Y1345691D03*
X124294Y1362595D03*
Y1357603D03*
X129250D03*
Y1362595D03*
X124294Y1374881D03*
Y1369889D03*
Y1381801D03*
X129250Y1374881D03*
Y1369889D03*
Y1381801D03*
X124294Y1394087D03*
Y1399079D03*
Y1386793D03*
X129250Y1394087D03*
Y1399079D03*
Y1386793D03*
X124294Y1405999D03*
Y1410991D03*
X129250Y1405999D03*
Y1410991D03*
X124992Y1465913D03*
Y1456451D03*
Y1461182D03*
X133653Y1465513D03*
Y1460782D03*
X124992Y1471805D03*
Y1476536D03*
Y1481267D03*
X133653Y1476136D03*
Y1470244D03*
Y1480867D03*
Y1496221D03*
X124992Y1487159D03*
Y1491890D03*
Y1496621D03*
X133653Y1491490D03*
Y1485598D03*
Y1506845D03*
Y1500952D03*
Y1511576D03*
X124992Y1511976D03*
Y1507245D03*
Y1502514D03*
X133653Y1516307D03*
X124992Y1558813D03*
Y1563544D03*
X133653Y1563144D03*
Y1567875D03*
X124992Y1574167D03*
Y1578898D03*
X133653Y1578498D03*
Y1572606D03*
X124992Y1568275D03*
Y1589522D03*
Y1594253D03*
X133653Y1593853D03*
Y1587960D03*
X124992Y1583629D03*
X133653Y1583229D03*
X124992Y1609607D03*
Y1604876D03*
Y1598984D03*
X133653Y1609207D03*
Y1598584D03*
Y1603315D03*
X124992Y1614338D03*
X133653Y1613938D03*
Y1618669D03*
X132000Y1644980D03*
X148812Y80384D03*
Y82984D03*
Y75184D03*
Y77784D03*
Y85584D03*
X135650Y109410D03*
X140350Y116496D03*
Y109410D03*
Y102323D03*
X135650Y116497D03*
Y123583D03*
Y130670D03*
X140350D03*
Y123583D03*
Y137756D03*
X136604Y450750D03*
X140703Y536382D03*
X145670Y597580D03*
X147893Y599588D03*
X147155Y589556D03*
X147094Y592354D03*
X145609Y594668D03*
X147896Y596095D03*
X147925Y615600D03*
X147893Y607588D03*
X139836Y997860D03*
X147836D03*
X143836D03*
X135836D03*
X145516Y1024954D03*
Y1012354D03*
X148534Y1046476D03*
X134457Y1180654D03*
X141490Y1345691D03*
Y1350683D03*
X136534D03*
Y1345691D03*
X148774Y1350683D03*
Y1345691D03*
X141490Y1357603D03*
Y1362595D03*
X136534D03*
Y1357603D03*
X148774D03*
Y1362595D03*
X141490Y1369889D03*
Y1374881D03*
Y1381801D03*
X136534Y1369889D03*
Y1381801D03*
Y1374881D03*
X148774Y1369889D03*
Y1381801D03*
Y1374881D03*
X141490Y1386793D03*
Y1394087D03*
Y1399079D03*
X136534D03*
Y1394087D03*
Y1386793D03*
X148774Y1394087D03*
Y1399079D03*
Y1386793D03*
X141490Y1405999D03*
Y1410991D03*
X136534D03*
Y1405999D03*
X148774D03*
Y1410991D03*
X142315Y1456451D03*
Y1461182D03*
Y1465913D03*
Y1471805D03*
Y1476536D03*
Y1481267D03*
Y1487159D03*
Y1491890D03*
Y1496621D03*
Y1507245D03*
Y1502514D03*
Y1511976D03*
Y1558813D03*
Y1563544D03*
Y1574167D03*
Y1578898D03*
Y1568275D03*
Y1589522D03*
Y1594253D03*
Y1583629D03*
Y1609607D03*
Y1604876D03*
Y1598984D03*
Y1614338D03*
X151366Y92849D03*
X158460Y116496D03*
X158326Y103037D03*
X158460Y109410D03*
Y130670D03*
Y123583D03*
X155051Y137756D03*
X163141Y293796D03*
X160641D03*
X166528Y312392D03*
X157375Y555234D03*
X157090Y562003D03*
X152386Y634946D03*
X151836Y997860D03*
X159836D03*
X164028Y1041468D03*
X155513Y1065148D03*
X161014Y1345691D03*
Y1350683D03*
X153730Y1345691D03*
Y1350683D03*
X165970Y1345691D03*
Y1350683D03*
X161014Y1362595D03*
Y1357603D03*
X153730Y1362595D03*
Y1357603D03*
X165970Y1362595D03*
Y1357603D03*
X161014Y1381801D03*
Y1369889D03*
Y1374881D03*
X153730Y1369889D03*
Y1381801D03*
Y1374881D03*
X165970D03*
Y1381801D03*
Y1369889D03*
X161014Y1394087D03*
Y1386793D03*
X153730Y1394087D03*
Y1386793D03*
X165970Y1394087D03*
Y1386793D03*
X161014Y1399079D03*
X153730D03*
X165970D03*
X161014Y1410991D03*
Y1405999D03*
X153730D03*
Y1410991D03*
X165970D03*
Y1405999D03*
X159637Y1461182D03*
X150976Y1465513D03*
Y1460782D03*
X159637Y1465913D03*
Y1456451D03*
X150976Y1476136D03*
Y1470244D03*
Y1480867D03*
X159637Y1471805D03*
Y1476536D03*
Y1481267D03*
Y1496621D03*
X150976Y1491490D03*
Y1485598D03*
Y1496221D03*
X159637Y1487159D03*
Y1491890D03*
X150976Y1500952D03*
Y1511576D03*
X159637Y1507245D03*
Y1502514D03*
Y1511976D03*
X150976Y1506845D03*
Y1516307D03*
X159637Y1558813D03*
Y1563544D03*
X150976Y1563144D03*
X159637Y1578898D03*
X150976Y1567875D03*
Y1578498D03*
Y1572606D03*
X159637Y1568275D03*
Y1574167D03*
X150976Y1583229D03*
Y1593853D03*
Y1587960D03*
X159637Y1583629D03*
Y1589522D03*
Y1594253D03*
X150976Y1609207D03*
Y1598584D03*
Y1603315D03*
X159637Y1609607D03*
Y1604876D03*
Y1598984D03*
X150976Y1613938D03*
Y1618669D03*
X159637Y1614338D03*
X152000Y1644980D03*
X179743Y94017D03*
X175743D03*
X171743D03*
X175871Y110445D03*
X180863Y115401D03*
Y110445D03*
X175871Y115401D03*
X180863Y129574D03*
Y124618D03*
X175871Y129574D03*
Y124618D03*
X173784Y151540D03*
X177434Y191941D03*
X177301Y188727D03*
X171258Y226141D03*
X174058D03*
X179128Y256535D03*
X173955Y285690D03*
Y288190D03*
X171155Y285690D03*
X168655Y288190D03*
X171155D03*
X168655Y285690D03*
X182181Y290755D03*
X178181D03*
X177369Y389154D03*
Y396240D03*
Y403327D03*
Y410413D03*
Y417500D03*
Y424587D03*
Y431673D03*
Y438760D03*
Y445847D03*
Y467539D03*
Y474626D03*
Y488799D03*
Y481713D03*
Y495886D03*
Y511673D03*
Y518760D03*
Y525847D03*
Y532933D03*
Y540020D03*
Y547106D03*
X176650Y602197D03*
X177114Y595108D03*
X173254Y1345691D03*
Y1350683D03*
X178210Y1345691D03*
Y1350683D03*
X173254Y1362595D03*
Y1357603D03*
X178210D03*
Y1362595D03*
X173254Y1374881D03*
Y1369889D03*
Y1381801D03*
X178210Y1374881D03*
Y1369889D03*
Y1381801D03*
X173254Y1394087D03*
Y1386793D03*
X178210Y1394087D03*
Y1386793D03*
X173254Y1399079D03*
X178210D03*
X173254Y1405999D03*
Y1410991D03*
X178210Y1405999D03*
Y1410991D03*
X168299Y1465513D03*
Y1460782D03*
X176960Y1465914D03*
Y1456452D03*
Y1461183D03*
X168299Y1476136D03*
Y1470244D03*
Y1480867D03*
X176960Y1476537D03*
Y1471806D03*
Y1481268D03*
X168299Y1491490D03*
Y1485598D03*
Y1496221D03*
X176960Y1491891D03*
Y1487160D03*
Y1496622D03*
Y1507246D03*
Y1502515D03*
X168299Y1506845D03*
Y1500952D03*
Y1511576D03*
X176960Y1511977D03*
X168299Y1516307D03*
Y1563144D03*
X176960Y1563544D03*
Y1558813D03*
Y1568275D03*
X168299Y1578498D03*
Y1572606D03*
Y1567875D03*
Y1583229D03*
X176960Y1583629D03*
X168299Y1593853D03*
Y1587960D03*
X176960Y1594253D03*
Y1589522D03*
X168299Y1609207D03*
Y1598584D03*
Y1603315D03*
X176960Y1609607D03*
Y1598984D03*
Y1604876D03*
X168299Y1613938D03*
Y1618669D03*
X176960Y1614338D03*
X172000Y1644980D03*
X188820Y80140D03*
Y84140D03*
Y76140D03*
X183752Y94017D03*
X186273Y117557D03*
X191265D03*
X186273Y131731D03*
Y122513D03*
X191265D03*
Y131731D03*
X189364Y146461D03*
X186273Y136687D03*
X191265D03*
X188266Y152367D03*
X194649Y180527D03*
X189966Y180572D03*
X198372Y192421D03*
X189966Y185165D03*
X194604Y185121D03*
X183934Y184619D03*
X185914Y206760D03*
X187128Y256535D03*
X188158Y279208D03*
X192262Y281307D03*
X186181Y290755D03*
X191988Y389154D03*
X190518Y396240D03*
X194603Y422864D03*
X195295Y414823D03*
X194673Y429832D03*
X194278Y436447D03*
X196313Y447953D03*
X195480Y467539D03*
X194222Y472772D03*
X194956Y487711D03*
X195069Y479104D03*
X195480Y495886D03*
X190829Y516841D03*
X194080Y510565D03*
X185654Y552872D03*
X185776Y550123D03*
X185099Y562443D03*
X186867Y560675D03*
X187408Y572334D03*
X185640Y574102D03*
X193723Y656942D03*
X185494Y1345597D03*
Y1350683D03*
X190450Y1345597D03*
Y1350683D03*
X197734Y1345691D03*
Y1350683D03*
X185494Y1362595D03*
Y1357603D03*
X197734Y1362595D03*
Y1357603D03*
X190450Y1362595D03*
Y1357603D03*
X185494Y1374881D03*
Y1381801D03*
Y1369889D03*
X197734D03*
Y1381801D03*
Y1374881D03*
X190450Y1369889D03*
Y1374881D03*
Y1381801D03*
X185494Y1393993D03*
Y1386793D03*
X190450Y1393993D03*
Y1386793D03*
X197734Y1394087D03*
Y1386793D03*
X185494Y1399079D03*
X190450D03*
X197734D03*
X185494Y1410991D03*
Y1405999D03*
X190450Y1410991D03*
Y1405999D03*
X197734D03*
Y1410991D03*
X185622Y1465513D03*
Y1460782D03*
Y1480868D03*
Y1476137D03*
Y1470244D03*
Y1485599D03*
X192000Y1644980D03*
X211262Y60922D03*
X206398Y55513D03*
X208463Y96472D03*
X202195Y117261D03*
X209726Y113394D03*
Y110394D03*
X212375Y110784D03*
X211969Y133298D03*
X214116Y134579D03*
X209902Y172665D03*
Y180665D03*
X209934Y200864D03*
Y212864D03*
Y216864D03*
Y221864D03*
X211691Y252371D03*
X215380Y389153D03*
X210580D03*
X215380Y396240D03*
X208080Y403327D03*
X215380Y403326D03*
X210580D03*
X208080Y410413D03*
X210580D03*
X215380D03*
X208080Y396240D03*
X210580D03*
X208080Y417500D03*
X215380Y417499D03*
X210580D03*
X208080Y424586D03*
X210580D03*
X215380D03*
X208080Y431673D03*
Y438760D03*
X210580D03*
X215380D03*
Y431673D03*
X210580D03*
X208080Y445847D03*
X215380Y467539D03*
X210580D03*
X208080Y474626D03*
X210580D03*
X215380D03*
Y488799D03*
X208080D03*
X210580D03*
Y481712D03*
X208080D03*
X215380D03*
X208080Y495886D03*
X215380Y518760D03*
X210580D03*
X208080D03*
X210580Y511673D03*
X215380D03*
X210580Y532933D03*
X208080D03*
Y540020D03*
Y525846D03*
X210580D03*
X215380D03*
Y532933D03*
X212460Y560500D03*
X209429Y625300D03*
X202690Y1345597D03*
Y1350683D03*
Y1362595D03*
Y1357603D03*
Y1369889D03*
Y1381801D03*
Y1374881D03*
Y1394087D03*
Y1386793D03*
Y1399079D03*
Y1405999D03*
Y1410991D03*
X211473Y1446675D03*
X213296Y1438215D03*
X211473Y1451631D03*
Y1462631D03*
Y1457675D03*
X224961Y109172D03*
X226968Y106495D03*
X230712Y116497D03*
X227961Y109172D03*
X230712Y123584D03*
Y130670D03*
X219969Y133298D03*
X228608Y141228D03*
X230712Y137757D03*
X226702Y146012D03*
X231496Y150847D03*
X226173Y253198D03*
X228760Y316122D03*
X223925Y543925D03*
X224500Y555000D03*
X222646Y607542D03*
X217945Y1423924D03*
X217799Y1433684D03*
X216465Y1446675D03*
X222253Y1438483D03*
X216465Y1451631D03*
Y1462631D03*
Y1457675D03*
X229260Y1469587D03*
X218171Y1474460D03*
X224176Y1492816D03*
X223235Y1506770D03*
X222908Y1502028D03*
X226957Y1510442D03*
X216342Y1515642D03*
X217519Y1537172D03*
X242712Y116496D03*
Y109410D03*
Y102323D03*
X238012Y116497D03*
X235512D03*
X238012Y109410D03*
Y123583D03*
Y130670D03*
X235512D03*
X242712D03*
Y123583D03*
X235512Y123584D03*
Y137757D03*
X242712Y137756D03*
X233464Y247292D03*
X236349Y339428D03*
X247333Y599506D03*
X241967Y616063D03*
X243078Y636486D03*
X240249Y628328D03*
X241084Y638243D03*
X246583Y665140D03*
X241850Y678462D03*
X247600Y848500D03*
X240845Y1345691D03*
Y1350683D03*
X245801Y1345691D03*
Y1350683D03*
X240845Y1357603D03*
Y1362595D03*
X245801Y1357603D03*
Y1362595D03*
X240845Y1381801D03*
Y1374881D03*
Y1369889D03*
X245801Y1381801D03*
Y1374881D03*
Y1369889D03*
X240845Y1386793D03*
X245801D03*
X232675Y1466801D03*
X240466Y1503857D03*
X243268Y1501903D03*
X237700Y1531600D03*
X251174Y77784D03*
Y80384D03*
Y82984D03*
Y75184D03*
Y85584D03*
X253728Y92849D03*
X260688Y103037D03*
X260822Y116496D03*
Y109410D03*
Y130670D03*
Y123583D03*
X257413Y137756D03*
X263003Y293796D03*
X257226Y312081D03*
X265011Y403307D03*
X255000Y427017D03*
X254692Y431029D03*
X253758Y435029D03*
X254678Y449873D03*
X261605Y465492D03*
Y472579D03*
X259105D03*
X254305D03*
X261605Y486752D03*
X254305D03*
X259105Y479666D03*
X261605D03*
X254305D03*
X259105Y486752D03*
X254305Y493839D03*
X259105D03*
X261605Y516713D03*
X259105D03*
Y523800D03*
X261605D03*
X254305D03*
Y516713D03*
X261605Y509626D03*
Y530886D03*
X259105D03*
Y537973D03*
X254305Y530886D03*
Y537973D03*
Y566752D03*
X261605Y559665D03*
Y566752D03*
X259105D03*
X261605Y588012D03*
X259105Y588013D03*
X254305Y573839D03*
X261605D03*
X259105D03*
X261605Y580926D03*
X259105D03*
X254305D03*
Y588013D03*
X259105Y602186D03*
X254305D03*
Y595099D03*
X259105D03*
X261605D03*
Y602185D03*
X254305Y609272D03*
X259105D03*
X261605D03*
X259105Y616359D03*
X254305D03*
X248984Y638125D03*
X258867Y680499D03*
X258041Y1350683D03*
Y1345691D03*
X253085Y1350683D03*
Y1345691D03*
X258041Y1362595D03*
X253085D03*
X258041Y1357603D03*
X253085D03*
X258041Y1381801D03*
Y1369795D03*
Y1374881D03*
X253085Y1381801D03*
Y1369795D03*
Y1374881D03*
Y1393993D03*
Y1399079D03*
X258041Y1386793D03*
Y1399079D03*
Y1393993D03*
X253085Y1386793D03*
X258041Y1405999D03*
Y1410991D03*
X253085Y1405999D03*
Y1410991D03*
X248042Y1532900D03*
X274105Y94017D03*
X278105D03*
X278233Y115401D03*
Y110445D03*
Y129574D03*
Y124618D03*
X276146Y151540D03*
X279796Y191941D03*
X279663Y188727D03*
X276420Y226141D03*
X273620D03*
X276317Y288190D03*
X273517Y285690D03*
X271017Y288190D03*
X273517D03*
X271017Y285690D03*
X265503Y293796D03*
X276317Y285690D03*
X274425Y390500D03*
X265011Y410394D03*
X266405Y451319D03*
Y458406D03*
Y465492D03*
X266229Y462264D03*
X266405Y472579D03*
Y479665D03*
Y486752D03*
Y493839D03*
Y523799D03*
Y516713D03*
Y509626D03*
Y530886D03*
Y537973D03*
Y566752D03*
Y559665D03*
Y580926D03*
Y588012D03*
Y573839D03*
Y602185D03*
Y595099D03*
Y609272D03*
Y616358D03*
X269700Y884600D03*
X269900Y914200D03*
X270100Y946500D03*
X277565Y1350683D03*
Y1345691D03*
X265325D03*
Y1350683D03*
X270281Y1345691D03*
Y1350683D03*
X277565Y1362595D03*
X265325D03*
X270281D03*
X277565Y1357603D03*
X265325D03*
X270281D03*
X277565Y1381801D03*
Y1374881D03*
Y1369889D03*
X265325D03*
Y1374881D03*
Y1381801D03*
X270281Y1369889D03*
Y1374881D03*
Y1381801D03*
X277565Y1386793D03*
Y1394087D03*
Y1399079D03*
X265325Y1394087D03*
Y1399079D03*
Y1386793D03*
X270281Y1399079D03*
Y1394087D03*
Y1386793D03*
X265325Y1405999D03*
Y1410991D03*
X270281Y1405999D03*
Y1410991D03*
X277565Y1405999D03*
Y1410991D03*
X272000Y1644980D03*
X291182Y84140D03*
Y80140D03*
Y76140D03*
X282105Y94017D03*
X286114D03*
X288635Y117557D03*
X283225Y115401D03*
Y110445D03*
X293627Y117557D03*
X288635Y131731D03*
Y122513D03*
X283225Y129574D03*
Y124618D03*
X293627Y122513D03*
Y131731D03*
X291726Y146461D03*
X293627Y136687D03*
X288635D03*
X290628Y152367D03*
X292328Y180572D03*
Y185165D03*
X286296Y184619D03*
X288276Y206760D03*
X281490Y256535D03*
X289490D03*
X290520Y279208D03*
X294624Y281307D03*
X284543Y290755D03*
X280543D03*
X288543D03*
X284075Y381500D03*
X284482Y460250D03*
X284516Y465492D03*
X282247Y470136D03*
X284516Y472579D03*
Y479665D03*
Y486752D03*
Y493839D03*
Y516713D03*
Y509626D03*
X283377Y532756D03*
X283456Y525483D03*
X280976Y537973D03*
X284516Y559665D03*
Y566752D03*
X284366Y579978D03*
X284516Y573839D03*
X284580Y608117D03*
X282521Y1345691D03*
X289805Y1350683D03*
Y1345691D03*
X294761Y1350683D03*
Y1345691D03*
X282521Y1350683D03*
X289805Y1362595D03*
X294761D03*
X282521D03*
X289805Y1357603D03*
X294761D03*
X282521D03*
X289805Y1374881D03*
Y1369889D03*
Y1381801D03*
X294761Y1374881D03*
Y1369889D03*
Y1381801D03*
X282521D03*
Y1374881D03*
Y1369889D03*
X289805Y1394087D03*
Y1399079D03*
Y1386793D03*
X294761Y1394087D03*
Y1399079D03*
Y1386793D03*
X282521D03*
Y1399079D03*
Y1394087D03*
X289805Y1405999D03*
Y1410991D03*
X294761Y1405999D03*
Y1410991D03*
X282521Y1405999D03*
Y1410991D03*
X280897Y1465913D03*
X289558Y1465513D03*
X280897Y1461182D03*
X289558Y1460782D03*
X280897Y1456451D03*
X289558Y1480867D03*
X280897Y1476536D03*
X289558Y1476136D03*
Y1470244D03*
X280897Y1471805D03*
Y1481267D03*
Y1491890D03*
X289558Y1491490D03*
Y1485598D03*
X280897Y1487159D03*
Y1496621D03*
X289558Y1496221D03*
X280897Y1507245D03*
X289558Y1506845D03*
Y1500952D03*
X280897Y1502514D03*
X289558Y1511576D03*
X280897Y1511976D03*
X289558Y1516307D03*
X280897Y1563544D03*
X289558Y1563144D03*
X280897Y1558813D03*
Y1574167D03*
Y1568275D03*
X289558Y1567875D03*
X280897Y1578898D03*
X289558Y1578498D03*
Y1572606D03*
Y1593853D03*
Y1587960D03*
X280897Y1589522D03*
Y1583629D03*
X289558Y1583229D03*
X280897Y1594253D03*
Y1609607D03*
X289558Y1609207D03*
X280897Y1598984D03*
X289558Y1598584D03*
Y1603315D03*
X280897Y1604876D03*
Y1614338D03*
X289558Y1613938D03*
Y1618669D03*
X292000Y1644980D03*
X308760Y55513D03*
X310882Y96613D03*
X305953Y91951D03*
X312088Y113394D03*
X304557Y117261D03*
X297011Y180527D03*
X312264Y172665D03*
Y180665D03*
X299759Y190285D03*
X296966Y185121D03*
X312296Y212864D03*
Y200864D03*
Y221864D03*
Y216864D03*
X306812Y342319D03*
X309258Y389912D03*
Y393924D03*
Y385912D03*
Y409924D03*
Y405924D03*
Y401924D03*
X306673Y418838D03*
X298507Y445908D03*
X302457Y445787D03*
X302045Y1345691D03*
Y1350683D03*
X307001D03*
Y1345691D03*
X302045Y1362595D03*
X307001D03*
X302045Y1357603D03*
X307001D03*
X302045Y1374881D03*
Y1381801D03*
Y1369889D03*
X307001Y1374881D03*
Y1369889D03*
Y1381801D03*
X302045Y1386793D03*
Y1394087D03*
Y1399079D03*
X307001Y1386793D03*
Y1399079D03*
Y1394087D03*
X302045Y1405999D03*
Y1410991D03*
X307001Y1405999D03*
Y1410991D03*
X298220Y1465913D03*
Y1456451D03*
Y1461182D03*
X306881Y1465513D03*
Y1460782D03*
Y1470244D03*
Y1480867D03*
X298220Y1471805D03*
Y1476536D03*
Y1481267D03*
X306881Y1476136D03*
X298220Y1487159D03*
Y1491890D03*
Y1496621D03*
X306881Y1491490D03*
Y1485598D03*
Y1496221D03*
X298220Y1507245D03*
Y1502514D03*
X306881Y1506845D03*
Y1500952D03*
Y1511576D03*
X298220Y1511976D03*
X306881Y1516307D03*
X298220Y1558813D03*
Y1563544D03*
X306881Y1563144D03*
X298220Y1568275D03*
X306881Y1567875D03*
X298220Y1574167D03*
Y1578898D03*
X306881Y1578498D03*
Y1572606D03*
X298220Y1583629D03*
X306881Y1583229D03*
X298220Y1589522D03*
Y1594253D03*
X306881Y1593853D03*
Y1587960D03*
Y1598584D03*
Y1603315D03*
X298220Y1609607D03*
Y1604876D03*
Y1598984D03*
X306881Y1609207D03*
X298220Y1614338D03*
X306881Y1613938D03*
Y1618669D03*
X312000Y1644980D03*
X313624Y60922D03*
X327323Y109172D03*
X314737Y110784D03*
X314854Y130898D03*
X322331Y133298D03*
X329064Y146012D03*
X316478Y134579D03*
X328535Y253198D03*
X314053Y252371D03*
X323882Y303839D03*
X315904Y336324D03*
X320483Y353506D03*
X319241Y1350683D03*
Y1345691D03*
X314285D03*
Y1350683D03*
X326525Y1345691D03*
Y1350683D03*
X319241Y1362595D03*
X314285D03*
X326525D03*
X319241Y1357603D03*
X314285D03*
X326525D03*
X319241Y1374881D03*
Y1381801D03*
Y1369889D03*
X314285Y1374881D03*
Y1381801D03*
Y1369889D03*
X326525Y1381801D03*
Y1369889D03*
Y1374881D03*
X319241Y1386793D03*
Y1399079D03*
Y1394087D03*
X314285Y1386793D03*
Y1399079D03*
Y1394087D03*
X326525Y1399079D03*
Y1394087D03*
Y1386793D03*
X319241Y1410991D03*
Y1405999D03*
X314285Y1410991D03*
Y1405999D03*
X326525Y1410991D03*
Y1405999D03*
X315543Y1465913D03*
Y1456451D03*
Y1461182D03*
X324204Y1465513D03*
Y1460782D03*
Y1480867D03*
X315543Y1471805D03*
Y1476536D03*
Y1481267D03*
X324204Y1476136D03*
Y1470244D03*
X315543Y1487159D03*
Y1491890D03*
Y1496621D03*
X324204Y1491490D03*
Y1485598D03*
Y1496221D03*
Y1500952D03*
Y1511576D03*
X315543Y1507245D03*
Y1502514D03*
Y1511976D03*
X324204Y1506845D03*
Y1516307D03*
X315543Y1558813D03*
Y1563544D03*
X324204Y1563144D03*
X315543Y1574167D03*
Y1578898D03*
X324204Y1567875D03*
Y1578498D03*
Y1572606D03*
X315543Y1568275D03*
Y1583629D03*
Y1589522D03*
Y1594253D03*
X324204Y1583229D03*
Y1593853D03*
Y1587960D03*
X315543Y1609607D03*
Y1604876D03*
Y1598984D03*
X324204Y1609207D03*
Y1598584D03*
Y1603315D03*
X315543Y1614338D03*
X324204Y1613938D03*
Y1618669D03*
X329330Y106495D03*
X345074Y116496D03*
X337874Y116497D03*
X340374D03*
X345074Y109410D03*
Y102323D03*
X340374Y109410D03*
X333074Y116497D03*
X330323Y109172D03*
X337874Y130670D03*
X345074D03*
Y123583D03*
X340374D03*
X337874Y123584D03*
X333074D03*
Y130670D03*
X340374D03*
X333074Y137757D03*
X337874D03*
X330970Y141228D03*
X345074Y137756D03*
X333858Y150847D03*
X335826Y247292D03*
X338358Y554861D03*
X337564Y1018294D03*
X337629Y1186071D03*
X336901Y1196407D03*
X338765Y1350683D03*
Y1345691D03*
X331481D03*
Y1350683D03*
X343721Y1345691D03*
Y1350683D03*
X331481Y1362595D03*
X343721D03*
X338765D03*
X331481Y1357603D03*
X343721D03*
X338765D03*
X331481Y1374881D03*
Y1381801D03*
Y1369889D03*
X343721Y1381801D03*
Y1369889D03*
Y1374881D03*
X338765Y1381801D03*
Y1369889D03*
Y1374881D03*
X331481Y1399079D03*
Y1394087D03*
Y1386793D03*
X343721D03*
Y1394087D03*
Y1399079D03*
X338765Y1386793D03*
Y1394087D03*
Y1399079D03*
X331481Y1410991D03*
Y1405999D03*
X343721Y1410991D03*
Y1405999D03*
X338765Y1410991D03*
Y1405999D03*
X341527Y1460782D03*
X332865Y1465913D03*
Y1456451D03*
Y1461182D03*
X341527Y1465513D03*
Y1476136D03*
Y1470244D03*
Y1480867D03*
X332865Y1471805D03*
Y1476536D03*
Y1481267D03*
X341527Y1491490D03*
Y1485598D03*
Y1496221D03*
X332865Y1487159D03*
Y1491890D03*
Y1496621D03*
Y1511976D03*
X341527Y1506845D03*
Y1500952D03*
Y1511576D03*
X332865Y1507245D03*
Y1502514D03*
X341527Y1516307D03*
X332865Y1558813D03*
Y1563544D03*
X341527Y1563144D03*
X332865Y1578898D03*
X341527Y1567875D03*
Y1578498D03*
Y1572606D03*
X332865Y1568275D03*
Y1574167D03*
Y1583629D03*
Y1589522D03*
Y1594253D03*
X341527Y1583229D03*
Y1593853D03*
Y1587960D03*
X332865Y1598984D03*
X341527Y1609207D03*
Y1598584D03*
Y1603315D03*
X332865Y1609607D03*
Y1604876D03*
X341527Y1613938D03*
Y1618669D03*
X332865Y1614338D03*
X332000Y1644980D03*
X353536Y82984D03*
Y80384D03*
Y77784D03*
Y75184D03*
X356090Y92849D03*
X353536Y85584D03*
X359525Y137756D03*
X356423Y301288D03*
X348375Y322284D03*
X348968Y333138D03*
X359278Y491870D03*
X356778D03*
X358096Y867459D03*
X358086Y884616D03*
X357962Y898800D03*
X358024Y912085D03*
X358085Y923327D03*
X355929Y1132042D03*
X351563Y1132410D03*
X349700Y1148000D03*
X357947Y1159455D03*
X352536Y1160168D03*
X357297Y1192709D03*
X360659Y1209789D03*
X355961Y1350683D03*
X351005Y1345597D03*
Y1350683D03*
X355961Y1345597D03*
X351005Y1362595D03*
X355961D03*
X351005Y1357603D03*
X355961D03*
X351005Y1374881D03*
Y1381801D03*
Y1369889D03*
X355961Y1381801D03*
Y1374881D03*
Y1369889D03*
X351005Y1399079D03*
Y1393993D03*
Y1386793D03*
X355961D03*
Y1399079D03*
Y1393993D03*
X351005Y1410991D03*
Y1405999D03*
X355961D03*
Y1410991D03*
X350188Y1491891D03*
Y1487160D03*
Y1496622D03*
Y1507246D03*
Y1502515D03*
Y1511977D03*
X358850Y1511576D03*
Y1506845D03*
Y1516307D03*
X350188Y1563544D03*
Y1558813D03*
Y1568275D03*
Y1578898D03*
Y1574167D03*
Y1583629D03*
Y1594253D03*
Y1589522D03*
Y1604876D03*
Y1609607D03*
Y1598984D03*
Y1614338D03*
X352000Y1644980D03*
X376467Y94017D03*
X363050Y103037D03*
X363184Y116496D03*
Y109410D03*
Y130670D03*
Y123583D03*
X375982Y226141D03*
X378782D03*
X365365Y293796D03*
X367865D03*
X373379Y288190D03*
X375879Y285690D03*
X373379D03*
X375879Y288190D03*
X368057Y354184D03*
X364933Y374232D03*
X373264Y370010D03*
X366443Y472189D03*
X373504Y517954D03*
X375040Y932959D03*
X371424Y937185D03*
X367944Y946082D03*
X368657Y1146937D03*
X366133Y1162817D03*
X368661Y1182649D03*
X368917Y1195419D03*
X365029Y1214158D03*
X362735Y1211864D03*
X369839Y1218940D03*
X363245Y1345691D03*
Y1350683D03*
X368201Y1345691D03*
Y1350683D03*
X363245Y1362595D03*
X368201D03*
X363245Y1357603D03*
X368201D03*
X363245Y1369889D03*
Y1381801D03*
Y1374881D03*
X368201D03*
Y1381801D03*
Y1369889D03*
X363245Y1399079D03*
Y1394087D03*
Y1386793D03*
X368201D03*
Y1394087D03*
Y1399079D03*
X363245Y1405999D03*
Y1410991D03*
X368201D03*
Y1405999D03*
X372000Y1644980D03*
X393544Y76140D03*
Y84140D03*
Y80140D03*
X384467Y94017D03*
X388476D03*
X380467D03*
X390997Y117557D03*
X385587Y115401D03*
X380595D03*
X385587Y110445D03*
X380595D03*
X390997Y131731D03*
Y122513D03*
X385587Y129574D03*
X380595D03*
X385587Y124618D03*
X380595D03*
X390997Y136687D03*
X382158Y191941D03*
X388658Y184619D03*
X382025Y188727D03*
X390638Y206760D03*
X391852Y256535D03*
X383852D03*
X392882Y279208D03*
X378679Y285690D03*
Y288190D03*
X386905Y290755D03*
X382905D03*
X390905D03*
X392387Y337599D03*
Y342555D03*
X392444Y401949D03*
X393893Y413611D03*
X393833Y423944D03*
X393652Y482382D03*
X393746Y478382D03*
X388593Y664232D03*
X386350Y693559D03*
X391478Y690675D03*
X391614Y938651D03*
X381377Y1003008D03*
X381045Y1009444D03*
X391284Y1307238D03*
X394000Y1508100D03*
X382017Y1555700D03*
Y1547700D03*
Y1551700D03*
X392000Y1644980D03*
X408493Y117577D03*
X395989Y117557D03*
Y131731D03*
Y122513D03*
Y136687D03*
X399373Y180527D03*
X394690Y180572D03*
X403096Y192421D03*
X394690Y185165D03*
X399328Y185121D03*
X396986Y281307D03*
X409484Y314921D03*
X398951Y333711D03*
X397374Y344439D03*
X407493Y354142D03*
X394237Y370899D03*
X394944Y398949D03*
X399518Y402642D03*
X402018D03*
X396633Y423944D03*
X396693Y413611D03*
X399193D03*
X401693D03*
X401633Y423944D03*
X399133D03*
X409284Y741316D03*
X401121Y936686D03*
X409121Y939186D03*
X401121D03*
X409121Y936686D03*
X409231Y1123101D03*
X406105Y1139435D03*
X410131Y1129301D03*
X407631D03*
X409231Y1125801D03*
X406105Y1131935D03*
Y1134435D03*
Y1136935D03*
Y1141935D03*
Y1146935D03*
Y1144435D03*
X403263Y1152684D03*
X406319Y1204405D03*
Y1206905D03*
Y1211905D03*
Y1209405D03*
X397695Y1287071D03*
X399716Y1295198D03*
X408523Y1332967D03*
X404657D03*
X408937Y1351568D03*
X403981D03*
X401990Y1446807D03*
X399731Y1442755D03*
X397245Y1511640D03*
X404053Y1513673D03*
X397220Y1521207D03*
X409461Y1569560D03*
X405461D03*
X426147Y151540D03*
X414626Y180665D03*
Y172665D03*
X414658Y212864D03*
Y200864D03*
Y216864D03*
Y221864D03*
X422873Y309966D03*
X419955Y306966D03*
X414999D03*
X411984Y314921D03*
X421231Y338523D03*
Y331255D03*
Y345776D03*
X413432Y346797D03*
X416318Y367903D03*
X424479Y367859D03*
X418754Y468607D03*
X418226Y653288D03*
Y646480D03*
Y648980D03*
Y655788D03*
X425121Y936686D03*
Y939186D03*
X417121Y936686D03*
Y939186D03*
X417677Y1052215D03*
X425175Y1098767D03*
X417171Y1098887D03*
X419987Y1098518D03*
X419731Y1123101D03*
X417231D03*
X422631Y1125801D03*
X425131Y1129301D03*
X422631D03*
X420131D03*
X417631D03*
X415131D03*
X412631D03*
X420131Y1125801D03*
X417631D03*
X425131D03*
X422495Y1152713D03*
Y1155213D03*
X412095Y1152713D03*
Y1155213D03*
X422934Y1200821D03*
Y1198321D03*
X420619Y1204617D03*
Y1207117D03*
Y1209617D03*
Y1212117D03*
X411174Y1282776D03*
X418537Y1300197D03*
X423741Y1300115D03*
X413354Y1300197D03*
X425582Y1291743D03*
X423762Y1305298D03*
X413374D03*
X418558Y1310523D03*
X413395Y1310481D03*
X423721Y1310523D03*
X425283Y1373958D03*
X411147Y1474993D03*
X419818Y1474945D03*
X415241Y1492990D03*
X415095Y1502750D03*
X411353Y1519440D03*
X419467Y1519706D03*
X420279Y1525978D03*
X410626Y1525991D03*
X413461Y1569560D03*
X412000Y1644980D03*
X441727Y146461D03*
X440629Y152367D03*
X435703Y306966D03*
X430747D03*
X427829Y309966D03*
X428459Y331255D03*
X435793D03*
X428500Y345776D03*
X435793Y345738D03*
X430439Y358115D03*
X435702Y367813D03*
X430746D03*
X427782Y464026D03*
X438396Y511493D03*
X435834Y509580D03*
X431804Y536682D03*
Y539182D03*
X441832Y626193D03*
X433206Y1055498D03*
X430706D03*
Y1057998D03*
X433206D03*
Y1060498D03*
Y1062998D03*
X430706D03*
Y1060498D03*
X441359Y1123101D03*
X438233Y1139435D03*
X441359Y1125801D03*
X439759Y1129301D03*
X442259D03*
X429331Y1136935D03*
Y1134435D03*
Y1139435D03*
Y1131935D03*
X435733D03*
Y1134435D03*
Y1136935D03*
Y1139435D03*
X438233Y1131935D03*
Y1134435D03*
Y1136935D03*
X429331Y1141935D03*
X435733D03*
Y1146935D03*
Y1144435D03*
X438233Y1141935D03*
Y1146935D03*
Y1144435D03*
X437231Y1154902D03*
Y1152402D03*
X429331Y1146935D03*
Y1144435D03*
X433249Y1204405D03*
Y1209405D03*
Y1211905D03*
Y1206905D03*
X437991Y1286544D03*
X440896Y1311366D03*
X432485Y1325784D03*
X439624Y1345691D03*
Y1350683D03*
Y1357603D03*
Y1362595D03*
Y1381801D03*
Y1369889D03*
Y1374881D03*
X436002Y1382252D03*
X439624Y1386793D03*
X437675Y1550158D03*
X429784Y1548222D03*
X432000Y1644980D03*
X458454Y328963D03*
Y324007D03*
Y339755D03*
Y344711D03*
X453463Y370694D03*
X448092Y375770D03*
X443094Y491251D03*
X455104Y536582D03*
Y539082D03*
X447279Y633881D03*
X454815Y974622D03*
X448999Y994483D03*
X456210Y1004680D03*
X452319Y1000828D03*
X449731Y1000855D03*
X453710Y1018825D03*
X443091Y1022766D03*
Y1030266D03*
X450063Y1043140D03*
X449767Y1047047D03*
X457303Y1098767D03*
X452115Y1098518D03*
X446863Y1098428D03*
X449359Y1123101D03*
X451859D03*
X457259Y1129301D03*
X449759Y1125801D03*
X452259D03*
X444759Y1129301D03*
X447259D03*
X449759D03*
X452259D03*
X454759Y1125801D03*
X457259D03*
X454759Y1129301D03*
X443223Y1155213D03*
Y1152713D03*
X452623D03*
Y1155213D03*
X447549Y1204617D03*
X449864Y1198321D03*
Y1200821D03*
X447549Y1209617D03*
Y1207117D03*
Y1212117D03*
X454120Y1269498D03*
X456213Y1286776D03*
X451304Y1293045D03*
X456820Y1345691D03*
X451864D03*
Y1350683D03*
X456820D03*
X444580Y1345691D03*
Y1350683D03*
X456820Y1362595D03*
Y1357603D03*
X451864Y1362595D03*
Y1357603D03*
X444580D03*
Y1362595D03*
X456820Y1374881D03*
X451864D03*
X444580Y1369889D03*
X456820Y1369795D03*
X451864D03*
X444580Y1374881D03*
Y1381801D03*
X456820D03*
X451864D03*
X456820Y1399079D03*
X451864Y1393993D03*
Y1399079D03*
X456820Y1393993D03*
Y1386793D03*
X451864D03*
X444580D03*
X456820Y1405999D03*
X451864D03*
Y1410991D03*
X456820D03*
X454125Y1461182D03*
Y1465913D03*
Y1471805D03*
Y1481267D03*
Y1476536D03*
Y1491890D03*
Y1487159D03*
Y1496621D03*
Y1511976D03*
Y1507245D03*
Y1502514D03*
Y1558813D03*
Y1578898D03*
Y1568275D03*
Y1563544D03*
Y1574167D03*
Y1583629D03*
Y1589522D03*
Y1594253D03*
Y1609607D03*
Y1598984D03*
Y1604876D03*
Y1614338D03*
X452000Y1644980D03*
X464738Y110784D03*
X462089Y113394D03*
X472332Y133298D03*
X464332D03*
X466479Y134579D03*
X464054Y252371D03*
X461454Y336837D03*
Y331881D03*
Y347629D03*
Y352585D03*
X466375Y366365D03*
X470389Y389553D03*
X468558Y491669D03*
Y503669D03*
Y507669D03*
Y512669D03*
X462242Y809792D03*
X475032Y843252D03*
X474678Y857919D03*
X463134Y859203D03*
X460455Y867050D03*
X475046Y885952D03*
X467494Y924532D03*
X462427Y1030218D03*
X460277Y1090268D03*
Y1093068D03*
X474818Y1123101D03*
X469192Y1131935D03*
X474818Y1125801D03*
X473218Y1129301D03*
X461459Y1136935D03*
Y1134435D03*
Y1139435D03*
Y1131935D03*
X471692Y1139435D03*
Y1136935D03*
Y1134435D03*
Y1131935D03*
X469192Y1139435D03*
Y1136935D03*
Y1134435D03*
X471692Y1146935D03*
Y1141935D03*
X469192Y1144435D03*
Y1146935D03*
Y1141935D03*
X471692Y1144435D03*
X461459D03*
X462687Y1152684D03*
X468850D03*
X461459Y1141935D03*
Y1146935D03*
X463216Y1254164D03*
Y1250760D03*
Y1244055D03*
X461613Y1286776D03*
X469060Y1345691D03*
Y1350683D03*
X464104Y1345691D03*
Y1350683D03*
X469060Y1357603D03*
Y1362595D03*
X464104D03*
Y1357603D03*
Y1381801D03*
X469060D03*
X464104Y1369889D03*
X469060D03*
X464104Y1374881D03*
X469060D03*
Y1386793D03*
X464104D03*
X469060Y1399079D03*
X464104Y1394087D03*
X469060D03*
X464104Y1399079D03*
Y1405999D03*
X469060D03*
X464104Y1410991D03*
X469060D03*
X471448Y1461182D03*
X462786Y1460782D03*
X471448Y1465913D03*
X462786Y1465513D03*
X471448Y1481267D03*
X462786Y1480867D03*
X471448Y1471805D03*
Y1476536D03*
X462786Y1476136D03*
Y1470244D03*
X471448Y1496621D03*
X462786Y1496221D03*
X471448Y1491890D03*
X462786Y1491490D03*
Y1485598D03*
X471448Y1487159D03*
Y1511976D03*
Y1502514D03*
Y1507245D03*
X462786Y1511576D03*
Y1506845D03*
Y1500952D03*
Y1516307D03*
Y1563144D03*
X471448Y1558813D03*
X462786Y1578498D03*
X471448Y1574167D03*
Y1568275D03*
Y1563544D03*
X462786Y1567875D03*
Y1572606D03*
X471448Y1578898D03*
Y1594253D03*
X462786Y1593853D03*
X471448Y1589522D03*
Y1583629D03*
X462786Y1583229D03*
Y1587960D03*
X471448Y1598984D03*
X462786Y1609207D03*
Y1598584D03*
Y1603315D03*
X471448Y1609607D03*
Y1604876D03*
Y1614338D03*
X462786Y1613938D03*
Y1618669D03*
X472000Y1644980D03*
X480324Y109172D03*
X477324D03*
X479331Y106495D03*
X483075Y116497D03*
X487875D03*
X490375Y109410D03*
Y116497D03*
X483075Y130670D03*
X487875Y123584D03*
Y130670D03*
X490375Y123583D03*
Y130670D03*
X483075Y123584D03*
X479065Y146012D03*
X480971Y141228D03*
X483075Y137757D03*
X487875D03*
X483859Y150847D03*
X485827Y247292D03*
X478536Y253198D03*
X483242Y366481D03*
X483584Y375840D03*
X483736Y371266D03*
X483541Y380306D03*
X481724Y391589D03*
Y387089D03*
X488438Y425464D03*
X482532Y418464D03*
X482484Y444517D03*
X486738Y581222D03*
X489538D03*
Y591215D03*
X486738D03*
X491340Y611091D03*
X485005Y659771D03*
X491324Y667293D03*
X485303Y681841D03*
X486246Y804497D03*
X485824Y819787D03*
X481593Y826387D03*
X491453Y834546D03*
X491527Y843206D03*
X488469Y857013D03*
X481943Y924633D03*
X488388Y938903D03*
X483636Y952152D03*
X490143Y989521D03*
X476148Y1057998D03*
Y1055498D03*
X478648D03*
Y1057998D03*
X476148Y1060498D03*
Y1062998D03*
X478648D03*
Y1060498D03*
X490762Y1098767D03*
X485574Y1098518D03*
X480322Y1098428D03*
X485318Y1123101D03*
X482818D03*
X490718Y1129301D03*
X483218Y1125801D03*
X485718D03*
X475718Y1129301D03*
X478218D03*
X480718D03*
X483218D03*
X485718D03*
X488218Y1125801D03*
X490718D03*
X488218Y1129301D03*
X477682Y1152713D03*
Y1155213D03*
X488082D03*
Y1152713D03*
X479521Y1204405D03*
Y1206905D03*
Y1211905D03*
Y1209405D03*
X488584Y1345691D03*
Y1350683D03*
X481300Y1345691D03*
X476344D03*
X481300Y1350683D03*
X476344D03*
X488584Y1357603D03*
Y1362595D03*
X481300D03*
Y1357603D03*
X476344Y1362595D03*
Y1357603D03*
X488584Y1381801D03*
X481300D03*
X488584Y1374881D03*
Y1369889D03*
X481300D03*
Y1374881D03*
X476344Y1381801D03*
Y1369889D03*
Y1374881D03*
X488584Y1386793D03*
X481300D03*
Y1399079D03*
X476344Y1394087D03*
Y1399079D03*
X488584Y1394087D03*
X481300D03*
X488584Y1399079D03*
X476344Y1386793D03*
Y1410991D03*
X481300Y1405999D03*
X476344D03*
X488584D03*
Y1410991D03*
X481300D03*
X480109Y1460782D03*
Y1465513D03*
X488771Y1465913D03*
Y1461182D03*
X480109Y1476136D03*
Y1470244D03*
X488771Y1471805D03*
Y1476536D03*
Y1481267D03*
X480109Y1480867D03*
Y1496221D03*
X488771Y1487159D03*
Y1491890D03*
X480109Y1491490D03*
Y1485598D03*
X488771Y1496621D03*
Y1511976D03*
X480109Y1511576D03*
Y1506845D03*
Y1500952D03*
X488771Y1502514D03*
Y1507245D03*
X480109Y1516307D03*
X488771Y1558813D03*
X480109Y1563144D03*
X488771Y1578898D03*
X480109Y1578498D03*
X488771Y1574167D03*
Y1568275D03*
Y1563544D03*
X480109Y1567875D03*
Y1572606D03*
X488771Y1589522D03*
Y1583629D03*
X480109Y1583229D03*
Y1587960D03*
X488771Y1594253D03*
X480109Y1593853D03*
X488771Y1609607D03*
Y1604876D03*
Y1598984D03*
X480109Y1609207D03*
Y1598584D03*
Y1603315D03*
X488771Y1614338D03*
X480109Y1613938D03*
Y1618669D03*
X503537Y77784D03*
Y75184D03*
Y80384D03*
Y82984D03*
X506091Y92849D03*
X503537Y85584D03*
X495075Y116496D03*
Y102323D03*
Y109410D03*
Y130670D03*
Y123583D03*
Y137756D03*
X497424Y354559D03*
X492317Y376252D03*
X503682Y455466D03*
X497776Y448466D03*
X493929Y555194D03*
X496729D03*
X493929Y563194D03*
X496729D03*
X493929Y571194D03*
X496729D03*
X492338Y581222D03*
Y591215D03*
X494632Y654622D03*
X501618Y698355D03*
X499012Y699819D03*
X503311Y715652D03*
X500705Y705524D03*
X507546Y738539D03*
X505673Y767961D03*
X500717D03*
X504341Y812040D03*
X491655Y829173D03*
X506246Y824689D03*
X492799Y846488D03*
X503741Y846830D03*
X497467Y833027D03*
X499640Y861538D03*
X499595Y963963D03*
X493050Y976078D03*
X506566Y1000766D03*
Y1004766D03*
Y1016266D03*
Y1030766D03*
X505981Y1052487D03*
X506946Y1123101D03*
Y1125801D03*
X505346Y1129301D03*
X507846D03*
X503820Y1139435D03*
Y1136935D03*
Y1134435D03*
Y1131935D03*
X501320Y1139435D03*
Y1136935D03*
Y1134435D03*
Y1131935D03*
X494918Y1136935D03*
Y1134435D03*
Y1139435D03*
Y1131935D03*
X503820Y1144435D03*
Y1146935D03*
Y1141935D03*
X501320Y1144435D03*
Y1146935D03*
Y1141935D03*
X494918Y1146935D03*
Y1144435D03*
Y1141935D03*
X502562Y1152713D03*
Y1155213D03*
X506451Y1204405D03*
X493821Y1204617D03*
X496136Y1200821D03*
Y1198321D03*
X506451Y1206905D03*
Y1211905D03*
Y1209405D03*
X493821Y1207117D03*
Y1209617D03*
Y1212117D03*
X500824Y1350683D03*
Y1345691D03*
X505780Y1350683D03*
Y1345691D03*
X493540D03*
Y1350683D03*
X505780Y1362595D03*
Y1357603D03*
X500824Y1362595D03*
Y1357603D03*
X493540Y1362595D03*
Y1357603D03*
Y1381801D03*
Y1374881D03*
Y1369889D03*
X505780Y1381801D03*
Y1374881D03*
Y1369889D03*
X500824D03*
Y1381801D03*
Y1374881D03*
Y1394087D03*
X505780Y1399079D03*
X500824D03*
X505780Y1394087D03*
X493540Y1386793D03*
Y1394087D03*
Y1399079D03*
X505780Y1386793D03*
X500824D03*
X505780Y1410991D03*
X500824D03*
X505780Y1405999D03*
X500824D03*
X493540D03*
Y1410991D03*
X497432Y1465513D03*
X506093Y1465913D03*
X497432Y1460782D03*
X506093Y1461182D03*
X497432Y1480867D03*
X506093Y1481267D03*
X497432Y1476136D03*
Y1470244D03*
X506093Y1471805D03*
Y1476536D03*
X497432Y1496221D03*
Y1491490D03*
Y1485598D03*
X506093Y1487159D03*
Y1491890D03*
Y1496621D03*
Y1511976D03*
X497432Y1506845D03*
Y1500952D03*
X506093Y1502514D03*
Y1507245D03*
X497432Y1511576D03*
Y1516307D03*
Y1563144D03*
X506093Y1558813D03*
X497432Y1578498D03*
X506093Y1578898D03*
X497432Y1567875D03*
Y1572606D03*
X506093Y1574167D03*
Y1568275D03*
Y1563544D03*
X497432Y1587960D03*
X506093Y1589522D03*
Y1583629D03*
X497432Y1593853D03*
X506093Y1594253D03*
X497432Y1583229D03*
X506093Y1604876D03*
Y1598984D03*
X497432Y1609207D03*
X506093Y1609607D03*
X497432Y1598584D03*
Y1603315D03*
Y1613938D03*
Y1618669D03*
X506093Y1614338D03*
X492000Y1644980D03*
X513051Y103037D03*
X513185Y116496D03*
Y109410D03*
Y130670D03*
Y123583D03*
X509251Y137756D03*
X517866Y293796D03*
X515366D03*
X523380Y285690D03*
Y288190D03*
X511342Y311124D03*
X520845Y434508D03*
X516845D03*
X512845D03*
X514608Y445874D03*
X510022Y446352D03*
X523705Y444269D03*
X523583Y447201D03*
X521636Y504699D03*
X516636D03*
X519136D03*
X516338Y516979D03*
X521338D03*
X518838D03*
X512404Y629362D03*
X510215Y627948D03*
X511990Y686365D03*
X518001Y694940D03*
X522410Y694881D03*
X518067Y699378D03*
X518530Y703584D03*
X522628Y703884D03*
X508237Y723585D03*
X512502Y738539D03*
X516953Y738575D03*
X521909D03*
X520159Y758832D03*
X509063Y782867D03*
X517194Y773232D03*
X522316Y793574D03*
X509316Y793224D03*
X508130Y787488D03*
X521178Y814001D03*
X521565Y820931D03*
X520720Y846133D03*
X517832Y834558D03*
X508049Y877789D03*
X523272Y880067D03*
X509428Y888390D03*
X521115Y897500D03*
X511025Y911443D03*
X509673Y900295D03*
X516256Y939157D03*
X514886Y952189D03*
X519792Y1031271D03*
X517702Y1098518D03*
X512450Y1098428D03*
X522890Y1098767D03*
X514946Y1123101D03*
X517446D03*
X522846Y1129301D03*
X515346Y1125801D03*
X517846D03*
X510346Y1129301D03*
X512846D03*
X515346D03*
X517846D03*
X520346Y1125801D03*
X522846D03*
X520346Y1129301D03*
X518210Y1155213D03*
Y1152713D03*
X508810D03*
Y1155213D03*
X520751Y1204617D03*
X523066Y1200821D03*
Y1198321D03*
X520751Y1207117D03*
Y1209617D03*
Y1212117D03*
X513064Y1345691D03*
X518020Y1350683D03*
X513064D03*
X518020Y1345691D03*
Y1357603D03*
X513064Y1362595D03*
Y1357603D03*
X518020Y1362595D03*
X513064Y1369889D03*
Y1381801D03*
Y1374881D03*
X518020Y1369889D03*
Y1381801D03*
Y1374881D03*
Y1394087D03*
Y1399079D03*
X513064Y1394087D03*
Y1399079D03*
Y1386793D03*
X518020D03*
Y1405999D03*
Y1410991D03*
X513064D03*
Y1405999D03*
X514755Y1460782D03*
Y1465513D03*
Y1480867D03*
Y1476136D03*
Y1470244D03*
Y1491490D03*
Y1485598D03*
Y1496221D03*
Y1511576D03*
Y1506845D03*
Y1500952D03*
Y1516307D03*
Y1563144D03*
Y1567875D03*
Y1572606D03*
Y1578498D03*
Y1593853D03*
Y1583229D03*
Y1587960D03*
Y1603315D03*
Y1609207D03*
Y1598584D03*
Y1613938D03*
Y1618669D03*
X512000Y1644980D03*
X526468Y94017D03*
X534468D03*
X538477D03*
X530468D03*
X530596Y115401D03*
X535588Y110445D03*
Y115401D03*
X530596Y110445D03*
Y124618D03*
Y129574D03*
X535588Y124618D03*
Y129574D03*
X528509Y151540D03*
X538659Y184619D03*
X532159Y191941D03*
X532026Y188727D03*
X528783Y226141D03*
X525983D03*
X533853Y256535D03*
X525880Y285690D03*
X528680D03*
X525880Y288190D03*
X528680D03*
X532906Y290755D03*
X536906D03*
X540906D03*
X524206Y354119D03*
X533027Y351836D03*
X530215Y364422D03*
X535142Y397552D03*
X532936Y519544D03*
X527936D03*
X525436D03*
X530436D03*
X538826Y633450D03*
X526756Y636005D03*
Y633205D03*
X538826Y636250D03*
Y639050D03*
X526756Y638805D03*
X524653Y643595D03*
X534940Y684489D03*
X539111Y681459D03*
X526956Y694959D03*
X526951Y699443D03*
X535387Y712617D03*
X526933Y703820D03*
X532628Y720776D03*
X526276Y721339D03*
X539763Y734097D03*
X534807D03*
X531763Y739097D03*
X526807D03*
X532450Y767474D03*
X532278Y762736D03*
X531501Y792331D03*
X531260Y794934D03*
X531666Y815724D03*
X531313Y822693D03*
X527733Y847026D03*
X527346Y911458D03*
X528674Y964851D03*
X527046Y1131935D03*
Y1139435D03*
Y1134435D03*
Y1136935D03*
X528274Y1152684D03*
X527046Y1146935D03*
Y1144435D03*
Y1141935D03*
X525304Y1345691D03*
X530260D03*
X537544Y1350683D03*
X525304D03*
X530260D03*
X537544Y1345691D03*
Y1357603D03*
X525304Y1362595D03*
X530260D03*
X525304Y1357603D03*
X530260D03*
X537544Y1362595D03*
Y1374881D03*
X525304Y1369889D03*
Y1381801D03*
Y1374881D03*
X530260Y1369889D03*
Y1381801D03*
Y1374881D03*
X537544Y1369889D03*
Y1381801D03*
Y1399079D03*
Y1394087D03*
X530260D03*
Y1399079D03*
X525304Y1394087D03*
Y1399079D03*
X537544Y1386793D03*
X525304D03*
X530260D03*
X537544Y1410991D03*
Y1405999D03*
X530260D03*
X525304D03*
X530260Y1410991D03*
X525304D03*
X532000Y1644980D03*
X543545Y84140D03*
Y80140D03*
Y76140D03*
X540998Y117557D03*
X545990D03*
Y122513D03*
Y131731D03*
X540998Y122513D03*
Y131731D03*
X544089Y146461D03*
X545990Y136687D03*
X540998D03*
X542991Y152367D03*
X549374Y180527D03*
X544691Y180572D03*
X553097Y192421D03*
X549329Y185121D03*
X544691Y185165D03*
X540639Y206760D03*
X541853Y256535D03*
X542883Y279208D03*
X546987Y281307D03*
X541644Y389047D03*
X553731Y388487D03*
X541706Y381723D03*
X552905Y430829D03*
X550274Y658676D03*
X556574Y684031D03*
Y700031D03*
Y688987D03*
Y716031D03*
Y704987D03*
Y720987D03*
X552384Y762892D03*
X552188Y766577D03*
X553871Y811298D03*
X545741Y804149D03*
X548464Y823156D03*
X540807Y816556D03*
X541129Y828335D03*
Y838865D03*
X545981Y846389D03*
X549241Y841388D03*
X545237Y850319D03*
X548521Y877859D03*
Y874859D03*
X545144Y909025D03*
X544793Y899220D03*
X548215Y1006560D03*
X552923Y997860D03*
X541766Y1018368D03*
X557681Y1035088D03*
X554740Y1345597D03*
X542500Y1345691D03*
X549784Y1345597D03*
X542500Y1350683D03*
X549784D03*
X554740D03*
Y1362595D03*
Y1357603D03*
X542500Y1362595D03*
X549784D03*
X542500Y1357603D03*
X549784D03*
X554740Y1381801D03*
Y1374881D03*
X542500D03*
X549784Y1369889D03*
Y1381801D03*
Y1374881D03*
X542500Y1369889D03*
Y1381801D03*
X554740Y1369889D03*
Y1399079D03*
Y1393993D03*
X542500Y1399079D03*
X549784Y1393993D03*
Y1399079D03*
X542500Y1394087D03*
X554740Y1386793D03*
X549784D03*
X542500D03*
X554740Y1410991D03*
Y1405999D03*
X542500Y1410991D03*
X549784D03*
X542500Y1405999D03*
X549784D03*
X552000Y1644980D03*
X566287Y60922D03*
X561123Y55513D03*
X563224Y96813D03*
X558316Y91951D03*
X556920Y117261D03*
X567100Y110784D03*
X564451Y113394D03*
X567290Y130898D03*
X568841Y134579D03*
X564627Y180665D03*
Y172665D03*
X569969Y195176D03*
X564659Y212864D03*
Y200864D03*
X569829Y203393D03*
X564659Y221864D03*
Y216864D03*
X566416Y252371D03*
X570634Y375453D03*
X559074Y696987D03*
Y692031D03*
Y712987D03*
Y708031D03*
X561886Y728138D03*
X559625Y739609D03*
X557813Y747814D03*
X570578Y749800D03*
X570695Y767052D03*
X564276Y776701D03*
X558241Y796389D03*
X569186Y787332D03*
X561401Y811242D03*
X567316Y806224D03*
X561061Y803606D03*
X563099Y829943D03*
X567316Y827724D03*
X559741Y822149D03*
X572171Y842346D03*
X559196Y846296D03*
X569577Y886913D03*
X560814Y901022D03*
X564923Y997860D03*
X560923D03*
X568923D03*
X556923D03*
X571857Y1009354D03*
X565451Y1035102D03*
X569520Y1102091D03*
X560211D03*
X566020D03*
X569520Y1114691D03*
X566020D03*
X560211D03*
X569520Y1139891D03*
X566020D03*
X560211D03*
X566020Y1127291D03*
X560211D03*
X569520D03*
X566020Y1152491D03*
X560211D03*
X569520D03*
X566020Y1165091D03*
X560211D03*
X569520D03*
X560211Y1177691D03*
X566020D03*
X569520D03*
X566502Y1202103D03*
X569882Y1223749D03*
X562024Y1350683D03*
Y1345691D03*
X566980D03*
Y1350683D03*
X562024Y1357603D03*
X566980D03*
Y1362595D03*
X562024D03*
Y1369889D03*
Y1381801D03*
Y1374881D03*
X566980Y1369889D03*
Y1381801D03*
Y1374881D03*
Y1399079D03*
Y1394087D03*
X562024Y1399079D03*
Y1394087D03*
X566980Y1386793D03*
X562024D03*
X566980Y1410991D03*
X562024D03*
X566980Y1405999D03*
X562024D03*
X565600Y1530800D03*
X569349Y1541947D03*
X560635Y1543531D03*
X566800Y1541800D03*
X582686Y109172D03*
X579686D03*
X581693Y106495D03*
X585437Y116497D03*
X574694Y133298D03*
X585437Y123584D03*
Y130670D03*
X581427Y146012D03*
X583333Y141228D03*
X585437Y137757D03*
X586221Y150847D03*
X588189Y247292D03*
X580898Y253198D03*
X581487Y336676D03*
X573805Y728301D03*
X574620Y772724D03*
X584624Y781850D03*
X581001Y814123D03*
X579758Y817753D03*
X579827Y884000D03*
X579251Y903364D03*
X582706Y908959D03*
X580923Y997860D03*
X576923D03*
X588923D03*
X577666Y1009354D03*
X581166D03*
X572923Y997860D03*
X584923D03*
X581166Y1021954D03*
X577666D03*
X578298Y1215195D03*
X584024Y1209607D03*
X587689Y1505724D03*
X583661Y1529142D03*
X573784Y1530646D03*
X575332Y1523740D03*
X583800Y1518000D03*
X583740Y1520640D03*
X587858Y1517942D03*
X577645Y1540982D03*
X580700Y1544100D03*
X592737Y109410D03*
X590237Y116497D03*
X592737D03*
X597437Y102323D03*
Y109410D03*
Y116496D03*
Y123583D03*
Y130670D03*
X592737Y123583D03*
X590237Y123584D03*
Y130670D03*
X592737D03*
X597437Y137756D03*
X590237Y137757D03*
X590178Y309760D03*
X593690Y450750D03*
X597872Y512743D03*
X592880D03*
X597789Y536382D03*
X602756Y597580D03*
X604979Y599588D03*
X604241Y589556D03*
X604180Y592354D03*
X602695Y594668D03*
X604982Y596095D03*
X605011Y615600D03*
X604979Y607588D03*
X592238Y880612D03*
X597129Y913386D03*
X602385Y940920D03*
X596923Y997860D03*
X592923D03*
X604923D03*
X600923D03*
X602603Y1012354D03*
Y1024954D03*
X604405Y1034870D03*
X591898Y1035011D03*
X590957Y1105091D03*
Y1117691D03*
Y1130291D03*
Y1155491D03*
Y1142891D03*
Y1168091D03*
Y1180691D03*
X592978Y1514812D03*
X591858Y1523542D03*
X598800Y1546400D03*
X605899Y80384D03*
Y82984D03*
Y77784D03*
Y75184D03*
X608453Y92849D03*
X605899Y85584D03*
X615413Y103037D03*
X615547Y116496D03*
Y109410D03*
Y130670D03*
Y123583D03*
X612138Y137756D03*
X617728Y293796D03*
X620228D03*
X614461Y555234D03*
X614176Y562003D03*
X609472Y634946D03*
X612489Y941024D03*
X616923Y997860D03*
X608923D03*
X620151Y1040363D03*
X619086Y1056453D03*
X620715Y1046785D03*
X612000Y1644980D03*
X636830Y94017D03*
X628830D03*
X632830D03*
X632958Y110445D03*
Y115401D03*
Y124618D03*
Y129574D03*
X630871Y151540D03*
X634521Y191941D03*
X634388Y188727D03*
X631145Y226141D03*
X628345D03*
X636215Y256535D03*
X631042Y288190D03*
Y285690D03*
X625742Y288190D03*
X628242Y285690D03*
X625742D03*
X628242Y288190D03*
X635268Y290755D03*
X634455Y389154D03*
Y396240D03*
Y403327D03*
Y410413D03*
Y417500D03*
Y424587D03*
Y431673D03*
Y438760D03*
Y445847D03*
Y467539D03*
Y474626D03*
Y488799D03*
Y481713D03*
Y495886D03*
Y511673D03*
Y518760D03*
Y525847D03*
Y532933D03*
Y540020D03*
Y547106D03*
X633736Y602197D03*
X634200Y595108D03*
X622270Y864781D03*
X630466Y1394087D03*
X625510Y1399079D03*
Y1394087D03*
X630466Y1399079D03*
X625510Y1405999D03*
X630466D03*
X625510Y1410991D03*
X630466D03*
X636015Y1460782D03*
X627354Y1461182D03*
X636015Y1465513D03*
X627354Y1465913D03*
Y1456451D03*
X636015Y1476136D03*
X627354Y1476536D03*
X636015Y1480867D03*
X627354Y1481267D03*
Y1471805D03*
X636015Y1470244D03*
X627354Y1487159D03*
X636015Y1485598D03*
Y1491490D03*
X627354Y1491890D03*
X636015Y1496221D03*
X627354Y1496621D03*
Y1507245D03*
Y1511976D03*
X636015Y1511576D03*
X627354Y1502514D03*
X636015Y1500952D03*
Y1506845D03*
Y1516307D03*
X627354Y1558813D03*
X636015Y1563144D03*
X627354Y1563544D03*
X636015Y1567875D03*
X627354Y1568275D03*
Y1574167D03*
X636015Y1572606D03*
Y1578498D03*
X627354Y1578898D03*
X636015Y1593853D03*
X627354Y1594253D03*
X636015Y1583229D03*
X627354Y1583629D03*
Y1589522D03*
X636015Y1587960D03*
X627354Y1604876D03*
X636015Y1603315D03*
Y1598584D03*
X627354Y1598984D03*
X636015Y1609207D03*
X627354Y1609607D03*
X636015Y1618669D03*
Y1613938D03*
X627354Y1614338D03*
X632000Y1644980D03*
X645907Y76140D03*
Y84140D03*
Y80140D03*
X640839Y94017D03*
X643360Y117557D03*
X637950Y110445D03*
Y115401D03*
X648352Y117557D03*
X643360Y122513D03*
Y131731D03*
X637950Y124618D03*
Y129574D03*
X648352Y122513D03*
Y131731D03*
X646451Y146461D03*
X643360Y136687D03*
X648352D03*
X645353Y152367D03*
X647053Y180572D03*
X651736Y180527D03*
X651691Y185121D03*
X647053Y185165D03*
X641021Y184619D03*
X643001Y206760D03*
X644215Y256535D03*
X645245Y279208D03*
X649349Y281307D03*
X639268Y290755D03*
X643268D03*
X649074Y389154D03*
X647604Y396240D03*
X652381Y414823D03*
X651689Y422864D03*
X651759Y429832D03*
X651364Y436447D03*
X653399Y447953D03*
X652566Y467539D03*
X651308Y472772D03*
X652042Y487711D03*
X652155Y479104D03*
X652566Y495886D03*
X647915Y516841D03*
X651166Y510565D03*
X642862Y550123D03*
X642740Y552872D03*
X644494Y572334D03*
X642185Y562443D03*
X643953Y560675D03*
X642726Y574102D03*
X647361Y653161D03*
X648352Y645467D03*
X650958Y677843D03*
X649990Y1350683D03*
Y1345691D03*
Y1357603D03*
Y1362595D03*
Y1381801D03*
X642706Y1374881D03*
Y1381801D03*
Y1369889D03*
X649990Y1374881D03*
Y1369889D03*
X637750Y1374881D03*
Y1381801D03*
Y1369889D03*
X649990Y1399079D03*
Y1394087D03*
X642706Y1386793D03*
X649990D03*
X637750Y1399079D03*
X642706Y1394087D03*
X637750D03*
X642706Y1399079D03*
X637750Y1386793D03*
X649990Y1405999D03*
Y1410991D03*
X637750D03*
X642706D03*
Y1405999D03*
X637750D03*
X653338Y1465513D03*
X644677Y1461182D03*
Y1456451D03*
Y1465913D03*
X653338Y1460782D03*
X644677Y1476536D03*
Y1471805D03*
X653338Y1480867D03*
Y1470244D03*
Y1476136D03*
X644677Y1481267D03*
X653338Y1491490D03*
X644677Y1496621D03*
Y1491890D03*
Y1487159D03*
X653338Y1496221D03*
Y1485598D03*
X644677Y1511976D03*
X653338Y1511576D03*
Y1500952D03*
Y1506845D03*
X644677Y1502514D03*
Y1507245D03*
X653338Y1516307D03*
X644677Y1558813D03*
X653338Y1563144D03*
X644677Y1563544D03*
X653338Y1572606D03*
Y1578498D03*
X644677Y1578898D03*
Y1574167D03*
X653338Y1567875D03*
X644677Y1568275D03*
X653338Y1587960D03*
Y1593853D03*
X644677Y1594253D03*
Y1589522D03*
X653338Y1583229D03*
X644677Y1583629D03*
X653338Y1609207D03*
X644677Y1598984D03*
Y1604876D03*
Y1609607D03*
X653338Y1603315D03*
Y1598584D03*
Y1613938D03*
X644677Y1614338D03*
X653338Y1618669D03*
X652000Y1644980D03*
X668649Y60922D03*
X666209Y57297D03*
X665423Y96853D03*
X660678Y91951D03*
X659282Y117261D03*
X666813Y113394D03*
X669462Y110784D03*
X669056Y133298D03*
X666989Y172665D03*
Y180665D03*
X655459Y192421D03*
X667021Y200864D03*
Y212864D03*
Y221864D03*
Y216864D03*
X668778Y252371D03*
X667666Y389153D03*
X665166Y396240D03*
X667666D03*
X665166Y403327D03*
X667666Y403326D03*
X665166Y410413D03*
X667666D03*
Y417499D03*
X665166Y424586D03*
X667666D03*
X665166Y417500D03*
Y431673D03*
Y438760D03*
X667666D03*
Y431673D03*
X665166Y445847D03*
X667666Y467539D03*
X665166Y474626D03*
X667666D03*
X665166Y488799D03*
X667666D03*
Y481712D03*
X665166D03*
Y495886D03*
X667666Y518760D03*
X665166D03*
X667666Y511673D03*
Y532933D03*
X665166D03*
Y540020D03*
Y525846D03*
X667666D03*
X669546Y560500D03*
X655752Y668885D03*
X661776Y662981D03*
X656157Y691851D03*
X661768Y705043D03*
X654946Y1350683D03*
X662230D03*
X667186D03*
Y1345691D03*
X654946D03*
X662230D03*
X654946Y1357603D03*
Y1362595D03*
X662230Y1357603D03*
Y1362595D03*
X667186Y1357603D03*
Y1362595D03*
X662230Y1369889D03*
X667186Y1374881D03*
Y1381801D03*
Y1369889D03*
X662230Y1374881D03*
Y1381801D03*
X654946D03*
Y1369889D03*
Y1374881D03*
X667186Y1399079D03*
Y1393993D03*
X662230D03*
Y1399079D03*
X655046D03*
Y1394087D03*
X667186Y1386793D03*
X662230D03*
X654946D03*
X667186Y1410991D03*
Y1405999D03*
X662230D03*
Y1410991D03*
X655046Y1405999D03*
Y1410991D03*
X662000Y1456451D03*
Y1465913D03*
Y1461182D03*
Y1481267D03*
Y1476536D03*
Y1471805D03*
Y1496621D03*
Y1491890D03*
Y1487159D03*
Y1511976D03*
Y1502514D03*
Y1507245D03*
Y1563544D03*
Y1558813D03*
Y1568275D03*
Y1578898D03*
Y1574167D03*
Y1594253D03*
Y1589522D03*
Y1583629D03*
Y1598984D03*
Y1604876D03*
Y1609607D03*
Y1614338D03*
X682048Y109172D03*
X685048D03*
X684055Y106495D03*
X677056Y133298D03*
X671203Y134579D03*
X683789Y146012D03*
X685695Y141228D03*
X677331Y195176D03*
X676950Y198883D03*
X683260Y253198D03*
X686012Y339795D03*
X672466Y389153D03*
Y410413D03*
Y396240D03*
Y403326D03*
Y424586D03*
Y417499D03*
Y438760D03*
Y431673D03*
Y467539D03*
Y474626D03*
Y488799D03*
Y481712D03*
Y518760D03*
Y511673D03*
Y525846D03*
Y532933D03*
X681586Y555000D03*
X681011Y543925D03*
X679426Y1350683D03*
X674470Y1345691D03*
X679426D03*
X674470Y1350683D03*
Y1357603D03*
Y1362595D03*
X679426Y1357603D03*
Y1362595D03*
Y1374881D03*
X674470D03*
Y1381801D03*
X679426D03*
Y1369889D03*
X674470D03*
X679426Y1399079D03*
X674470Y1394087D03*
X679426D03*
X674470Y1399079D03*
Y1386793D03*
X679426D03*
X674470Y1405999D03*
X679426D03*
X674470Y1410991D03*
X679426D03*
X679322Y1461182D03*
Y1456451D03*
Y1465913D03*
X670661Y1460782D03*
Y1465513D03*
Y1470244D03*
Y1476136D03*
X679322Y1481267D03*
Y1476536D03*
Y1471805D03*
X670661Y1480867D03*
X679322Y1487159D03*
X670661Y1496221D03*
Y1485598D03*
Y1491490D03*
X679322Y1496621D03*
Y1491890D03*
X670661Y1500952D03*
Y1506845D03*
X679322Y1511976D03*
Y1502514D03*
Y1507245D03*
X670661Y1511576D03*
Y1516307D03*
X679322Y1558813D03*
X670661Y1563144D03*
X679322Y1563544D03*
Y1578898D03*
Y1574167D03*
Y1568275D03*
X670661Y1572606D03*
Y1578498D03*
Y1567875D03*
X679322Y1583629D03*
X670661Y1587960D03*
Y1593853D03*
Y1583229D03*
X679322Y1594253D03*
Y1589522D03*
Y1604876D03*
Y1609607D03*
X670661Y1603315D03*
Y1598584D03*
Y1609207D03*
X679322Y1598984D03*
Y1614338D03*
X670661Y1618669D03*
Y1613938D03*
X672000Y1644980D03*
X695099Y109410D03*
X687799Y116497D03*
X692599D03*
X695099D03*
X699799Y116496D03*
Y109410D03*
Y102323D03*
X687799Y123584D03*
X695099Y123583D03*
X692599Y123584D03*
X687799Y130670D03*
X692599D03*
X695099D03*
X699799Y123583D03*
Y130670D03*
X687799Y137757D03*
X692599D03*
X699799Y137756D03*
X688583Y150847D03*
X690551Y247292D03*
X700164Y636842D03*
X698936Y678462D03*
X702691Y766471D03*
Y753471D03*
X702677Y771159D03*
Y784659D03*
X698950Y1350683D03*
Y1345597D03*
X686710Y1350683D03*
X691666D03*
X686710Y1345691D03*
X691666D03*
X698950Y1362595D03*
Y1357603D03*
X686710D03*
Y1362595D03*
X691666Y1357603D03*
Y1362595D03*
X698950Y1374881D03*
Y1381801D03*
Y1369889D03*
X691666D03*
Y1374881D03*
Y1381801D03*
X686710Y1374881D03*
Y1369889D03*
Y1381801D03*
X698950Y1399079D03*
Y1394087D03*
X686710D03*
Y1399079D03*
X691666Y1394087D03*
Y1399079D03*
X698950Y1386793D03*
X691666D03*
X686710D03*
X698950Y1405999D03*
Y1410991D03*
X686710D03*
X691666D03*
X686710Y1405999D03*
X691666D03*
X696645Y1461183D03*
Y1456452D03*
Y1465914D03*
X687984Y1460782D03*
Y1465513D03*
Y1470244D03*
Y1476136D03*
X696645Y1481268D03*
Y1471806D03*
Y1476537D03*
X687984Y1480867D03*
X696645Y1491891D03*
X687984Y1496221D03*
Y1485598D03*
Y1491490D03*
X696645Y1496622D03*
Y1487160D03*
Y1511977D03*
Y1502515D03*
Y1507246D03*
X687984Y1511576D03*
Y1500952D03*
Y1506845D03*
Y1516307D03*
X696645Y1558813D03*
Y1563544D03*
X687984Y1563144D03*
X696645Y1574167D03*
Y1578898D03*
X687984Y1572606D03*
Y1578498D03*
X696645Y1568275D03*
X687984Y1567875D03*
Y1583229D03*
X696645Y1589522D03*
Y1594253D03*
X687984Y1587960D03*
Y1593853D03*
X696645Y1583629D03*
Y1598984D03*
Y1609607D03*
X687984Y1603315D03*
Y1598584D03*
Y1609207D03*
X696645Y1604876D03*
X687984Y1613938D03*
X696645Y1614338D03*
X687984Y1618669D03*
X692000Y1644980D03*
X718488Y-27642D03*
X718503Y-25127D03*
X708261Y82984D03*
Y80384D03*
Y77784D03*
Y75184D03*
X710815Y92849D03*
X708261Y85584D03*
X717775Y103037D03*
X717909Y116496D03*
Y109410D03*
Y130670D03*
Y123583D03*
X714500Y137756D03*
X713162Y434493D03*
X711764Y449873D03*
X718691Y465492D03*
Y472579D03*
X716191D03*
X711391D03*
X716191Y479666D03*
X718691D03*
X711391D03*
Y486752D03*
X716191D03*
X718691D03*
X711391Y493839D03*
X716191D03*
Y516713D03*
Y523800D03*
X718691D03*
X711391D03*
Y516713D03*
X718691D03*
Y509626D03*
Y530886D03*
X716191D03*
Y537973D03*
X711391Y530886D03*
Y537973D03*
Y566752D03*
X718691Y559665D03*
Y566752D03*
X716191D03*
X711391Y573839D03*
X718691D03*
X716191D03*
X711391Y588013D03*
X718691Y588012D03*
X716191Y588013D03*
X718691Y580926D03*
X716191D03*
X711391D03*
X716191Y602186D03*
X711391D03*
X718691Y602185D03*
Y595099D03*
X711391D03*
X716191D03*
X711391Y609272D03*
X716191D03*
X718691D03*
X716191Y616359D03*
X711391D03*
X706070Y638125D03*
X716656Y646429D03*
X703669Y665140D03*
X716350Y699477D03*
X703604Y699653D03*
X716146Y1350683D03*
X711190D03*
X716146Y1345691D03*
X711190D03*
X703906Y1350683D03*
Y1345597D03*
X716146Y1357603D03*
X711190D03*
Y1362595D03*
X716146D03*
X703906Y1357603D03*
Y1362595D03*
X716146Y1374881D03*
Y1381801D03*
Y1369889D03*
X711190D03*
Y1374881D03*
Y1381801D03*
X703906D03*
Y1369889D03*
Y1374881D03*
X716146Y1399079D03*
X711190D03*
X716146Y1393993D03*
X711190D03*
X703906Y1394087D03*
Y1399079D03*
X716146Y1386793D03*
X711190D03*
X703906D03*
X716146Y1405999D03*
X711190D03*
X716146Y1410991D03*
X711190D03*
X703906Y1405999D03*
Y1410991D03*
X712000Y1644980D03*
X721741Y-27628D03*
X721756Y-25113D03*
X724781Y-26433D03*
X735192Y94017D03*
X731192D03*
X733233Y151540D03*
X736750Y188727D03*
X730707Y226141D03*
X733507D03*
X733404Y285690D03*
X720090Y293796D03*
X722590D03*
X728104Y288190D03*
X730604Y285690D03*
X728104D03*
X730604Y288190D03*
X733404D03*
X731511Y390500D03*
X734606Y379562D03*
X722097Y410394D03*
Y403307D03*
X723491Y458406D03*
Y451319D03*
Y465492D03*
X723315Y462264D03*
X723491Y472579D03*
Y479665D03*
Y486752D03*
Y493839D03*
Y523799D03*
Y516713D03*
Y509626D03*
Y530886D03*
Y537973D03*
Y566752D03*
Y559665D03*
Y573839D03*
Y588012D03*
Y580926D03*
Y595099D03*
Y602185D03*
Y609272D03*
Y616358D03*
X734819Y646429D03*
X725318Y890354D03*
X720373Y940310D03*
X724547Y958287D03*
X723430Y1350683D03*
X728386Y1345691D03*
X723430D03*
X728386Y1350683D03*
Y1357603D03*
Y1362595D03*
X723430Y1357603D03*
Y1362595D03*
X728386Y1381801D03*
Y1374881D03*
Y1369889D03*
X723430D03*
Y1381801D03*
Y1374881D03*
X728386Y1386793D03*
X723430D03*
X728386Y1398985D03*
Y1393993D03*
X723430Y1398985D03*
Y1393993D03*
X728386Y1410897D03*
Y1405905D03*
X723430Y1410897D03*
Y1405905D03*
X732000Y1644980D03*
X748269Y84140D03*
Y76140D03*
Y80140D03*
X743201Y94017D03*
X739192D03*
X750714Y117557D03*
X745722D03*
X740312Y115401D03*
Y110445D03*
X735320D03*
Y115401D03*
X745722Y131731D03*
Y122513D03*
X740312Y129574D03*
Y124618D03*
X735320D03*
Y129574D03*
X750714Y131731D03*
Y122513D03*
Y136687D03*
X745722D03*
X748813Y146461D03*
X747715Y152367D03*
X749415Y180572D03*
Y185165D03*
X743383Y184619D03*
X736883Y191941D03*
X745363Y206760D03*
X738577Y256535D03*
X746577D03*
X747607Y279208D03*
X751711Y281307D03*
X741630Y290755D03*
X737630D03*
X745630D03*
X741161Y381500D03*
X741602Y465492D03*
X741568Y460250D03*
X739333Y470136D03*
X741602Y472579D03*
X741072Y478958D03*
X741602Y486752D03*
Y493839D03*
Y509626D03*
Y516713D03*
X738062Y537973D03*
X740542Y525483D03*
X740463Y532756D03*
X741602Y559665D03*
Y566752D03*
X741452Y579978D03*
X741602Y573839D03*
X741666Y608117D03*
X741000Y771100D03*
X738707Y987952D03*
X745673Y1007009D03*
X747910Y1345691D03*
Y1350683D03*
X735670D03*
X740626D03*
X735670Y1345691D03*
X740626D03*
X747910Y1357603D03*
Y1362595D03*
X735670Y1357603D03*
Y1362595D03*
X740626Y1357603D03*
Y1362595D03*
X747910Y1374881D03*
Y1381801D03*
Y1369889D03*
X740626Y1381801D03*
Y1369889D03*
Y1374881D03*
X735670Y1381801D03*
Y1369889D03*
Y1374881D03*
X747910Y1386793D03*
X735670Y1393993D03*
X740626D03*
Y1398985D03*
X735670D03*
X740626Y1386793D03*
X735670D03*
Y1405905D03*
Y1410897D03*
X740626Y1405905D03*
Y1410897D03*
X742655Y1445733D03*
X747590Y1627871D03*
X765847Y55513D03*
X762065Y117040D03*
X754098Y180527D03*
X757821Y192421D03*
X754053Y185121D03*
X756201Y288345D03*
Y290845D03*
X753701Y288345D03*
Y290845D03*
Y293645D03*
X756201D03*
X763898Y342319D03*
X766344Y393924D03*
Y389912D03*
Y385912D03*
X758038Y381143D03*
X766344Y409924D03*
Y405924D03*
Y401924D03*
X752341Y407148D03*
X756800Y403824D03*
X758381Y395391D03*
X759543Y445787D03*
X755593Y445908D03*
X765106Y1350683D03*
Y1345597D03*
X760150D03*
Y1350683D03*
X752866Y1345691D03*
Y1350683D03*
X765106Y1362595D03*
Y1357603D03*
X760150D03*
Y1362595D03*
X752866Y1357603D03*
Y1362595D03*
X765106Y1374881D03*
Y1381801D03*
Y1369889D03*
X760150Y1374881D03*
Y1381801D03*
Y1369889D03*
X752866Y1374881D03*
Y1381801D03*
Y1369889D03*
X765106Y1386793D03*
X760150D03*
X752866D03*
X766433Y1583713D03*
X752150Y1627871D03*
X762776Y1629415D03*
X752000Y1644980D03*
X771011Y60922D03*
X767929Y96890D03*
X771824Y110784D03*
X769175Y113394D03*
X779418Y133298D03*
X771960Y130898D03*
X773565Y134579D03*
X769351Y172665D03*
Y180665D03*
X769383Y200864D03*
Y212864D03*
Y221864D03*
Y216864D03*
X771140Y252371D03*
X780968Y303839D03*
X772990Y336324D03*
X777569Y353506D03*
X772390Y1350683D03*
X777346D03*
Y1345691D03*
X772390D03*
Y1357603D03*
Y1362595D03*
X777346Y1357603D03*
Y1362595D03*
X777114Y1442270D03*
X778045Y1622545D03*
X782289Y1620109D03*
X773822Y1627418D03*
X772000Y1644980D03*
X784410Y109172D03*
X787410D03*
X794961Y116497D03*
X797461D03*
X790161D03*
X786417Y106495D03*
X797461Y109410D03*
Y123583D03*
X794961Y123584D03*
X790161D03*
X794961Y130670D03*
X797461D03*
X790161D03*
X794961Y137757D03*
X790161D03*
X788057Y141228D03*
X786151Y146012D03*
X793221Y140296D03*
X790945Y150847D03*
X792913Y247292D03*
X785622Y253198D03*
X788522Y290304D03*
X799937Y347340D03*
X791686Y1025440D03*
X794716Y1186071D03*
X792183Y1334030D03*
Y1331230D03*
X789383Y1334030D03*
Y1331230D03*
X794506Y1411307D03*
X793723Y1468071D03*
X793564Y1642682D03*
X810623Y77784D03*
Y82984D03*
Y80384D03*
Y75184D03*
X813177Y92849D03*
X810623Y85584D03*
X802161Y116496D03*
Y109410D03*
Y102323D03*
Y130670D03*
Y123583D03*
Y137756D03*
X816364Y486870D03*
X813864D03*
X813566Y744187D03*
X812661Y810032D03*
X812980Y824166D03*
X816016Y838036D03*
X813182Y852800D03*
X814731Y889365D03*
X812811Y908162D03*
X809682Y1133284D03*
X806787Y1148000D03*
X815034Y1159455D03*
X809623Y1160168D03*
X809393Y1187252D03*
X807487Y1193019D03*
X815487D03*
X811487D03*
X817446Y1210089D03*
X800627Y1392748D03*
X800703Y1426779D03*
X811457Y1639797D03*
X820137Y103037D03*
X820271Y116496D03*
Y109410D03*
Y130670D03*
Y123583D03*
X816637Y137756D03*
X824952Y293796D03*
X822452D03*
X830466Y285690D03*
Y288190D03*
X825792Y305225D03*
X823529Y467189D03*
X830318Y674164D03*
X829784Y713939D03*
X832284Y731216D03*
X830484Y746701D03*
X819993Y754109D03*
X817500Y760000D03*
X820547Y780314D03*
X826925Y769000D03*
X820500Y777500D03*
X826925Y787000D03*
X820500Y792000D03*
X818500Y814000D03*
X820432Y800529D03*
X826925Y805000D03*
Y823000D03*
X826165Y863000D03*
X819134Y863607D03*
X829000Y852000D03*
X825686Y869496D03*
X826797Y883756D03*
X825508Y913869D03*
X822462Y915095D03*
X818347Y939610D03*
X828193Y949324D03*
X832432Y977982D03*
X832711Y993268D03*
X828385Y1120599D03*
X817006Y1133027D03*
X822006Y1130208D03*
X825744Y1146937D03*
X823220Y1162817D03*
X823487Y1193019D03*
X819487D03*
X826612Y1219254D03*
X819522Y1212164D03*
X821816Y1214458D03*
X832084Y1461072D03*
X831457Y1639797D03*
X844781Y-65613D03*
X841756Y-64293D03*
X838503Y-64307D03*
X841741Y-66808D03*
X838488Y-66822D03*
X841554Y94017D03*
X837554D03*
X845563D03*
X833554D03*
X837682Y110445D03*
Y115401D03*
X848084Y117557D03*
X842674Y115401D03*
Y110445D03*
Y129574D03*
Y124618D03*
X837682D03*
Y129574D03*
X848084Y131731D03*
Y122513D03*
Y136687D03*
X839112Y188727D03*
X839245Y191941D03*
X845745Y184619D03*
X847725Y206760D03*
X833069Y226141D03*
X835869D03*
X848939Y256535D03*
X840939D03*
X832966Y288190D03*
Y285690D03*
X835766Y288190D03*
Y285690D03*
X843992Y290755D03*
X839992D03*
X847992D03*
X835236Y533174D03*
X845729Y661263D03*
X836503Y667845D03*
X845784Y713939D03*
X848284Y731181D03*
X846484Y746701D03*
X841500Y758161D03*
Y776161D03*
Y794161D03*
Y812161D03*
X838685Y832987D03*
X845654Y895437D03*
X833870Y881860D03*
X839381Y915839D03*
X839122Y939655D03*
X843734Y1008778D03*
X848520Y1016855D03*
X850631Y84140D03*
Y80140D03*
Y76140D03*
X864006Y117261D03*
X853076Y117557D03*
Y131731D03*
Y122513D03*
Y136687D03*
X851777Y180572D03*
X856460Y180527D03*
X860183Y192421D03*
X851777Y185165D03*
X856415Y185121D03*
X849969Y279208D03*
X854073Y281307D03*
X864920Y343168D03*
X854086Y385000D03*
X858586D03*
X850733Y461382D03*
X850832Y473382D03*
X850738Y477382D03*
X850909Y482382D03*
X853900Y627700D03*
X858202Y646330D03*
X851111Y656635D03*
X856145Y677887D03*
X855646Y685230D03*
X858186Y713170D03*
X867227Y722060D03*
X849500Y761000D03*
X864575Y770500D03*
X849500Y779000D03*
X864575Y788500D03*
X849500Y797000D03*
Y815000D03*
X864575Y806500D03*
X865004Y831273D03*
X864464Y828503D03*
X864575Y824500D03*
X851782Y823720D03*
X851161Y855205D03*
X856628Y915242D03*
X864253D03*
X849600Y915266D03*
X855867Y935540D03*
X849088Y951081D03*
X852247Y1009529D03*
X849996Y1091073D03*
X850023Y1095179D03*
X863342Y1120636D03*
X855542D03*
X858142D03*
X860842D03*
X863442Y1130336D03*
X858242D03*
X855642D03*
X860942D03*
Y1139336D03*
X863442D03*
X861119Y1148080D03*
X863619D03*
X851457Y1639797D03*
X873373Y60922D03*
X868209Y55513D03*
X870395Y96738D03*
X865402Y91951D03*
X871713Y172665D03*
Y180665D03*
X871745Y200864D03*
Y212864D03*
Y216864D03*
Y221864D03*
X876246Y302754D03*
X869313Y688486D03*
X872069Y700894D03*
X876286Y686970D03*
X880501Y710611D03*
X873021Y715729D03*
X877616Y749484D03*
X873318Y744597D03*
X873250Y798750D03*
X872700Y816615D03*
X872628Y915242D03*
X880628D03*
X876481Y941126D03*
X868908Y933640D03*
X867199Y949372D03*
X869390Y978003D03*
X878004Y1224406D03*
X883142Y1259935D03*
X875700Y1299700D03*
X871457Y1639797D03*
X886011Y154100D03*
X895780Y237517D03*
Y232634D03*
X886261Y252090D03*
X885741Y261150D03*
X894844Y418983D03*
X889219Y426952D03*
X887770Y415290D03*
X890270D03*
X897344Y418983D03*
X894519Y426952D03*
X889596Y437264D03*
X896388Y437614D03*
X887096Y437264D03*
X892019Y426952D03*
X897019D03*
X882891Y536122D03*
X896449Y550863D03*
X893949Y550363D03*
X882949Y557363D03*
X887949Y608863D03*
X894449Y606363D03*
X884903Y694119D03*
X886836Y729778D03*
X889083Y780371D03*
X888545Y785528D03*
X888514Y797602D03*
X891916Y808965D03*
X882609Y994245D03*
X897056Y1091391D03*
X891055Y1095407D03*
X897056Y1095984D03*
X884906Y1102760D03*
X884890Y1098724D03*
X893190Y1208069D03*
X894887Y1227209D03*
X891003Y1292765D03*
X890738Y1311132D03*
X891457Y1639797D03*
X898813Y146461D03*
X897715Y152367D03*
X898851Y231496D03*
Y238583D03*
Y245669D03*
X910977Y238583D03*
X898851Y259843D03*
X898576Y253056D03*
X910977Y252756D03*
Y257480D03*
X898851Y274016D03*
X910977Y266929D03*
X898851D03*
X912786Y306697D03*
X901848Y307782D03*
Y312738D03*
X909417Y323302D03*
X912085Y332335D03*
X898888Y437614D03*
X906996Y530707D03*
X902459Y530755D03*
X911630Y543998D03*
X910578Y550186D03*
X909362Y555614D03*
X898156Y554812D03*
X909024Y586768D03*
X908730Y619120D03*
X913686D03*
X899898Y619040D03*
X904854D03*
X910036Y702285D03*
X910753Y715864D03*
X912864Y864189D03*
Y870488D03*
Y867338D03*
X899693Y895207D03*
X904833Y915340D03*
X912628Y928101D03*
X911355Y944909D03*
X906710Y962433D03*
X906909Y951494D03*
X909296Y1020224D03*
X909300Y1014639D03*
X901739Y1091346D03*
X897815Y1078042D03*
X901366Y1078069D03*
X901694Y1095940D03*
X911071Y1123803D03*
X905771D03*
X903171D03*
X908371D03*
X910971Y1114103D03*
X908271D03*
X903071D03*
X905671D03*
X911699Y1129488D03*
X909041Y1126328D03*
X911641D03*
X903908Y1132870D03*
X904063Y1135946D03*
X901940Y1236799D03*
Y1229899D03*
Y1232399D03*
Y1246199D03*
Y1243699D03*
Y1239299D03*
X904703Y1297398D03*
X911457Y1639797D03*
X919175Y113394D03*
X921824Y110784D03*
X921418Y133298D03*
X929418D03*
X923565Y134579D03*
X920142Y308501D03*
X926801Y323302D03*
X923902Y332411D03*
X924600Y533706D03*
X920961Y550075D03*
X915949Y563363D03*
X915712Y613792D03*
X915194Y666671D03*
X928043Y677795D03*
X917286Y679625D03*
X924932Y701051D03*
X920628Y928101D03*
X928628D03*
X916628D03*
X924628D03*
X924487Y951244D03*
X918648Y964717D03*
X915490Y969886D03*
X916749Y1080659D03*
Y1088659D03*
X917110Y1101902D03*
X927598Y1120636D03*
X924898D03*
X914661Y1132612D03*
X914299Y1129488D03*
X914241Y1126328D03*
X924919Y1130336D03*
X927619D03*
X924919Y1139336D03*
X927419D03*
X925097Y1147708D03*
X927597D03*
X927146Y1328597D03*
Y1323641D03*
X929094Y1542353D03*
Y1545353D03*
X926041Y1554503D03*
Y1551503D03*
Y1548503D03*
Y1557503D03*
Y1560503D03*
X944961Y116497D03*
X934410Y109172D03*
X936417Y106495D03*
X937410Y109172D03*
X940161Y116497D03*
Y123584D03*
X944961D03*
X940161Y130670D03*
X944961D03*
X940161Y137757D03*
X944961D03*
X936151Y146012D03*
X938057Y141228D03*
X940945Y150847D03*
X932388Y330517D03*
X932622Y336817D03*
X944694Y352192D03*
X931627Y561578D03*
Y565578D03*
X943825Y581222D03*
Y591215D03*
X935281Y677795D03*
X945626Y789761D03*
X932000Y831000D03*
X942634Y886520D03*
X933700Y887508D03*
X944839Y902400D03*
X938188Y900853D03*
X944628Y928101D03*
X932628D03*
X936628D03*
X940497D03*
X941981Y1224406D03*
X947119Y1259935D03*
X933254Y1308273D03*
X940848Y1310181D03*
X930441Y1455039D03*
Y1458039D03*
Y1464039D03*
Y1461039D03*
Y1467039D03*
X938670Y1510528D03*
X941270D03*
Y1505328D03*
X938670D03*
X940170Y1507928D03*
X943870Y1510528D03*
Y1505328D03*
X945370Y1507928D03*
X942770D03*
X935094Y1542353D03*
X932094D03*
X935094Y1545353D03*
X932094D03*
X938094Y1542353D03*
Y1545353D03*
X941094Y1542353D03*
X944094D03*
X941094Y1545353D03*
X944094D03*
X931457Y1639797D03*
X960623Y82984D03*
Y77784D03*
Y80384D03*
Y75184D03*
Y85584D03*
X947461Y116497D03*
X952161Y116496D03*
Y109410D03*
Y102323D03*
X947461Y109410D03*
Y130670D03*
X952161D03*
Y123583D03*
X947461D03*
X952161Y137756D03*
X949443Y208206D03*
X949579Y330517D03*
X949813Y336817D03*
X956863Y451466D03*
X953816Y555194D03*
X951016D03*
X953816Y571194D03*
X951016D03*
X953816Y563194D03*
X951016D03*
X946625Y581222D03*
X949425D03*
Y591215D03*
X946625D03*
X948427Y611091D03*
X957551Y698251D03*
X954023Y725336D03*
X951195Y727165D03*
X952681Y735256D03*
X956323Y748412D03*
X957474Y764426D03*
X955086Y779798D03*
X956051Y793937D03*
X947735Y824921D03*
X948935Y835800D03*
X954700Y842700D03*
X947735Y854935D03*
X953091Y857440D03*
X953217Y861440D03*
X955967Y860376D03*
X946700Y849200D03*
X950251Y874268D03*
X950291Y870240D03*
Y866240D03*
X953145Y874240D03*
X952738Y886624D03*
X953587Y902814D03*
X961479Y927643D03*
X957671Y991564D03*
X946642Y991361D03*
X961033Y1091391D03*
X948883Y1102760D03*
X948867Y1098724D03*
X955032Y1095407D03*
X961033Y1095984D03*
X957167Y1208069D03*
X958864Y1227209D03*
X949970Y1321749D03*
X952070Y1367717D03*
X949070D03*
X956238Y1455139D03*
Y1458139D03*
Y1461139D03*
Y1464139D03*
X952676Y1461039D03*
Y1464039D03*
Y1458039D03*
Y1455039D03*
X956238Y1467139D03*
Y1469902D03*
X952676Y1467039D03*
X946470Y1510528D03*
Y1505328D03*
X947094Y1545353D03*
Y1542353D03*
X951457Y1639797D03*
X963177Y92849D03*
X970137Y103037D03*
X970271Y116496D03*
Y109410D03*
Y130670D03*
Y123583D03*
X966347Y137756D03*
X974952Y293796D03*
X972452D03*
X972147Y323681D03*
X975932Y437508D03*
X971932D03*
X962769Y458466D03*
X973695Y448874D03*
X969109Y449352D03*
X978723Y504699D03*
X976223D03*
X973723D03*
X978425Y516979D03*
X973425D03*
X975925D03*
X967302Y627948D03*
X969491Y629362D03*
X963187Y667620D03*
X973138Y667621D03*
X978059Y747438D03*
X976764Y786563D03*
X964070Y807686D03*
Y813006D03*
X977218Y802178D03*
X964036Y818961D03*
X968319Y826191D03*
X976635Y835018D03*
X976800Y838011D03*
X974282D03*
X976902Y847135D03*
X971808Y851242D03*
X975925Y854783D03*
X978201Y897500D03*
X969806Y993033D03*
X965716Y1091346D03*
X965671Y1095940D03*
X967148Y1123803D03*
X969748D03*
X969648Y1114103D03*
X967048D03*
X972348Y1123803D03*
X975048D03*
X972248Y1114103D03*
X974948D03*
X970485Y1132870D03*
X967885D03*
X968874Y1145169D03*
X966374D03*
X965917Y1236799D03*
Y1229899D03*
Y1232399D03*
Y1246199D03*
Y1243699D03*
Y1239299D03*
X978727Y1284908D03*
X971467Y1509515D03*
X974067D03*
X972567Y1512115D03*
X969967D03*
X976667Y1509515D03*
X977767Y1506915D03*
X975167D03*
X969967D03*
X972567D03*
X975167Y1512115D03*
X977767D03*
X971140Y1514693D03*
X968540D03*
X973740D03*
X976340D03*
X971457Y1639797D03*
X983554Y94017D03*
X987554D03*
X991554D03*
X987682Y115401D03*
X992674D03*
Y110445D03*
X987682D03*
X992674Y124618D03*
X987682D03*
Y129574D03*
X992674D03*
X985595Y151540D03*
X989245Y191941D03*
X989112Y188727D03*
X983069Y226141D03*
X985869D03*
X990939Y256535D03*
X985766Y288190D03*
X982966D03*
X985766Y285690D03*
X982966D03*
X980466Y288190D03*
Y285690D03*
X993992Y290755D03*
X989992D03*
X979932Y437508D03*
X982792Y447269D03*
X982670Y450201D03*
X989936Y519531D03*
X987436D03*
X982436D03*
X984936D03*
X983843Y633205D03*
Y636005D03*
Y638805D03*
X984307Y748432D03*
X985030Y781204D03*
X988329Y781445D03*
X991990Y773974D03*
X984963Y785387D03*
X979313Y814316D03*
X987903Y818645D03*
X993061Y833135D03*
X979203Y837159D03*
X988820Y858903D03*
X980529Y879097D03*
X988231Y878203D03*
X984892Y868720D03*
X987790Y896596D03*
X995133Y888503D03*
X982787Y899757D03*
X988461Y1013841D03*
X980726Y1080659D03*
Y1088659D03*
X981087Y1101902D03*
X988389Y1302558D03*
X980501Y1369685D03*
X983501D03*
X979538Y1464039D03*
Y1461039D03*
Y1458039D03*
Y1455039D03*
Y1467039D03*
Y1469802D03*
X979267Y1509515D03*
X984467D03*
X981867D03*
X985567Y1512115D03*
Y1506915D03*
X980367D03*
X982967D03*
Y1512115D03*
X980367D03*
X989667Y1509515D03*
X992267D03*
X987067D03*
X988167Y1512115D03*
X990767D03*
Y1506915D03*
X988167D03*
X984140Y1514693D03*
X981540D03*
X978940D03*
X986740D03*
X989340D03*
X991457Y1639797D03*
X1005256Y-25113D03*
X1002003Y-25027D03*
X1005241Y-27628D03*
X1001988Y-27542D03*
X1008281Y-26433D03*
X1000631Y84140D03*
Y76140D03*
Y80140D03*
X995563Y94017D03*
X1003076Y117557D03*
X998084D03*
X1003076Y122513D03*
Y131731D03*
X998084Y122513D03*
Y131731D03*
X1001175Y146461D03*
X1003076Y136687D03*
X998084D03*
X1000077Y152367D03*
X1001777Y180572D03*
X1006460Y180527D03*
X1010183Y192421D03*
X1001777Y185165D03*
X1006415Y185121D03*
X995745Y184619D03*
X997725Y206760D03*
X998939Y256535D03*
X999826Y278734D03*
X1004061Y280808D03*
X997992Y290755D03*
X1004544Y318050D03*
X1004933Y314535D03*
X997921Y333654D03*
X995913Y633450D03*
Y636250D03*
Y639050D03*
X1008342Y761735D03*
X1003539Y762632D03*
X1002834Y777394D03*
X1006053Y787745D03*
X999825Y819488D03*
X1002887Y834342D03*
X1000369D03*
X1005607Y874859D03*
Y877859D03*
X1002930Y906785D03*
X1010009Y998100D03*
X1005301Y1006560D03*
X999700Y1018400D03*
X1008312Y1363533D03*
X1008452Y1376752D03*
X1008483Y1372734D03*
X1006211Y1397662D03*
X1009338Y1391597D03*
Y1388597D03*
X1002538Y1463939D03*
Y1460939D03*
Y1457939D03*
Y1454939D03*
Y1466939D03*
Y1469702D03*
X1008549Y1509815D03*
X1007049Y1507215D03*
X1011149Y1509815D03*
X1009649Y1507215D03*
Y1512415D03*
X1007049D03*
X1008222Y1514993D03*
X1005622D03*
X1010822D03*
X1023373Y60922D03*
X1018209Y55513D03*
X1020254Y97068D03*
X1014006Y117261D03*
X1021537Y113394D03*
X1024186Y110784D03*
X1024289Y130898D03*
X1025927Y134579D03*
X1021713Y180665D03*
Y172665D03*
X1026915Y203393D03*
X1021745Y212864D03*
Y200864D03*
Y221864D03*
Y216864D03*
X1023502Y252371D03*
X1013354Y323362D03*
X1013327Y327453D03*
X1013318Y333190D03*
X1022845Y340944D03*
X1013313Y339909D03*
X1015195Y428305D03*
X1015804Y760454D03*
X1026090Y770943D03*
X1019375Y783056D03*
X1018044Y793592D03*
X1015800Y807535D03*
X1014587Y802788D03*
X1025859Y802275D03*
X1020703Y833659D03*
X1021221Y848712D03*
X1025219Y842155D03*
X1025239Y845070D03*
X1022009Y997860D03*
X1018009D03*
X1026009D03*
X1014009D03*
X1014767Y1035088D03*
X1022594Y1035114D03*
X1017297Y1102091D03*
X1026606Y1102591D03*
X1023106Y1102091D03*
X1017297Y1114691D03*
X1023106D03*
X1026606D03*
X1023106Y1127291D03*
X1026606D03*
X1017297Y1139891D03*
X1023106D03*
X1026606D03*
X1017297Y1127291D03*
X1026606Y1152491D03*
X1017297D03*
X1023106D03*
X1017297Y1165091D03*
X1023106D03*
X1026606D03*
X1017297Y1177691D03*
X1023106D03*
X1026606D03*
X1022420Y1203204D03*
X1026968Y1223749D03*
X1025434Y1320606D03*
X1011829Y1347471D03*
Y1342515D03*
X1015286Y1344924D03*
X1021623Y1373216D03*
X1012338Y1388597D03*
Y1391597D03*
X1015338D03*
Y1388597D03*
X1021338D03*
Y1391597D03*
X1018338D03*
Y1388597D03*
X1027338D03*
Y1391597D03*
X1024338D03*
Y1388597D03*
X1025138Y1463839D03*
Y1460839D03*
Y1457839D03*
Y1454839D03*
Y1466839D03*
Y1469602D03*
X1013749Y1509815D03*
X1016349D03*
X1021549D03*
X1018949D03*
X1024149D03*
X1022649Y1507215D03*
X1025249D03*
X1017449D03*
X1020049D03*
X1014849D03*
X1012249D03*
X1026749Y1509815D03*
X1012249Y1512415D03*
X1014849D03*
X1025249D03*
X1022649D03*
X1020049D03*
X1017449D03*
X1013422Y1514993D03*
X1023822D03*
X1021222D03*
X1018622D03*
X1016022D03*
X1026422D03*
X1011457Y1639797D03*
X1036772Y109172D03*
X1039772D03*
X1038779Y106495D03*
X1042523Y116497D03*
X1031780Y133298D03*
X1042523Y130670D03*
Y123584D03*
X1038513Y146012D03*
X1040419Y141228D03*
X1042523Y137757D03*
X1043307Y150847D03*
X1037984Y253198D03*
X1031354Y325901D03*
X1031382Y340947D03*
X1031310Y337888D03*
X1031377Y333671D03*
X1031362Y329268D03*
X1038796Y763272D03*
X1042880Y794924D03*
X1028155Y879413D03*
X1030300Y881400D03*
X1043252Y902501D03*
X1030009Y997860D03*
X1034009D03*
X1038252Y1009354D03*
X1034752D03*
X1028943D03*
X1042009Y997860D03*
X1038009D03*
X1034752Y1021954D03*
X1038252D03*
X1043553Y1035384D03*
X1040600Y1210600D03*
X1035384Y1215195D03*
X1034513Y1333665D03*
X1042586Y1345824D03*
X1030338Y1391597D03*
Y1388597D03*
X1029349Y1509815D03*
X1027849Y1507215D03*
Y1512415D03*
X1031457Y1639797D03*
X1049823Y109410D03*
X1054523Y116496D03*
Y109410D03*
Y102323D03*
X1049823Y116497D03*
X1047323D03*
X1049823Y130670D03*
X1047323D03*
Y123584D03*
X1049823Y123583D03*
X1054523Y130670D03*
Y123583D03*
Y137756D03*
X1047323Y137757D03*
X1045275Y247292D03*
X1050777Y450750D03*
X1054876Y536382D03*
X1059843Y597580D03*
X1059782Y594668D03*
X1062098Y615600D03*
X1044112Y778835D03*
X1045744Y800835D03*
X1048328Y808166D03*
X1057961Y931919D03*
X1046009Y997860D03*
X1054009D03*
X1050009D03*
X1058009D03*
X1059689Y1012354D03*
Y1024954D03*
X1048043Y1105091D03*
Y1117691D03*
Y1130291D03*
Y1155491D03*
Y1142891D03*
Y1168091D03*
Y1180691D03*
X1051249Y1290288D03*
X1052221Y1336984D03*
X1058891Y1345691D03*
Y1350683D03*
X1053935Y1345691D03*
Y1350683D03*
X1058891Y1362595D03*
X1053935D03*
X1058891Y1357603D03*
X1053935D03*
X1058891Y1381801D03*
Y1374881D03*
Y1369889D03*
X1053935Y1381801D03*
Y1374881D03*
Y1369889D03*
X1058891Y1386793D03*
X1053935D03*
X1051457Y1639797D03*
X1071988Y-66722D03*
X1075241Y-66808D03*
X1072003Y-64207D03*
X1075256Y-64293D03*
X1062985Y82984D03*
Y75184D03*
Y77784D03*
Y80384D03*
X1065539Y92849D03*
X1062985Y85584D03*
X1072499Y103037D03*
X1072633Y116496D03*
Y109410D03*
Y130670D03*
Y123583D03*
X1069224Y137756D03*
X1074814Y293796D03*
X1061325Y339509D03*
X1060679Y360151D03*
Y364276D03*
X1071548Y555234D03*
X1071263Y562003D03*
X1062066Y599588D03*
X1061328Y589556D03*
X1061267Y592354D03*
X1062069Y596095D03*
X1062066Y607588D03*
X1066559Y634946D03*
X1066009Y997860D03*
X1062009D03*
X1074009D03*
X1070778Y1012252D03*
X1066933Y1040567D03*
X1071641Y1058029D03*
X1060172Y1050481D03*
X1071348Y1050503D03*
X1066175Y1350683D03*
Y1345691D03*
X1071131Y1350683D03*
Y1345691D03*
X1066175Y1357603D03*
Y1362595D03*
X1071131Y1357603D03*
Y1362595D03*
X1066175Y1381801D03*
Y1369795D03*
Y1374881D03*
X1071131Y1381801D03*
Y1369795D03*
Y1374881D03*
X1066175Y1393993D03*
Y1399079D03*
Y1386793D03*
X1071131Y1399079D03*
Y1393993D03*
Y1386793D03*
X1066175Y1405999D03*
Y1410991D03*
X1071131Y1405999D03*
Y1410991D03*
X1071457Y1639797D03*
X1078281Y-65613D03*
X1089916Y94017D03*
X1085916D03*
X1090044Y110445D03*
Y115401D03*
Y124618D03*
Y129574D03*
X1087957Y151540D03*
X1091607Y191941D03*
X1091474Y188727D03*
X1085431Y226141D03*
X1088231D03*
X1088128Y285690D03*
Y288190D03*
X1085328D03*
X1082828Y285690D03*
X1085328D03*
X1082828Y288190D03*
X1077314Y293796D03*
X1092354Y290755D03*
X1077602Y314060D03*
X1091542Y389154D03*
Y410413D03*
Y396240D03*
Y403327D03*
Y417500D03*
Y424587D03*
Y431673D03*
Y438760D03*
Y445847D03*
Y467539D03*
Y474626D03*
Y488799D03*
Y481713D03*
Y495886D03*
Y511673D03*
Y518760D03*
Y525847D03*
Y532933D03*
Y540020D03*
Y547106D03*
X1090823Y602197D03*
X1091287Y595108D03*
X1079809Y1034386D03*
X1090655Y1350683D03*
Y1345691D03*
X1083371D03*
Y1350683D03*
X1078415Y1345691D03*
Y1350683D03*
X1090655Y1357603D03*
Y1362595D03*
X1083371Y1357603D03*
Y1362595D03*
X1078415D03*
Y1357603D03*
X1090655Y1381801D03*
Y1374881D03*
Y1369889D03*
X1083371D03*
Y1374881D03*
Y1381801D03*
X1078415Y1369889D03*
Y1374881D03*
Y1381801D03*
X1090655Y1394087D03*
Y1399079D03*
Y1386793D03*
X1083371D03*
Y1399079D03*
Y1394087D03*
X1078415Y1386793D03*
Y1394087D03*
Y1399079D03*
X1090655Y1405999D03*
Y1410991D03*
X1083371Y1405999D03*
Y1410991D03*
X1078415Y1405999D03*
Y1410991D03*
X1092000Y1644980D03*
X1102993Y84140D03*
Y76140D03*
Y80140D03*
X1097925Y94017D03*
X1093916D03*
X1100446Y117557D03*
X1095036Y115401D03*
Y110445D03*
X1105438Y117557D03*
X1095036Y129574D03*
Y124618D03*
X1105438Y131731D03*
Y122513D03*
X1100446Y131731D03*
Y122513D03*
X1103537Y146461D03*
X1100446Y136687D03*
X1105438D03*
X1102439Y152367D03*
X1104139Y180572D03*
X1108822Y180527D03*
X1104139Y185165D03*
X1108777Y185121D03*
X1098107Y184619D03*
X1100087Y206760D03*
X1101301Y256535D03*
X1093301D03*
X1102331Y279208D03*
X1106435Y281307D03*
X1096354Y290755D03*
X1100354D03*
X1100703Y340560D03*
X1101999Y353495D03*
X1093994Y374003D03*
X1106161Y389154D03*
X1104691Y396240D03*
X1108776Y422864D03*
X1108846Y429832D03*
X1108451Y436447D03*
X1108395Y472772D03*
X1105002Y516841D03*
X1108253Y510565D03*
X1099949Y550123D03*
X1099827Y552872D03*
X1101581Y572334D03*
X1099272Y562443D03*
X1101040Y560675D03*
X1099813Y574102D03*
X1104448Y653161D03*
X1108045Y677843D03*
X1107851Y1345691D03*
X1102895Y1350683D03*
Y1345691D03*
X1107851Y1350683D03*
X1095611D03*
Y1345691D03*
X1107851Y1357603D03*
X1102895Y1362595D03*
Y1357603D03*
X1107851Y1362595D03*
X1095611Y1357603D03*
Y1362595D03*
X1107851Y1369889D03*
Y1374881D03*
Y1381801D03*
X1102895Y1374881D03*
Y1369889D03*
Y1381801D03*
X1095611D03*
Y1374881D03*
Y1369889D03*
X1107851Y1386793D03*
Y1394087D03*
Y1399079D03*
X1102895Y1386793D03*
Y1394087D03*
Y1399079D03*
X1095611D03*
Y1394087D03*
Y1386793D03*
X1107851Y1405999D03*
Y1410991D03*
X1102895Y1405999D03*
Y1410991D03*
X1095611Y1405999D03*
Y1410991D03*
X1099900Y1535700D03*
X1107620Y1606752D03*
X1123052Y57511D03*
X1122613Y97042D03*
X1116368Y117261D03*
X1123899Y113394D03*
X1124075Y180665D03*
Y172665D03*
X1112545Y192421D03*
X1124107Y200864D03*
Y212864D03*
Y216864D03*
Y221864D03*
X1123500Y329000D03*
Y339000D03*
Y334000D03*
X1124753Y389153D03*
X1122253Y396240D03*
X1124753D03*
X1122253Y403327D03*
X1124753Y403326D03*
X1122253Y410413D03*
X1124753D03*
X1109468Y414823D03*
X1122253Y424586D03*
X1124753D03*
X1122253Y417500D03*
X1124753Y417499D03*
X1122253Y438760D03*
X1124753D03*
Y431673D03*
X1122253D03*
X1110486Y447953D03*
X1122253Y445847D03*
X1109653Y467539D03*
X1124753D03*
X1122253Y474626D03*
X1124753D03*
X1122253Y488799D03*
X1124753D03*
X1109129Y487711D03*
X1109242Y479104D03*
X1124753Y481712D03*
X1122253D03*
Y495886D03*
X1109653D03*
X1124753Y518760D03*
X1122253D03*
X1124753Y511673D03*
Y532933D03*
X1122253D03*
Y540020D03*
Y525846D03*
X1124753D03*
X1118863Y662981D03*
X1112839Y668885D03*
X1113244Y691851D03*
X1118855Y705043D03*
X1115135Y1345691D03*
Y1350683D03*
X1120091Y1345691D03*
Y1350683D03*
X1115135Y1357603D03*
Y1362595D03*
X1120091Y1357603D03*
Y1362595D03*
X1115135Y1374881D03*
Y1381801D03*
Y1369889D03*
X1120091D03*
Y1374881D03*
Y1381801D03*
X1115135Y1394087D03*
Y1399079D03*
Y1386793D03*
X1120091Y1399079D03*
Y1394087D03*
Y1386793D03*
X1115135Y1405999D03*
Y1410991D03*
X1120091Y1405999D03*
Y1410991D03*
X1112000Y1644980D03*
X1125735Y60922D03*
X1139134Y109172D03*
X1141141Y106495D03*
X1126548Y110784D03*
X1134142Y133298D03*
X1126142D03*
X1140875Y146012D03*
X1128289Y134579D03*
X1129277Y203393D03*
X1140346Y253198D03*
X1125864Y252371D03*
X1129553Y389153D03*
Y396240D03*
Y403326D03*
Y410413D03*
Y424586D03*
Y417499D03*
Y431673D03*
Y438760D03*
X1126931Y453564D03*
X1130355Y453483D03*
X1129553Y467539D03*
X1125178Y459792D03*
X1129553Y474626D03*
Y488799D03*
Y481712D03*
Y518760D03*
Y511673D03*
Y532933D03*
Y525846D03*
X1138098Y543925D03*
X1138673Y555000D03*
X1126633Y560500D03*
X1139615Y1350683D03*
Y1345691D03*
X1132331D03*
Y1350683D03*
X1127375D03*
Y1345691D03*
X1139615Y1357603D03*
Y1362595D03*
X1132331D03*
Y1357603D03*
X1127375D03*
Y1362595D03*
X1139615Y1374881D03*
Y1369889D03*
Y1381801D03*
X1132331Y1369889D03*
Y1381801D03*
Y1374881D03*
X1127375Y1369889D03*
Y1381801D03*
Y1374881D03*
X1139615Y1394087D03*
Y1399079D03*
Y1386793D03*
X1132331D03*
Y1394087D03*
Y1399079D03*
X1127375Y1386793D03*
Y1394087D03*
Y1399079D03*
X1139615Y1405999D03*
Y1410991D03*
X1132331Y1405999D03*
Y1410991D03*
X1127375Y1405999D03*
Y1410991D03*
X1129637Y1465913D03*
Y1461182D03*
Y1456451D03*
X1138298Y1465513D03*
Y1460782D03*
X1129637Y1476536D03*
Y1481267D03*
X1138298Y1476136D03*
Y1470244D03*
Y1480867D03*
X1129637Y1471805D03*
Y1496621D03*
X1138298Y1491490D03*
Y1485598D03*
Y1496221D03*
X1129637Y1491890D03*
Y1487159D03*
X1138298Y1500952D03*
Y1511576D03*
X1129637Y1507245D03*
Y1502514D03*
Y1511976D03*
X1138298Y1506845D03*
Y1516307D03*
X1129637Y1563544D03*
Y1558813D03*
X1138298Y1563144D03*
Y1572606D03*
X1129637Y1568275D03*
Y1578898D03*
Y1574167D03*
X1138298Y1567875D03*
Y1578498D03*
X1129637Y1583629D03*
Y1594253D03*
Y1589522D03*
X1138298Y1583229D03*
Y1593853D03*
Y1587960D03*
Y1598584D03*
Y1603315D03*
X1129637Y1609607D03*
Y1598984D03*
Y1604876D03*
X1138298Y1609207D03*
X1129637Y1614338D03*
X1138298Y1613938D03*
Y1618669D03*
X1132000Y1644980D03*
X1142134Y109172D03*
X1156885Y116496D03*
Y102323D03*
Y109410D03*
X1152185D03*
Y116497D03*
X1149685D03*
X1144885D03*
X1152185Y130670D03*
X1149685D03*
Y123584D03*
X1152185Y123583D03*
X1144885Y130670D03*
Y123584D03*
X1156885Y130670D03*
Y123583D03*
X1142781Y141228D03*
X1156885Y137756D03*
X1149685Y137757D03*
X1144885D03*
X1145669Y150847D03*
X1147637Y247292D03*
X1145761Y324148D03*
X1157251Y636842D03*
X1156023Y678462D03*
X1149345Y771517D03*
X1145910Y794217D03*
X1151277Y790996D03*
X1149627Y813323D03*
X1146985Y812642D03*
X1152510Y844642D03*
X1156811Y1350683D03*
Y1345691D03*
X1151855D03*
Y1350683D03*
X1144571D03*
Y1345691D03*
X1156811Y1357603D03*
Y1362595D03*
X1151855D03*
Y1357603D03*
X1144571D03*
Y1362595D03*
X1156811Y1374881D03*
Y1369889D03*
Y1381801D03*
X1151855Y1374881D03*
Y1369889D03*
Y1381801D03*
X1144571Y1369889D03*
Y1381801D03*
Y1374881D03*
X1156811Y1386793D03*
Y1399079D03*
Y1394087D03*
X1151855Y1386793D03*
Y1399079D03*
Y1394087D03*
X1144571D03*
Y1399079D03*
Y1386793D03*
X1156811Y1405999D03*
Y1410991D03*
X1151855Y1405999D03*
Y1410991D03*
X1144571Y1405999D03*
Y1410991D03*
X1146960Y1465913D03*
Y1461182D03*
X1155621Y1465513D03*
Y1460782D03*
X1146960Y1456451D03*
X1155621Y1480867D03*
X1146960Y1471805D03*
Y1476536D03*
Y1481267D03*
X1155621Y1476136D03*
Y1470244D03*
Y1491490D03*
Y1485598D03*
Y1496221D03*
X1146960Y1487159D03*
Y1491890D03*
Y1496621D03*
Y1507245D03*
Y1502514D03*
X1155621Y1506845D03*
Y1500952D03*
Y1511576D03*
X1146960Y1511976D03*
X1155621Y1516307D03*
X1146960Y1563544D03*
X1155621Y1563144D03*
X1146960Y1558813D03*
X1155621Y1572606D03*
X1146960Y1568275D03*
X1155621Y1567875D03*
X1146960Y1574167D03*
Y1578898D03*
X1155621Y1578498D03*
X1146960Y1594253D03*
X1155621Y1593853D03*
Y1587960D03*
X1146960Y1583629D03*
X1155621Y1583229D03*
X1146960Y1589522D03*
Y1609607D03*
Y1604876D03*
Y1598984D03*
X1155621Y1609207D03*
Y1598584D03*
Y1603315D03*
X1146960Y1614338D03*
X1155621Y1613938D03*
Y1618669D03*
X1152000Y1644980D03*
X1165347Y82984D03*
Y75184D03*
Y77784D03*
Y80384D03*
X1167756Y92734D03*
X1165347Y85584D03*
X1171586Y137756D03*
X1168902Y431029D03*
X1167931Y435029D03*
X1169173Y427017D03*
X1168851Y449873D03*
X1171255Y456287D03*
X1173278Y472579D03*
X1168478D03*
X1173278Y479666D03*
X1168478D03*
Y486752D03*
X1173278D03*
X1168478Y493839D03*
X1173278D03*
X1168478Y523800D03*
Y516713D03*
X1173278D03*
Y523800D03*
Y537973D03*
X1168478D03*
X1173278Y530886D03*
X1168478D03*
X1173278Y566752D03*
X1168478D03*
Y580926D03*
X1173278D03*
Y588013D03*
X1168478D03*
X1173278Y573839D03*
X1168478D03*
Y602186D03*
X1173278D03*
Y595099D03*
X1168478D03*
X1173278Y609272D03*
X1168478D03*
Y616359D03*
X1173278D03*
X1163157Y638125D03*
X1160756Y665140D03*
X1157985Y791142D03*
X1161291Y791662D03*
X1173697Y791911D03*
X1160516Y800900D03*
X1169051Y1345597D03*
Y1350683D03*
X1164095D03*
Y1345597D03*
X1169051Y1357603D03*
Y1362595D03*
X1164095Y1357603D03*
Y1362595D03*
X1169051Y1381801D03*
Y1374881D03*
Y1369889D03*
X1164095D03*
Y1381801D03*
Y1374881D03*
X1169051Y1393993D03*
Y1399079D03*
Y1386793D03*
X1164095Y1393993D03*
Y1399079D03*
Y1386793D03*
X1169051Y1410991D03*
Y1405999D03*
X1164095D03*
Y1410991D03*
X1164283Y1465913D03*
Y1456451D03*
Y1461182D03*
X1172944Y1465513D03*
Y1460782D03*
Y1470244D03*
Y1480867D03*
X1164283Y1471805D03*
Y1476536D03*
Y1481267D03*
X1172944Y1476136D03*
X1164283Y1487159D03*
Y1491890D03*
Y1496621D03*
X1172944Y1491490D03*
Y1485598D03*
Y1496221D03*
X1164283Y1507245D03*
Y1502514D03*
X1172944Y1506845D03*
Y1500952D03*
Y1511576D03*
X1164283Y1511976D03*
X1172944Y1516307D03*
X1164283Y1558813D03*
Y1563544D03*
X1172944Y1563144D03*
Y1567875D03*
X1164283Y1574167D03*
Y1578898D03*
X1172944Y1578498D03*
Y1572606D03*
X1164283Y1568275D03*
Y1583629D03*
X1172944Y1583229D03*
X1164283Y1589522D03*
Y1594253D03*
X1172944Y1593853D03*
Y1587960D03*
Y1598584D03*
Y1603315D03*
X1164283Y1609607D03*
Y1604876D03*
Y1598984D03*
X1172944Y1609207D03*
X1164283Y1614338D03*
X1172944Y1613938D03*
Y1618669D03*
X1172000Y1644980D03*
X1188278Y94017D03*
X1174861Y103037D03*
X1174995Y116496D03*
Y109410D03*
Y130670D03*
Y123583D03*
X1187793Y226141D03*
X1190593D03*
X1179676Y293796D03*
X1187690Y288190D03*
X1185190Y285690D03*
X1187690D03*
X1185190Y288190D03*
X1177176Y293796D03*
X1182911Y336516D03*
X1177036Y334148D03*
X1188598Y390500D03*
X1179184Y410394D03*
Y403307D03*
X1180578Y458406D03*
Y451319D03*
X1180402Y462264D03*
X1175778Y465492D03*
X1180578D03*
X1175778Y472579D03*
X1180578D03*
X1175778Y479666D03*
X1180578Y479665D03*
Y486752D03*
X1175778D03*
X1180578Y493839D03*
X1175778Y509626D03*
X1180578Y523799D03*
Y516713D03*
Y509626D03*
X1175778Y516713D03*
Y523800D03*
X1180578Y537973D03*
X1175778Y530886D03*
X1180578D03*
Y559665D03*
Y566752D03*
X1175778D03*
Y559665D03*
Y580926D03*
X1180578D03*
Y588012D03*
X1175778D03*
X1180578Y573839D03*
X1175778D03*
Y602185D03*
X1180578D03*
X1175778Y595099D03*
X1180578D03*
X1175778Y609272D03*
X1180578Y616358D03*
Y609272D03*
X1177745Y771744D03*
X1177566Y778539D03*
X1190062Y844378D03*
X1187703Y849734D03*
X1186742Y855466D03*
X1183431Y868340D03*
X1177775Y894053D03*
X1178480Y915220D03*
X1178000Y936500D03*
X1187200Y963400D03*
X1181291Y1350683D03*
Y1345691D03*
X1176335D03*
Y1350683D03*
X1181291Y1362595D03*
Y1357603D03*
X1176335Y1362595D03*
Y1357603D03*
X1181291Y1369889D03*
Y1381801D03*
Y1374881D03*
X1176335Y1369889D03*
Y1381801D03*
Y1374881D03*
X1181291Y1386793D03*
Y1399079D03*
Y1394087D03*
X1176335Y1386793D03*
Y1399079D03*
Y1394087D03*
X1181291Y1405999D03*
Y1410991D03*
X1176335Y1405999D03*
Y1410991D03*
X1181605Y1465913D03*
Y1456451D03*
Y1461182D03*
Y1471805D03*
Y1476536D03*
Y1481267D03*
Y1487159D03*
Y1491890D03*
Y1496621D03*
Y1507245D03*
Y1502514D03*
Y1511976D03*
Y1558813D03*
Y1563544D03*
Y1568275D03*
Y1574167D03*
Y1578898D03*
Y1583629D03*
Y1589522D03*
Y1594253D03*
Y1598984D03*
Y1609607D03*
Y1604876D03*
Y1614338D03*
X1205355Y84140D03*
Y76140D03*
Y80140D03*
X1196278Y94017D03*
X1200287D03*
X1192278D03*
X1202808Y117557D03*
X1197398Y110445D03*
Y115401D03*
X1192406Y110445D03*
Y115401D03*
X1197398Y129574D03*
Y124618D03*
X1192406D03*
Y129574D03*
X1202808Y122513D03*
Y131731D03*
X1205899Y146461D03*
X1202808Y136687D03*
X1204801Y152367D03*
X1190319Y151540D03*
X1200469Y184619D03*
X1193969Y191941D03*
X1193836Y188727D03*
X1202449Y206760D03*
X1203663Y256535D03*
X1195663D03*
X1204693Y279208D03*
X1194716Y290755D03*
X1202716D03*
X1190490Y285690D03*
Y288190D03*
X1198716Y290755D03*
X1198248Y381500D03*
X1198689Y465492D03*
X1198655Y460250D03*
X1196420Y470136D03*
X1198689Y472579D03*
Y486752D03*
Y479665D03*
Y493839D03*
Y509626D03*
Y516713D03*
X1195149Y537973D03*
X1197629Y525483D03*
X1197550Y532756D03*
X1198689Y559665D03*
Y566752D03*
X1198539Y579978D03*
X1198689Y573839D03*
X1198753Y608117D03*
X1198997Y790610D03*
X1198845Y998504D03*
X1204919Y1021860D03*
X1202268Y1013551D03*
X1190267Y1465513D03*
Y1460782D03*
X1198928Y1465914D03*
Y1456452D03*
Y1461183D03*
Y1481268D03*
X1190267Y1476136D03*
Y1470244D03*
Y1480867D03*
X1198928Y1476537D03*
Y1471806D03*
X1190267Y1485598D03*
Y1496221D03*
X1198928Y1491891D03*
Y1487160D03*
Y1496622D03*
X1190267Y1491490D03*
Y1506845D03*
Y1500952D03*
Y1511576D03*
X1198928Y1507246D03*
Y1502515D03*
Y1511977D03*
X1190267Y1516307D03*
X1198928Y1558813D03*
X1190267Y1563144D03*
X1198928Y1563544D03*
X1190267Y1567875D03*
X1198928Y1568275D03*
X1190267Y1578498D03*
Y1572606D03*
X1198928Y1578898D03*
Y1574167D03*
X1190267Y1583229D03*
X1198928Y1583629D03*
X1190267Y1593853D03*
Y1587960D03*
X1198928Y1594253D03*
Y1589522D03*
X1190267Y1609207D03*
Y1598584D03*
Y1603315D03*
X1198928Y1609607D03*
Y1598984D03*
Y1604876D03*
X1190267Y1613938D03*
Y1618669D03*
X1198928Y1614338D03*
X1192000Y1644980D03*
X1218730Y117261D03*
X1207800Y117557D03*
Y122513D03*
Y131731D03*
Y136687D03*
X1206501Y180572D03*
X1211184Y180527D03*
X1214907Y192421D03*
X1206501Y185165D03*
X1211139Y185121D03*
X1208797Y281307D03*
X1220985Y342319D03*
X1212680Y445908D03*
X1216630Y445787D03*
X1212000Y1644980D03*
X1222933Y55513D03*
X1228097Y60922D03*
X1225041Y97080D03*
X1228910Y110784D03*
X1226261Y113394D03*
X1229195Y130898D03*
X1236504Y133298D03*
X1230651Y134579D03*
X1226437Y180665D03*
Y172665D03*
X1226469Y200864D03*
Y212864D03*
Y216864D03*
Y221864D03*
X1228226Y252371D03*
X1238055Y303839D03*
X1230077Y336324D03*
X1234656Y353506D03*
X1223431Y393924D03*
Y389912D03*
Y385912D03*
Y409924D03*
Y405924D03*
Y401924D03*
X1229548Y1350683D03*
Y1345691D03*
X1234504D03*
Y1350683D03*
X1229548Y1362595D03*
Y1357603D03*
X1234504D03*
Y1362595D03*
X1229548Y1369889D03*
Y1374881D03*
Y1381801D03*
X1234504Y1369889D03*
Y1374881D03*
Y1381801D03*
X1229548Y1386793D03*
X1234504D03*
X1232000Y1644980D03*
X1243503Y106495D03*
X1244496Y109172D03*
X1241496D03*
X1247247Y116497D03*
X1254547Y109410D03*
Y116497D03*
X1252047D03*
X1247247Y123584D03*
Y130670D03*
X1252047Y123584D03*
X1254547Y123583D03*
Y130670D03*
X1252047D03*
X1243237Y146012D03*
X1245143Y141228D03*
X1247247Y137757D03*
X1252047D03*
X1250307Y140296D03*
X1248031Y150847D03*
X1249999Y247292D03*
X1242708Y253198D03*
X1248064Y567813D03*
Y572769D03*
Y581987D03*
Y586943D03*
Y601116D03*
Y596160D03*
Y615289D03*
Y610333D03*
X1246800Y1001600D03*
X1249200Y1014000D03*
X1248721Y1025864D03*
X1251802Y1186071D03*
X1254028Y1350683D03*
Y1345691D03*
X1241788D03*
Y1350683D03*
X1246744Y1345691D03*
Y1350683D03*
X1254028Y1357603D03*
Y1362595D03*
X1241788D03*
Y1357603D03*
X1246744Y1362595D03*
Y1357603D03*
X1254028Y1381801D03*
Y1374881D03*
Y1369889D03*
X1241788Y1374881D03*
Y1369795D03*
Y1381801D03*
X1246744Y1374881D03*
Y1369795D03*
Y1381801D03*
X1254028Y1386793D03*
Y1399079D03*
Y1394087D03*
X1241788Y1399079D03*
Y1393993D03*
Y1386793D03*
X1246744Y1393993D03*
Y1399079D03*
Y1386793D03*
X1254028Y1410991D03*
Y1405999D03*
X1241788Y1410991D03*
Y1405999D03*
X1246744Y1410991D03*
Y1405999D03*
X1245900Y1528000D03*
X1267709Y82984D03*
Y75184D03*
Y77784D03*
Y80384D03*
X1270263Y92849D03*
X1267709Y85584D03*
X1259247Y116496D03*
Y102323D03*
Y109410D03*
Y130670D03*
Y123583D03*
Y137756D03*
X1258925Y324075D03*
X1270951Y491870D03*
X1270515Y908277D03*
X1269876Y1132319D03*
X1263873Y1148000D03*
X1266709Y1160168D03*
X1258736Y1188223D03*
X1268573Y1193019D03*
X1264573D03*
X1266268Y1345691D03*
Y1350683D03*
X1258984D03*
Y1345691D03*
X1266268Y1362595D03*
Y1357603D03*
X1258984Y1362595D03*
Y1357603D03*
X1266268Y1369889D03*
Y1374881D03*
Y1381801D03*
X1258984D03*
Y1369889D03*
Y1374881D03*
X1266268Y1399079D03*
Y1394087D03*
Y1386793D03*
X1258984Y1394087D03*
Y1386793D03*
Y1399079D03*
X1266268Y1410991D03*
Y1405999D03*
X1258984D03*
Y1410991D03*
X1263242Y1523458D03*
X1262985Y1519459D03*
X1260260Y1546500D03*
X1277223Y103037D03*
X1277357Y116496D03*
Y109410D03*
Y130670D03*
Y123583D03*
X1273555Y137756D03*
X1279538Y293796D03*
X1282038D03*
X1283494Y339495D03*
X1287437Y370010D03*
X1280616Y472189D03*
X1273451Y491870D03*
X1279539Y772576D03*
Y776576D03*
X1274417Y861964D03*
X1282317Y880193D03*
X1285493Y892175D03*
X1277039Y916484D03*
X1284021Y940008D03*
X1273865Y1132497D03*
X1282830Y1146937D03*
X1272120Y1159455D03*
X1280306Y1162817D03*
X1276573Y1193019D03*
X1280573D03*
X1272573D03*
X1277108Y1211664D03*
X1279402Y1213958D03*
X1275032Y1209589D03*
X1284198Y1218754D03*
X1283464Y1345691D03*
Y1350683D03*
X1278508Y1345691D03*
Y1350683D03*
X1271224Y1345691D03*
Y1350683D03*
X1283464Y1362595D03*
Y1357603D03*
X1278508D03*
Y1362595D03*
X1271224D03*
Y1357603D03*
X1283464Y1381801D03*
Y1369889D03*
Y1374881D03*
X1278508Y1381801D03*
Y1369889D03*
Y1374881D03*
X1271224Y1369889D03*
Y1374881D03*
Y1381801D03*
X1283464Y1386793D03*
Y1399079D03*
Y1394087D03*
X1278508Y1386793D03*
Y1399079D03*
Y1394087D03*
X1271224D03*
Y1399079D03*
Y1386793D03*
X1283464Y1410991D03*
Y1405999D03*
X1278508Y1410991D03*
Y1405999D03*
X1271224Y1410991D03*
Y1405999D03*
X1291756Y-25143D03*
X1288503Y-25157D03*
X1291741Y-27658D03*
X1288488Y-27672D03*
X1294781Y-26463D03*
X1302649Y94017D03*
X1298640D03*
X1290640D03*
X1294640D03*
X1299760Y110445D03*
Y115401D03*
X1294768Y110445D03*
Y115401D03*
Y129574D03*
X1299760D03*
Y124618D03*
X1294768D03*
X1296331Y191941D03*
X1302831Y184619D03*
X1296198Y188727D03*
X1292955Y226141D03*
X1290155D03*
X1298025Y256535D03*
X1290052Y288190D03*
X1292852D03*
Y285690D03*
X1305078Y290755D03*
X1297078D03*
X1301078D03*
X1287552Y288190D03*
X1290052Y285690D03*
X1287552D03*
X1294425Y321425D03*
X1299959Y351454D03*
X1296783Y511956D03*
X1303520Y748403D03*
X1300516Y832047D03*
X1300504Y835985D03*
X1300204Y859088D03*
X1300097Y851193D03*
X1300091Y854824D03*
X1291955Y901295D03*
X1289547Y928047D03*
X1298090Y940852D03*
X1295453Y940953D03*
X1302988Y1345691D03*
Y1350683D03*
X1290748D03*
Y1345691D03*
X1295704Y1350683D03*
Y1345691D03*
X1302988Y1362595D03*
Y1357603D03*
X1290748Y1362595D03*
Y1357603D03*
X1295704Y1362595D03*
Y1357603D03*
X1302988Y1374881D03*
Y1381801D03*
Y1369889D03*
X1290748D03*
Y1381801D03*
Y1374881D03*
X1295704Y1381801D03*
Y1374881D03*
Y1369889D03*
X1302988Y1386793D03*
Y1399079D03*
Y1394087D03*
X1290748Y1399079D03*
Y1394087D03*
Y1386793D03*
X1295704Y1394087D03*
Y1399079D03*
Y1386793D03*
X1302988Y1410991D03*
Y1405999D03*
X1290748Y1410991D03*
Y1405999D03*
X1295704Y1410991D03*
Y1405999D03*
X1302866Y1461182D03*
Y1456451D03*
Y1465913D03*
Y1476536D03*
Y1471805D03*
Y1481267D03*
Y1491890D03*
Y1487159D03*
Y1496621D03*
Y1507245D03*
Y1502514D03*
Y1511976D03*
Y1558813D03*
Y1563544D03*
Y1578898D03*
Y1574167D03*
Y1568275D03*
Y1594253D03*
Y1589522D03*
Y1583629D03*
Y1609607D03*
Y1598984D03*
Y1604876D03*
Y1614338D03*
X1292000Y1644980D03*
X1307717Y84140D03*
Y76140D03*
Y80140D03*
X1310162Y117557D03*
X1305170D03*
X1310162Y122513D03*
Y131731D03*
X1305170Y122513D03*
Y131731D03*
X1310162Y136687D03*
X1305170D03*
X1313546Y180527D03*
X1308863Y180572D03*
Y185165D03*
X1317269Y192421D03*
X1313501Y185121D03*
X1304811Y206760D03*
X1306025Y256535D03*
X1307055Y279208D03*
X1311159Y281307D03*
X1314569Y318013D03*
X1312069D03*
X1317584Y313058D03*
X1316017Y349889D03*
X1308410Y370899D03*
X1313691Y402642D03*
X1316191D03*
X1309117Y398949D03*
X1306617Y401949D03*
X1308066Y413611D03*
X1310866D03*
X1313366D03*
X1315866D03*
X1315806Y423944D03*
X1313306D03*
X1310806D03*
X1308006D03*
X1307919Y478382D03*
X1307825Y482382D03*
X1305134Y812065D03*
X1313756Y829871D03*
X1308857Y836076D03*
X1316906Y842470D03*
Y867665D03*
Y883413D03*
Y892862D03*
X1316893Y925603D03*
X1318375Y943951D03*
X1303907Y960093D03*
X1307580Y990314D03*
X1304664Y1023462D03*
X1309937Y1037038D03*
X1319326Y1040723D03*
X1317437Y1152684D03*
X1307167Y1245696D03*
X1308276Y1276446D03*
X1315228Y1345691D03*
Y1350683D03*
X1307944D03*
Y1345691D03*
X1315228Y1362595D03*
Y1357603D03*
X1307944D03*
Y1362595D03*
X1315228Y1381801D03*
Y1369889D03*
Y1374881D03*
X1307944D03*
Y1381801D03*
Y1369889D03*
X1315228Y1399079D03*
Y1394087D03*
Y1386793D03*
X1307944D03*
Y1399079D03*
Y1394087D03*
X1315228Y1410991D03*
Y1405999D03*
X1307944Y1410991D03*
Y1405999D03*
X1311527Y1465513D03*
Y1460782D03*
Y1480867D03*
Y1476136D03*
Y1470244D03*
Y1491490D03*
Y1485598D03*
Y1496221D03*
Y1506845D03*
Y1500952D03*
Y1511576D03*
Y1516307D03*
Y1563144D03*
Y1567875D03*
Y1578498D03*
Y1572606D03*
Y1583229D03*
Y1593853D03*
Y1587960D03*
Y1609207D03*
Y1598584D03*
Y1603315D03*
Y1613938D03*
Y1618669D03*
X1312000Y1644980D03*
X1331756Y-64193D03*
X1328503Y-64207D03*
X1331741Y-66708D03*
X1328488Y-66722D03*
X1334781Y-65513D03*
X1321092Y117261D03*
X1328799Y172665D03*
Y180665D03*
X1328831Y212864D03*
Y200864D03*
Y221864D03*
Y216864D03*
X1330414Y310058D03*
X1325458D03*
X1322540Y313058D03*
X1333332D03*
X1331085Y334347D03*
X1323816D03*
Y341615D03*
X1331085Y348868D03*
X1323816D03*
X1332927Y468607D03*
X1326912Y493153D03*
X1325630Y513238D03*
X1335000Y590500D03*
Y586500D03*
Y633000D03*
Y637000D03*
Y677500D03*
Y681500D03*
Y724500D03*
Y728500D03*
X1324217Y780595D03*
X1332654Y836170D03*
X1323205Y861367D03*
X1335803Y851918D03*
Y877114D03*
X1326355Y886562D03*
X1328457Y959986D03*
X1321104Y964398D03*
X1323554Y967623D03*
X1331890Y1051919D03*
X1331359Y1098898D03*
X1334161Y1098518D03*
X1333905Y1123101D03*
X1331405D03*
X1323405D03*
X1320279Y1131935D03*
Y1134435D03*
Y1136935D03*
Y1139435D03*
X1334305Y1129301D03*
X1331805D03*
X1329305D03*
X1326805D03*
X1324305D03*
X1321805D03*
X1334305Y1125801D03*
X1331805D03*
X1323405D03*
X1320279Y1141935D03*
Y1146935D03*
Y1144435D03*
X1326269Y1152713D03*
Y1155213D03*
X1320493Y1204405D03*
X1334793Y1204617D03*
X1320493Y1206905D03*
Y1211905D03*
Y1209405D03*
X1334793Y1207117D03*
Y1209617D03*
Y1212117D03*
X1330070Y1297498D03*
X1335470D03*
X1332424Y1345691D03*
Y1350683D03*
X1327468D03*
Y1345691D03*
X1320184Y1350683D03*
Y1345691D03*
X1332424Y1362595D03*
Y1357603D03*
X1327468D03*
Y1362595D03*
X1320184D03*
Y1357603D03*
X1332424Y1381801D03*
Y1369889D03*
Y1374881D03*
X1327468Y1381801D03*
Y1369889D03*
Y1374881D03*
X1320184Y1381801D03*
Y1374881D03*
Y1369889D03*
X1332424Y1386793D03*
Y1394087D03*
Y1399079D03*
X1327468Y1386793D03*
Y1394087D03*
Y1399079D03*
X1320184D03*
Y1394087D03*
Y1386793D03*
X1332424Y1410991D03*
Y1405999D03*
X1327468Y1410991D03*
Y1405999D03*
X1320184Y1410991D03*
Y1405999D03*
X1328850Y1465513D03*
Y1460782D03*
X1320189Y1465913D03*
Y1456451D03*
Y1461182D03*
X1328850Y1476136D03*
Y1470244D03*
X1320189Y1481267D03*
X1328850Y1480867D03*
X1320189Y1471805D03*
Y1476536D03*
X1328850Y1491490D03*
Y1485598D03*
X1320189Y1496621D03*
X1328850Y1496221D03*
X1320189Y1487159D03*
Y1491890D03*
Y1502514D03*
X1328850Y1506845D03*
Y1500952D03*
Y1511576D03*
X1320189Y1511976D03*
Y1507245D03*
X1328850Y1516307D03*
X1320189Y1558813D03*
Y1563544D03*
X1328850Y1563144D03*
Y1567875D03*
X1320189Y1574167D03*
Y1578898D03*
X1328850Y1578498D03*
Y1572606D03*
X1320189Y1568275D03*
X1328850Y1583229D03*
X1320189Y1589522D03*
Y1594253D03*
X1328850Y1593853D03*
Y1587960D03*
X1320189Y1583629D03*
X1328850Y1603315D03*
X1320189Y1609607D03*
Y1604876D03*
Y1598984D03*
X1328850Y1609207D03*
Y1598584D03*
Y1613938D03*
Y1618669D03*
X1320189Y1614338D03*
X1332000Y1644980D03*
X1340320Y151540D03*
X1338288Y313058D03*
X1338378Y334347D03*
X1338275Y341603D03*
X1338378Y348830D03*
X1345451Y699032D03*
X1347136Y780040D03*
X1351550Y839320D03*
Y855068D03*
X1345252D03*
X1342103D03*
Y861367D03*
X1338953D03*
Y858218D03*
X1338952Y855067D03*
X1338953Y870814D03*
X1342103Y867665D03*
X1338953D03*
X1351550Y873964D03*
X1345252D03*
X1342103D03*
X1338952Y873965D03*
X1345252Y892862D03*
X1341820Y947407D03*
X1347380Y1057998D03*
Y1055498D03*
X1344880D03*
Y1057998D03*
X1347380Y1060498D03*
Y1062998D03*
X1344880D03*
Y1060498D03*
X1339349Y1098767D03*
X1339305Y1129301D03*
X1336805D03*
X1339305Y1125801D03*
X1336805D03*
X1343505Y1136935D03*
Y1134435D03*
Y1139435D03*
Y1131935D03*
X1349907D03*
Y1134435D03*
Y1136935D03*
Y1139435D03*
X1352407Y1131935D03*
Y1134435D03*
Y1136935D03*
Y1139435D03*
X1343505Y1146935D03*
Y1144435D03*
Y1141935D03*
X1349907D03*
Y1146935D03*
Y1144435D03*
X1352407Y1141935D03*
Y1146935D03*
Y1144435D03*
X1336669Y1152713D03*
Y1155213D03*
X1351405Y1154902D03*
Y1152402D03*
X1347423Y1204405D03*
X1337108Y1200821D03*
Y1198321D03*
X1347423Y1209405D03*
Y1211905D03*
Y1206905D03*
X1340870Y1297498D03*
X1346270D03*
X1351670D03*
X1351948Y1350683D03*
Y1345691D03*
X1339708Y1345597D03*
Y1350683D03*
X1344664Y1345597D03*
Y1350683D03*
X1351948Y1357603D03*
Y1362595D03*
X1339708D03*
Y1357603D03*
X1344664Y1362595D03*
Y1357603D03*
X1351948Y1374881D03*
Y1381801D03*
Y1369889D03*
X1339708Y1374881D03*
Y1381801D03*
Y1369889D03*
X1344664D03*
Y1374881D03*
Y1381801D03*
X1351948Y1386793D03*
Y1394087D03*
Y1399079D03*
X1339708D03*
Y1393993D03*
Y1386793D03*
X1344664Y1393993D03*
Y1399079D03*
Y1386793D03*
X1351948Y1410991D03*
Y1405999D03*
X1339708Y1410991D03*
Y1405999D03*
X1344664Y1410991D03*
Y1405999D03*
X1337512Y1461182D03*
X1346173Y1465513D03*
Y1460782D03*
X1337512Y1465913D03*
Y1456451D03*
X1346173Y1476136D03*
Y1470244D03*
X1337512Y1481267D03*
X1346173Y1480867D03*
X1337512Y1471805D03*
Y1476536D03*
X1346173Y1485598D03*
Y1491490D03*
X1337512Y1487159D03*
Y1491890D03*
Y1496621D03*
X1346173Y1496221D03*
X1337512Y1507245D03*
Y1502514D03*
X1346173Y1506845D03*
Y1500952D03*
Y1511576D03*
X1337512Y1511976D03*
X1346173Y1516307D03*
X1337512Y1558813D03*
Y1563544D03*
X1346173Y1563144D03*
X1337512Y1574167D03*
Y1578898D03*
X1346173Y1578498D03*
Y1572606D03*
X1337512Y1568275D03*
X1346173Y1567875D03*
X1337512Y1583629D03*
X1346173Y1583229D03*
X1337512Y1589522D03*
Y1594253D03*
X1346173Y1593853D03*
Y1587960D03*
X1337512Y1609607D03*
Y1604876D03*
Y1598984D03*
X1346173Y1609207D03*
Y1598584D03*
Y1603315D03*
X1337512Y1614338D03*
X1346173Y1613938D03*
Y1618669D03*
X1352000Y1644980D03*
X1355900Y146461D03*
X1354802Y152367D03*
X1355255Y561032D03*
Y607532D03*
Y652032D03*
X1364148Y836170D03*
X1354699Y855068D03*
X1357849Y861367D03*
X1354699D03*
X1357849Y858218D03*
X1357850Y855067D03*
X1360999Y851918D03*
Y877114D03*
X1357850Y873965D03*
X1354699Y873964D03*
X1357849Y870814D03*
Y867665D03*
X1354699D03*
X1363173Y994483D03*
X1363905Y1000855D03*
X1366493Y1000828D03*
X1367884Y1018825D03*
X1357265Y1022766D03*
X1364237Y1043140D03*
X1357265Y1030266D03*
X1363941Y1047047D03*
X1366289Y1098518D03*
X1361037Y1098428D03*
X1355533Y1123101D03*
X1363533D03*
X1366033D03*
X1366433Y1129301D03*
X1355533Y1125801D03*
X1363933D03*
X1366433D03*
X1353933Y1129301D03*
X1356433D03*
X1358933D03*
X1361433D03*
X1363933D03*
X1357397Y1155213D03*
Y1152713D03*
X1366797D03*
Y1155213D03*
X1361723Y1204617D03*
X1364038Y1198321D03*
Y1200821D03*
X1361723Y1212117D03*
Y1209617D03*
Y1207117D03*
X1357070Y1297498D03*
X1356904Y1345691D03*
Y1350683D03*
Y1357603D03*
Y1362595D03*
Y1381801D03*
Y1369889D03*
Y1374881D03*
Y1386793D03*
Y1394087D03*
Y1399079D03*
Y1410991D03*
Y1405999D03*
X1354834Y1465913D03*
Y1456451D03*
Y1461182D03*
X1363496Y1465513D03*
Y1460782D03*
X1354834Y1481267D03*
X1363496Y1476136D03*
Y1470244D03*
Y1480867D03*
X1354834Y1471805D03*
Y1476536D03*
Y1487159D03*
Y1496621D03*
X1363496Y1485598D03*
Y1491490D03*
Y1496221D03*
X1354834Y1491890D03*
Y1502514D03*
Y1511976D03*
X1363496Y1511576D03*
Y1506845D03*
Y1500952D03*
X1354834Y1507245D03*
X1363496Y1516307D03*
X1354834Y1558813D03*
Y1563544D03*
X1363496Y1563144D03*
Y1572606D03*
X1354834Y1568275D03*
Y1574167D03*
Y1578898D03*
X1363496Y1567875D03*
Y1578498D03*
X1354834Y1583629D03*
Y1589522D03*
Y1594253D03*
X1363496Y1583229D03*
Y1593853D03*
Y1587960D03*
X1354834Y1609607D03*
Y1604876D03*
Y1598984D03*
X1363496Y1609207D03*
Y1598584D03*
Y1603315D03*
X1354834Y1614338D03*
X1363496Y1613938D03*
Y1618669D03*
X1376262Y113394D03*
X1378911Y110784D03*
X1378505Y133298D03*
X1380652Y134579D03*
X1378227Y252371D03*
X1383556Y558338D03*
X1383184Y587653D03*
X1383425Y593575D03*
X1383556Y604838D03*
X1381118Y634033D03*
X1383425Y640075D03*
X1381244Y673623D03*
X1383425Y684140D03*
X1381932Y722547D03*
X1383425Y731575D03*
X1383046Y829871D03*
X1379896Y842470D03*
Y858218D03*
X1370447Y867665D03*
Y886562D03*
X1371379Y986717D03*
X1370384Y1004680D03*
X1376601Y1030218D03*
X1374451Y1090568D03*
Y1093068D03*
X1371477Y1098767D03*
X1375633Y1136935D03*
Y1134435D03*
Y1139435D03*
Y1131935D03*
X1383366D03*
Y1134435D03*
Y1136935D03*
Y1139435D03*
X1368933Y1125801D03*
X1371433D03*
X1368933Y1129301D03*
X1371433D03*
X1383024Y1152684D03*
X1376861D03*
X1375633Y1146935D03*
Y1144435D03*
Y1141935D03*
X1383366D03*
Y1146935D03*
Y1144435D03*
X1377390Y1244055D03*
Y1250760D03*
Y1254164D03*
X1372300Y1422900D03*
X1372157Y1461183D03*
Y1456452D03*
Y1465914D03*
Y1471806D03*
Y1476537D03*
Y1481268D03*
Y1487160D03*
Y1491891D03*
Y1496622D03*
Y1502515D03*
Y1507246D03*
Y1511977D03*
Y1558813D03*
Y1563544D03*
Y1568275D03*
Y1574167D03*
Y1578898D03*
Y1583629D03*
Y1589522D03*
Y1594253D03*
Y1604876D03*
Y1598984D03*
Y1609607D03*
Y1614338D03*
X1372000Y1644980D03*
X1391497Y109172D03*
X1394497D03*
X1393504Y106495D03*
X1397248Y116497D03*
X1386505Y133298D03*
X1397248Y130670D03*
Y123584D03*
X1393238Y146012D03*
X1395144Y141228D03*
X1397248Y137757D03*
X1398032Y150847D03*
X1400000Y247292D03*
X1392709Y253198D03*
X1391086Y577192D03*
X1400912Y581222D03*
Y591215D03*
X1391587Y627817D03*
X1388414Y675000D03*
X1388241Y722000D03*
X1396916Y862829D03*
X1395561Y876204D03*
X1396163Y868597D03*
X1398247Y926261D03*
X1390322Y1057998D03*
Y1055498D03*
X1392822D03*
Y1057998D03*
X1390322Y1060498D03*
Y1062998D03*
X1392822D03*
Y1060498D03*
X1399748Y1098518D03*
X1394496Y1098428D03*
X1388992Y1123101D03*
X1396992D03*
X1399492D03*
X1385866Y1131935D03*
Y1134435D03*
Y1136935D03*
Y1139435D03*
X1388992Y1125801D03*
X1397392D03*
X1399892D03*
X1387392Y1129301D03*
X1389892D03*
X1392392D03*
X1394892D03*
X1397392D03*
X1399892D03*
X1391856Y1155213D03*
Y1152713D03*
X1385866Y1141935D03*
Y1146935D03*
Y1144435D03*
X1393695Y1204405D03*
Y1206905D03*
Y1211905D03*
Y1209405D03*
X1385992Y1285466D03*
X1390492D03*
X1392000Y1644980D03*
X1409248Y109410D03*
Y102323D03*
X1404548Y116497D03*
X1402048D03*
X1404548Y109410D03*
X1409248Y116496D03*
X1402048Y130670D03*
Y123584D03*
X1404548Y123583D03*
X1409248Y130670D03*
Y123583D03*
X1404548Y130670D03*
X1409248Y137756D03*
X1402048Y137757D03*
X1408666Y324733D03*
X1411950Y448466D03*
X1408103Y555194D03*
X1410903D03*
X1408103Y563194D03*
X1410903D03*
X1408103Y571194D03*
X1410903D03*
X1406512Y581222D03*
X1403712D03*
Y591215D03*
X1406512D03*
X1405514Y611091D03*
X1405000Y656000D03*
Y699000D03*
X1404689Y910897D03*
X1413575Y915186D03*
X1413322Y958908D03*
X1404317Y989436D03*
X1411038Y985379D03*
X1404936Y1098767D03*
X1415494Y1139435D03*
Y1136935D03*
Y1134435D03*
Y1131935D03*
X1409092Y1136935D03*
Y1134435D03*
Y1139435D03*
Y1131935D03*
X1402392Y1125801D03*
X1404892D03*
X1402392Y1129301D03*
X1404892D03*
X1409092Y1141935D03*
X1416736Y1152713D03*
Y1155213D03*
X1402256D03*
Y1152713D03*
X1415494Y1144435D03*
Y1146935D03*
Y1141935D03*
X1409092Y1146935D03*
Y1144435D03*
X1407995Y1204617D03*
X1410310Y1200821D03*
Y1198321D03*
X1407995Y1207117D03*
Y1209617D03*
Y1212117D03*
X1415903Y1282590D03*
X1404019Y1285290D03*
X1414346Y1303020D03*
X1412000Y1644980D03*
X1417710Y82984D03*
Y75184D03*
Y77784D03*
Y80384D03*
X1420264Y92849D03*
X1417710Y85584D03*
X1427224Y103037D03*
X1427358Y116496D03*
Y109410D03*
Y130670D03*
Y123583D03*
X1423515Y137756D03*
X1429539Y293796D03*
X1432039D03*
X1431019Y434508D03*
X1427019D03*
X1424196Y446352D03*
X1428782Y445874D03*
X1417856Y455466D03*
X1433310Y504699D03*
X1430810D03*
X1433012Y516979D03*
X1430512D03*
X1427233Y628183D03*
X1424389Y627948D03*
X1426000Y709000D03*
Y713000D03*
Y757000D03*
Y753000D03*
X1422813Y910065D03*
X1424126Y900295D03*
X1427553Y939200D03*
X1427473Y965621D03*
X1420740Y1004766D03*
Y1000766D03*
Y1016266D03*
Y1030766D03*
X1420107Y1052514D03*
X1431876Y1098518D03*
X1426624Y1098428D03*
X1421120Y1123101D03*
X1429120D03*
X1431620D03*
X1422020Y1129301D03*
X1424520D03*
X1427020D03*
X1429520D03*
X1432020D03*
X1417994Y1139435D03*
Y1136935D03*
Y1134435D03*
Y1131935D03*
X1421120Y1125801D03*
X1429520D03*
X1432020D03*
X1419520Y1129301D03*
X1432384Y1155213D03*
Y1152713D03*
X1422984D03*
Y1155213D03*
X1417994Y1144435D03*
Y1146935D03*
Y1141935D03*
X1420625Y1204405D03*
Y1206905D03*
Y1209405D03*
X1425652Y1297411D03*
X1433386Y1343309D03*
X1428840Y1407740D03*
X1423065Y1508327D03*
X1432499Y1512175D03*
X1424245Y1543338D03*
X1425558Y1537432D03*
X1425260Y1558072D03*
X1433558Y1555366D03*
X1423701Y1563978D03*
X1432000Y1644980D03*
X1444641Y94017D03*
X1448641D03*
X1440641D03*
X1449761Y115401D03*
Y110445D03*
X1444769D03*
Y115401D03*
X1449761Y124618D03*
X1444769D03*
Y129574D03*
X1449761D03*
X1442682Y151540D03*
X1446332Y191941D03*
X1446199Y188727D03*
X1442956Y226141D03*
X1440156D03*
X1448026Y256535D03*
X1440053Y285690D03*
X1437553D03*
X1440053Y288190D03*
X1442853D03*
Y285690D03*
X1447079Y290755D03*
X1437553Y288190D03*
X1437758Y362584D03*
X1435019Y434508D03*
X1437757Y447201D03*
X1437879Y444269D03*
X1435810Y504699D03*
X1447036Y519518D03*
X1435512Y516979D03*
X1444536Y519518D03*
X1439536D03*
X1442036D03*
X1435241Y593796D03*
X1440930Y636005D03*
Y633205D03*
Y638805D03*
X1437784Y683532D03*
X1436567Y727532D03*
X1443000Y798500D03*
Y794500D03*
Y842500D03*
Y838500D03*
X1438188Y867633D03*
X1437703Y880067D03*
X1449072Y892581D03*
X1435288Y897500D03*
X1444453Y938806D03*
X1439449Y979009D03*
X1440610Y1021567D03*
X1435266Y1031522D03*
X1437064Y1098767D03*
X1441220Y1131935D03*
Y1139435D03*
Y1134435D03*
Y1136935D03*
X1434520Y1125801D03*
X1437020D03*
X1434520Y1129301D03*
X1437020D03*
X1441220Y1141935D03*
Y1144435D03*
Y1146935D03*
X1442448Y1152684D03*
X1434925Y1204617D03*
X1437240Y1200821D03*
Y1198321D03*
X1434925Y1207117D03*
Y1209617D03*
Y1212117D03*
X1436408Y1303462D03*
X1444438Y1308312D03*
X1439482D03*
X1441286Y1335776D03*
X1457718Y84140D03*
Y76140D03*
Y80140D03*
X1452650Y94017D03*
X1460163Y117557D03*
X1455171D03*
Y122513D03*
X1460163Y131731D03*
Y122513D03*
X1455171Y131731D03*
X1458262Y146461D03*
X1460163Y136687D03*
X1455171D03*
X1457164Y152367D03*
X1463547Y180527D03*
X1458864Y180572D03*
Y185165D03*
X1463502Y185121D03*
X1452832Y184619D03*
X1454812Y206760D03*
X1456026Y256535D03*
X1457056Y279208D03*
X1461160Y281307D03*
X1455079Y290755D03*
X1451079D03*
X1458982Y356861D03*
X1453000Y633450D03*
Y636250D03*
Y639050D03*
X1453032Y769032D03*
X1453775Y813032D03*
X1461241Y867475D03*
X1462694Y874859D03*
Y877859D03*
X1460472Y885985D03*
X1459420Y899226D03*
X1451005Y931848D03*
X1462819Y949996D03*
X1462000Y960378D03*
X1460655Y964253D03*
X1466076Y979746D03*
X1462388Y1006560D03*
X1455939Y1018368D03*
X1465503Y1030233D03*
X1460592Y1345691D03*
Y1350683D03*
X1465548Y1345691D03*
Y1350683D03*
X1460592Y1357603D03*
Y1362595D03*
X1465548Y1357603D03*
Y1362595D03*
X1460592Y1381801D03*
Y1374881D03*
Y1369889D03*
X1465548Y1381801D03*
Y1374881D03*
Y1369889D03*
X1460592Y1386793D03*
X1465548D03*
X1452000Y1644980D03*
X1480460Y60922D03*
X1475296Y55513D03*
X1471093Y117261D03*
X1478624Y113394D03*
X1481273Y110784D03*
X1481368Y130898D03*
X1478800Y180665D03*
Y172665D03*
X1467270Y192421D03*
X1478832Y200864D03*
Y212864D03*
Y216864D03*
Y221864D03*
X1480589Y252371D03*
X1473900Y433100D03*
X1478710Y685630D03*
X1473525Y710052D03*
X1474425Y716075D03*
X1479962Y727500D03*
X1471415Y748629D03*
X1474425Y760075D03*
X1473634Y864337D03*
X1481454Y911570D03*
X1474075Y920575D03*
X1474349Y949394D03*
X1468500Y974181D03*
X1479096Y997860D03*
X1471096D03*
X1475096D03*
X1467096D03*
X1471854Y1035088D03*
X1479624Y1035102D03*
X1468371Y1030701D03*
X1480193Y1102091D03*
X1474384D03*
X1480193Y1114691D03*
X1474384D03*
X1480193Y1127291D03*
X1474384D03*
X1480193Y1139891D03*
X1474384D03*
X1480193Y1152491D03*
X1474384D03*
X1480193Y1165091D03*
X1474384D03*
X1480193Y1177691D03*
X1474384D03*
X1480675Y1202103D03*
X1477788Y1350683D03*
Y1345691D03*
X1472832Y1350683D03*
Y1345691D03*
X1477788Y1357603D03*
Y1362595D03*
X1472832Y1357603D03*
Y1362595D03*
X1477788Y1381801D03*
Y1369795D03*
Y1374881D03*
X1472832Y1381801D03*
Y1369795D03*
Y1374881D03*
X1477788Y1386793D03*
Y1399079D03*
Y1393993D03*
X1472832Y1386793D03*
Y1393993D03*
Y1399079D03*
X1477788Y1405999D03*
Y1410991D03*
X1472832Y1405999D03*
Y1410991D03*
X1476094Y1465913D03*
Y1461182D03*
Y1456451D03*
Y1471805D03*
Y1481267D03*
Y1476536D03*
Y1491890D03*
Y1487159D03*
Y1496621D03*
Y1502514D03*
Y1511976D03*
Y1507245D03*
Y1563544D03*
Y1558813D03*
Y1568275D03*
Y1578898D03*
Y1574167D03*
Y1583629D03*
Y1594253D03*
Y1589522D03*
Y1609607D03*
Y1598984D03*
Y1604876D03*
Y1614338D03*
X1472000Y1644980D03*
X1493859Y109172D03*
X1496859D03*
X1495866Y106495D03*
X1488867Y133298D03*
X1495600Y146012D03*
X1497506Y141228D03*
X1483014Y134579D03*
X1495071Y253198D03*
X1486360Y358700D03*
Y354200D03*
X1496473Y769000D03*
X1491062Y793003D03*
X1491425Y801575D03*
X1496845Y813000D03*
X1491425Y845575D03*
X1489650Y836985D03*
X1489805Y866386D03*
X1497488Y873839D03*
X1491414Y875383D03*
X1494000Y884000D03*
X1498084Y894825D03*
X1492101Y894860D03*
X1496383Y898023D03*
X1496500Y919000D03*
X1496000Y922000D03*
X1487075Y920925D03*
X1485100Y943900D03*
X1496425Y943075D03*
X1496072Y950044D03*
X1482591Y961909D03*
X1486500Y947000D03*
X1485226Y973886D03*
X1492560Y974654D03*
X1495339Y1009354D03*
X1491839D03*
X1486030D03*
X1491096Y997860D03*
X1483096D03*
X1495096D03*
X1487096D03*
X1495339Y1021954D03*
X1491839D03*
X1486030D03*
X1483693Y1102091D03*
Y1114691D03*
Y1127291D03*
Y1139891D03*
Y1152491D03*
Y1165091D03*
Y1177691D03*
X1498197Y1209607D03*
X1492471Y1215195D03*
X1484055Y1223749D03*
X1497312Y1350683D03*
Y1345691D03*
X1485072D03*
Y1350683D03*
X1490028Y1345691D03*
Y1350683D03*
X1497312Y1357603D03*
Y1362595D03*
X1485072D03*
Y1357603D03*
X1490028D03*
Y1362595D03*
X1485072Y1369889D03*
Y1374881D03*
Y1381801D03*
X1490028Y1369889D03*
Y1374881D03*
Y1381801D03*
X1497312D03*
Y1374881D03*
Y1369889D03*
Y1386793D03*
Y1394087D03*
Y1399079D03*
X1485072Y1394087D03*
Y1399079D03*
Y1386793D03*
X1490028Y1399079D03*
Y1394087D03*
Y1386793D03*
X1497312Y1405999D03*
Y1410991D03*
X1485072Y1405999D03*
Y1410991D03*
X1490028Y1405999D03*
Y1410991D03*
X1484755Y1465513D03*
Y1460782D03*
X1493417Y1465913D03*
Y1456451D03*
Y1461182D03*
Y1471805D03*
Y1476536D03*
Y1481267D03*
X1484755Y1476136D03*
Y1470244D03*
Y1480867D03*
Y1496221D03*
X1493417Y1487159D03*
Y1491890D03*
Y1496621D03*
X1484755Y1491490D03*
Y1485598D03*
Y1506845D03*
Y1500952D03*
Y1511576D03*
X1493417Y1507245D03*
Y1502514D03*
Y1511976D03*
X1484755Y1516307D03*
Y1563144D03*
X1493417Y1558813D03*
Y1563544D03*
Y1578898D03*
X1484755Y1567875D03*
Y1578498D03*
Y1572606D03*
X1493417Y1568275D03*
Y1574167D03*
X1484755Y1583229D03*
Y1593853D03*
Y1587960D03*
X1493417Y1583629D03*
Y1589522D03*
Y1594253D03*
X1484755Y1609207D03*
Y1598584D03*
Y1603315D03*
X1493417Y1609607D03*
Y1604876D03*
Y1598984D03*
X1484755Y1613938D03*
Y1618669D03*
X1493417Y1614338D03*
X1492000Y1644980D03*
X1511610Y116496D03*
Y109410D03*
Y102323D03*
X1499610Y116497D03*
X1506910D03*
X1504410D03*
X1506910Y109410D03*
X1511610Y123583D03*
X1499610Y130670D03*
Y123584D03*
X1506910Y130670D03*
X1504410D03*
Y123584D03*
X1506910Y123583D03*
X1511610Y130670D03*
Y137756D03*
X1499610Y137757D03*
X1504410D03*
X1500394Y150847D03*
X1502362Y247292D03*
X1501807Y323766D03*
X1507864Y450750D03*
X1511963Y536382D03*
X1510280Y899732D03*
X1514354Y938811D03*
X1510500Y931500D03*
X1513955Y950396D03*
X1505888Y965964D03*
X1514000Y968739D03*
X1510740Y973740D03*
X1507096Y997860D03*
X1503096D03*
X1511096D03*
X1499096D03*
X1505130Y1105091D03*
Y1117691D03*
Y1130291D03*
Y1142891D03*
Y1155491D03*
Y1168091D03*
Y1180691D03*
X1509552Y1350683D03*
Y1345691D03*
X1514508Y1350683D03*
Y1345691D03*
X1502268Y1350683D03*
Y1345691D03*
X1509552Y1362595D03*
Y1357603D03*
X1514508D03*
Y1362595D03*
X1502268Y1357603D03*
Y1362595D03*
X1509552Y1374881D03*
Y1369889D03*
Y1381801D03*
X1514508Y1374881D03*
Y1369889D03*
Y1381801D03*
X1502268D03*
Y1374881D03*
Y1369889D03*
X1509552Y1394087D03*
Y1399079D03*
Y1386793D03*
X1514508Y1394087D03*
Y1399079D03*
Y1386793D03*
X1502268D03*
Y1399079D03*
Y1394087D03*
X1509552Y1405999D03*
Y1410991D03*
X1514508Y1405999D03*
Y1410991D03*
X1502268Y1405999D03*
Y1410991D03*
X1502078Y1465513D03*
Y1460782D03*
X1510740Y1465913D03*
Y1456451D03*
Y1461182D03*
X1502078Y1470244D03*
Y1480867D03*
X1510740Y1471805D03*
Y1476536D03*
Y1481267D03*
X1502078Y1476136D03*
Y1491490D03*
Y1485598D03*
Y1496221D03*
X1510740Y1487159D03*
Y1491890D03*
Y1496621D03*
Y1507245D03*
Y1502514D03*
Y1511976D03*
X1502078Y1506845D03*
Y1500952D03*
Y1511576D03*
Y1516307D03*
X1510740Y1563544D03*
X1502078Y1563144D03*
X1510740Y1558813D03*
Y1578898D03*
X1502078Y1567875D03*
Y1578498D03*
Y1572606D03*
X1510740Y1568275D03*
Y1574167D03*
X1502078Y1583229D03*
Y1593853D03*
Y1587960D03*
X1510740Y1583629D03*
Y1589522D03*
Y1594253D03*
X1502078Y1609207D03*
Y1598584D03*
Y1603315D03*
X1510740Y1609607D03*
Y1604876D03*
Y1598984D03*
X1502078Y1613938D03*
Y1618669D03*
X1510740Y1614338D03*
X1512000Y1644980D03*
X1520072Y82984D03*
Y75184D03*
Y77784D03*
Y80384D03*
X1522626Y92849D03*
X1520072Y85584D03*
X1529586Y103037D03*
X1529720Y116496D03*
Y109410D03*
Y130670D03*
Y123583D03*
X1526311Y137756D03*
X1528635Y555234D03*
X1528350Y562003D03*
X1519156Y596095D03*
X1516869Y594668D03*
X1518354Y592354D03*
X1518415Y589556D03*
X1519153Y599588D03*
X1516930Y597580D03*
X1519185Y615600D03*
X1519153Y607588D03*
X1523646Y634946D03*
X1519063Y876339D03*
X1517344Y896999D03*
X1515743Y888133D03*
X1517344Y903179D03*
X1517153Y908367D03*
X1523000Y923740D03*
X1526611Y921442D03*
X1525740Y928740D03*
X1528087Y936394D03*
X1524500Y949500D03*
X1530174Y956986D03*
X1525522Y971075D03*
X1523966Y980281D03*
X1515096Y997860D03*
X1531096D03*
X1519096D03*
X1523096D03*
X1516776Y1024954D03*
Y1012354D03*
X1526748Y1345691D03*
Y1350683D03*
X1521792Y1345691D03*
Y1350683D03*
X1526748Y1357603D03*
Y1362595D03*
X1521792Y1357603D03*
Y1362595D03*
X1526748Y1369889D03*
Y1374881D03*
Y1381801D03*
X1521792Y1374881D03*
Y1381801D03*
Y1369889D03*
X1526748Y1386793D03*
Y1399079D03*
Y1394087D03*
X1521792Y1386793D03*
Y1394087D03*
Y1399079D03*
X1526748Y1405999D03*
Y1410991D03*
X1521792Y1405999D03*
Y1410991D03*
X1519401Y1465513D03*
Y1460782D03*
X1528062Y1465913D03*
Y1456451D03*
Y1461182D03*
Y1481267D03*
X1519401Y1476136D03*
Y1470244D03*
Y1480867D03*
X1528062Y1471805D03*
Y1476536D03*
X1519401Y1491490D03*
Y1485598D03*
Y1496221D03*
X1528062Y1487159D03*
Y1491890D03*
Y1496621D03*
X1519401Y1506845D03*
Y1500952D03*
Y1511576D03*
X1528062Y1507245D03*
Y1502514D03*
Y1511976D03*
X1519401Y1516307D03*
Y1563144D03*
X1528062Y1558813D03*
Y1563544D03*
Y1578898D03*
X1519401Y1567875D03*
Y1578498D03*
Y1572606D03*
X1528062Y1568275D03*
Y1574167D03*
X1519401Y1587960D03*
X1528062Y1583629D03*
Y1589522D03*
Y1594253D03*
X1519401Y1583229D03*
Y1593853D03*
Y1609207D03*
Y1598584D03*
Y1603315D03*
X1528062Y1609607D03*
Y1604876D03*
Y1598984D03*
X1519401Y1613938D03*
Y1618669D03*
X1528062Y1614338D03*
X1547003Y94017D03*
X1543003D03*
X1547131Y110445D03*
Y115401D03*
Y129574D03*
Y124618D03*
X1545044Y151540D03*
X1548561Y188727D03*
X1542518Y226141D03*
X1545318D03*
X1531901Y293796D03*
X1539915Y288190D03*
X1542415Y285690D03*
X1539915D03*
X1542415Y288190D03*
X1545215D03*
Y285690D03*
X1534401Y293796D03*
X1541283Y354553D03*
X1546272Y1350683D03*
Y1345691D03*
X1534032Y1350683D03*
Y1345691D03*
X1538988D03*
Y1350683D03*
X1546272Y1357603D03*
Y1362595D03*
X1534032Y1357603D03*
Y1362595D03*
X1538988D03*
Y1357603D03*
X1546272Y1374881D03*
Y1369889D03*
Y1381801D03*
X1534032Y1369889D03*
Y1381801D03*
Y1374881D03*
X1538988Y1369889D03*
Y1381801D03*
Y1374881D03*
X1546272Y1386793D03*
Y1394087D03*
Y1399079D03*
X1534032Y1394087D03*
Y1399079D03*
Y1386793D03*
X1538988Y1394087D03*
Y1399079D03*
Y1386793D03*
X1546272Y1405999D03*
Y1410991D03*
X1534032Y1405999D03*
Y1410991D03*
X1538988Y1405999D03*
Y1410991D03*
X1545385Y1461183D03*
X1536724Y1465513D03*
Y1460782D03*
X1545385Y1465914D03*
Y1456452D03*
X1536724Y1476136D03*
Y1470244D03*
Y1480867D03*
X1545385Y1476537D03*
Y1471806D03*
Y1481268D03*
X1536724Y1491490D03*
Y1485598D03*
Y1496221D03*
X1545385Y1491891D03*
Y1487160D03*
Y1496622D03*
X1536724Y1506845D03*
Y1500952D03*
Y1511576D03*
X1545385Y1507246D03*
Y1502515D03*
Y1511977D03*
X1536724Y1516307D03*
X1545385Y1563544D03*
Y1558813D03*
X1536724Y1563144D03*
Y1567875D03*
X1545385Y1568275D03*
X1536724Y1578498D03*
Y1572606D03*
X1545385Y1578898D03*
Y1574167D03*
Y1594253D03*
Y1589522D03*
X1536724Y1583229D03*
X1545385Y1583629D03*
X1536724Y1593853D03*
Y1587960D03*
Y1609207D03*
Y1598584D03*
Y1603315D03*
X1545385Y1609607D03*
Y1598984D03*
Y1604876D03*
Y1614338D03*
X1536724Y1613938D03*
Y1618669D03*
X1532000Y1644980D03*
X1560080Y84140D03*
Y76140D03*
Y80140D03*
X1555012Y94017D03*
X1551003D03*
X1562525Y117557D03*
X1557533D03*
X1552123Y115401D03*
Y110445D03*
X1562525Y122513D03*
X1552123Y129574D03*
Y124618D03*
X1557533Y131731D03*
Y122513D03*
X1562525Y131731D03*
X1560624Y146461D03*
X1557533Y136687D03*
X1562525D03*
X1559526Y152367D03*
X1561226Y180572D03*
X1548694Y191941D03*
X1555194Y184619D03*
X1561226Y185165D03*
X1557174Y206760D03*
X1550388Y256535D03*
X1558388D03*
X1559418Y279208D03*
X1563522Y281307D03*
X1549441Y290755D03*
X1553441D03*
X1557441D03*
X1554403Y352363D03*
X1563248Y389154D03*
X1548629D03*
Y403327D03*
Y410413D03*
X1561778Y396240D03*
X1548629D03*
Y417500D03*
Y424587D03*
Y438760D03*
Y431673D03*
Y445847D03*
Y467539D03*
Y474626D03*
Y488799D03*
Y481713D03*
Y495886D03*
Y511673D03*
Y518760D03*
X1562089Y516841D03*
X1548629Y540020D03*
Y525847D03*
Y532933D03*
Y547106D03*
X1556914Y552872D03*
X1557036Y550123D03*
X1556359Y562443D03*
X1558668Y572334D03*
X1558127Y560675D03*
X1556900Y574102D03*
X1547910Y602197D03*
X1548374Y595108D03*
X1561535Y653161D03*
X1565132Y677843D03*
X1547813Y906581D03*
X1551099Y959096D03*
X1558512Y1345691D03*
Y1350683D03*
X1563468D03*
Y1345691D03*
X1551228Y1350683D03*
Y1345691D03*
X1563468Y1362595D03*
X1551228Y1357603D03*
Y1362595D03*
X1558512D03*
Y1357603D03*
X1563468D03*
X1558512Y1374881D03*
Y1369889D03*
Y1381801D03*
X1563468Y1374881D03*
Y1369889D03*
Y1381801D03*
X1551228Y1369889D03*
Y1381801D03*
Y1374881D03*
X1558512Y1399079D03*
Y1394087D03*
Y1386793D03*
X1563468Y1399079D03*
Y1394087D03*
Y1386793D03*
X1551228D03*
Y1394087D03*
Y1399079D03*
X1558512Y1405999D03*
Y1410991D03*
X1563468Y1405999D03*
Y1410991D03*
X1551228Y1405999D03*
Y1410991D03*
X1552000Y1644980D03*
X1576256Y-25273D03*
X1573003Y-25287D03*
X1576241Y-27788D03*
X1572988Y-27802D03*
X1579281Y-26693D03*
X1573455Y117261D03*
X1565909Y180527D03*
X1569632Y192421D03*
X1565864Y185121D03*
X1571625Y333549D03*
X1579340Y396240D03*
Y403327D03*
Y410413D03*
X1566555Y414823D03*
X1565863Y422864D03*
X1579340Y417500D03*
Y424586D03*
X1565933Y429832D03*
X1565538Y436447D03*
X1579340Y431673D03*
Y438760D03*
X1567573Y447953D03*
X1579340Y445847D03*
X1566740Y467539D03*
X1565482Y472772D03*
X1579340Y474626D03*
Y488799D03*
X1566216Y487711D03*
X1566329Y479104D03*
X1579340Y481712D03*
Y495886D03*
X1566740D03*
X1579340Y518760D03*
X1565050Y511673D03*
X1579340Y540020D03*
Y532933D03*
Y525846D03*
X1574222Y629872D03*
X1569926Y668885D03*
X1575950Y662981D03*
X1570331Y691851D03*
X1575942Y705043D03*
X1575708Y1345597D03*
X1570752Y1350683D03*
Y1345597D03*
X1575708Y1350683D03*
X1570752Y1357603D03*
Y1362595D03*
X1575708D03*
Y1357603D03*
Y1381801D03*
Y1374881D03*
Y1369889D03*
X1570752D03*
Y1381801D03*
Y1374881D03*
X1575708Y1386793D03*
Y1399079D03*
Y1393993D03*
X1570752Y1386793D03*
Y1393993D03*
Y1399079D03*
X1575708Y1405999D03*
Y1410991D03*
X1570752Y1405999D03*
Y1410991D03*
X1572000Y1644980D03*
X1586256Y-64207D03*
X1583003D03*
X1586241Y-66722D03*
X1582988D03*
X1589281Y-65613D03*
X1582822Y60922D03*
X1580327Y57448D03*
X1580986Y113394D03*
X1583635Y110784D03*
X1591229Y133298D03*
X1583229D03*
X1585376Y134579D03*
X1581162Y180665D03*
Y172665D03*
X1581194Y212864D03*
Y200864D03*
Y221864D03*
Y216864D03*
X1582951Y252371D03*
X1586640Y389153D03*
X1581840D03*
Y403326D03*
Y410413D03*
X1586640D03*
X1581840Y396240D03*
X1586640D03*
Y403326D03*
Y417499D03*
X1581840D03*
Y424586D03*
X1586640D03*
X1581840Y438760D03*
X1586640D03*
Y431673D03*
X1581840D03*
X1586640Y467539D03*
X1581840D03*
Y474626D03*
X1586640D03*
X1581840Y488799D03*
X1586640D03*
X1581840Y481712D03*
X1586640D03*
X1581840Y518760D03*
Y511673D03*
X1586640D03*
Y518760D03*
Y525846D03*
Y532933D03*
X1581840D03*
Y525846D03*
X1595185Y543925D03*
X1595760Y555000D03*
X1583720Y560500D03*
X1587948Y1350683D03*
Y1345691D03*
X1582992D03*
Y1350683D03*
X1587948Y1362595D03*
Y1357603D03*
X1582992Y1362595D03*
Y1357603D03*
Y1369889D03*
Y1381801D03*
Y1374881D03*
X1587948Y1369889D03*
Y1381801D03*
Y1374881D03*
X1582992Y1399079D03*
Y1394087D03*
Y1386793D03*
X1587948Y1399079D03*
Y1394087D03*
Y1386793D03*
X1582992Y1405999D03*
Y1410991D03*
X1587948Y1405999D03*
Y1410991D03*
X1592020Y1433061D03*
X1591610Y1469940D03*
X1591586Y1505130D03*
X1609272Y109410D03*
X1601972Y116497D03*
X1609272D03*
X1606772D03*
X1596221Y109172D03*
X1599221D03*
X1598228Y106495D03*
X1601972Y123584D03*
Y130670D03*
X1606772Y123584D03*
X1609272Y123583D03*
Y130670D03*
X1606772D03*
Y137757D03*
X1597962Y146012D03*
X1599868Y141228D03*
X1601972Y137757D03*
X1602756Y150847D03*
X1604724Y247292D03*
X1597433Y253198D03*
X1608240Y329000D03*
X1603664Y342596D03*
X1598223Y351003D03*
X1599127Y375587D03*
X1596714Y383003D03*
X1614338Y636842D03*
X1610620Y1345691D03*
Y1350683D03*
Y1357603D03*
Y1362595D03*
Y1381801D03*
Y1374881D03*
Y1369889D03*
Y1386793D03*
X1597225Y1437014D03*
X1603363Y1460570D03*
X1597457Y1452556D03*
X1598500Y1472500D03*
X1606745Y1474242D03*
X1602580Y1483108D03*
X1598000Y1486000D03*
X1604000Y1516000D03*
X1600700Y1534300D03*
X1622434Y82984D03*
Y80384D03*
Y75184D03*
Y77784D03*
X1624988Y92849D03*
X1622434Y85584D03*
X1613972Y116496D03*
Y102323D03*
Y109410D03*
Y130670D03*
Y123583D03*
Y137756D03*
X1625952Y431029D03*
X1626260Y427017D03*
X1625018Y435029D03*
X1625938Y449873D03*
X1625565Y472579D03*
Y479666D03*
Y486752D03*
Y493839D03*
Y523800D03*
Y516713D03*
Y537973D03*
Y530886D03*
Y566752D03*
Y588013D03*
Y573839D03*
Y580926D03*
Y602186D03*
Y595099D03*
Y609272D03*
Y616359D03*
X1620244Y638125D03*
X1617843Y665140D03*
X1613110Y678462D03*
X1624148Y708258D03*
X1627455Y759489D03*
X1619612Y783152D03*
X1620359Y774830D03*
X1619569Y796035D03*
X1620755Y787530D03*
X1613235Y808466D03*
X1620479Y815730D03*
X1620072Y801630D03*
X1616255Y824405D03*
X1619859Y839519D03*
X1615576Y1345691D03*
Y1350683D03*
X1622860D03*
Y1345691D03*
X1627816Y1350683D03*
Y1345691D03*
X1615576Y1357603D03*
Y1362595D03*
X1622860Y1357603D03*
Y1362595D03*
X1627816Y1357603D03*
Y1362595D03*
X1622860Y1381801D03*
Y1369795D03*
Y1374881D03*
X1627816Y1381801D03*
Y1369795D03*
Y1374881D03*
X1615576Y1381801D03*
Y1374881D03*
Y1369889D03*
Y1386793D03*
X1622860D03*
Y1393993D03*
Y1399079D03*
X1627816Y1386793D03*
Y1399079D03*
Y1393993D03*
X1622860Y1405999D03*
Y1410991D03*
X1627816Y1405999D03*
Y1410991D03*
X1618800Y1528558D03*
X1614200Y1519500D03*
X1614360Y1542860D03*
X1618600Y1532000D03*
X1631948Y103037D03*
X1632082Y116496D03*
Y109410D03*
Y130670D03*
Y123583D03*
X1628673Y137756D03*
X1644880Y226141D03*
X1644777Y288190D03*
X1642277Y285690D03*
X1644777D03*
X1642277Y288190D03*
X1636763Y293796D03*
X1634263D03*
X1635987Y335616D03*
X1630703Y350655D03*
X1636468Y345595D03*
X1636271Y410394D03*
Y403307D03*
X1637665Y458406D03*
Y451319D03*
X1637489Y462264D03*
X1632865Y465492D03*
X1637665D03*
Y472579D03*
X1632865D03*
X1630365D03*
Y479666D03*
X1632865D03*
X1637665Y479665D03*
Y486752D03*
X1630365D03*
X1632865D03*
X1630365Y493839D03*
X1637665D03*
X1632865Y509626D03*
Y516713D03*
X1630365D03*
Y523800D03*
X1632865D03*
X1637665Y523799D03*
Y516713D03*
Y509626D03*
X1630365Y530886D03*
X1637665D03*
X1632865D03*
X1637665Y537973D03*
X1630365D03*
X1637665Y559665D03*
Y566752D03*
X1630365D03*
X1632865D03*
Y559665D03*
Y573839D03*
X1630365Y580926D03*
X1632865D03*
X1637665D03*
Y588012D03*
X1630365Y588013D03*
X1632865Y588012D03*
X1637665Y573839D03*
X1630365D03*
X1632865Y602185D03*
X1630365Y602186D03*
X1637665Y602185D03*
Y595099D03*
X1632865D03*
X1630365D03*
Y616359D03*
X1632865Y609272D03*
X1630365D03*
X1637665Y616358D03*
Y609272D03*
X1637526Y699930D03*
X1637472Y717830D03*
X1631031Y732430D03*
X1628813Y727045D03*
X1631187Y750630D03*
X1629969Y740826D03*
X1644304Y891353D03*
X1640056Y1345691D03*
Y1350683D03*
X1635100Y1345691D03*
Y1350683D03*
X1640056Y1357603D03*
Y1362595D03*
X1635100D03*
Y1357603D03*
X1640056Y1369889D03*
Y1374881D03*
Y1381801D03*
X1635100Y1369889D03*
Y1374881D03*
Y1381801D03*
X1640056Y1399079D03*
Y1394087D03*
Y1386793D03*
X1635100Y1394087D03*
Y1399079D03*
Y1386793D03*
Y1405999D03*
Y1410991D03*
X1640056Y1405999D03*
Y1410991D03*
X1649365Y94017D03*
X1657374D03*
X1653365D03*
X1645365D03*
X1659895Y117557D03*
X1654485Y110445D03*
Y115401D03*
X1649493Y110445D03*
Y115401D03*
X1659895Y122513D03*
Y131731D03*
X1654485Y124618D03*
Y129574D03*
X1649493Y124618D03*
Y129574D03*
X1659895Y136687D03*
X1647406Y151540D03*
X1651056Y191941D03*
X1657556Y184619D03*
X1650923Y188727D03*
X1659536Y206760D03*
X1647680Y226141D03*
X1660750Y256535D03*
X1652750D03*
X1647577Y285690D03*
Y288190D03*
X1655803Y290755D03*
X1651803D03*
X1659803D03*
X1645685Y390500D03*
X1655335Y381500D03*
X1653507Y470136D03*
X1655776Y465492D03*
X1655742Y460250D03*
X1655776Y472579D03*
Y486752D03*
Y479665D03*
Y493839D03*
Y509626D03*
Y516713D03*
X1652236Y537973D03*
X1654716Y525483D03*
X1654637Y532756D03*
X1655776Y559665D03*
Y566752D03*
X1655626Y579978D03*
X1655776Y573839D03*
X1655840Y608117D03*
X1654572Y771702D03*
X1645128Y929263D03*
X1645342Y962120D03*
X1657091Y990823D03*
X1649571Y983857D03*
X1647340Y1350683D03*
Y1345691D03*
X1652296Y1350683D03*
Y1345691D03*
X1659580Y1350683D03*
Y1345691D03*
X1647340Y1357603D03*
Y1362595D03*
X1652296Y1357603D03*
Y1362595D03*
X1659580D03*
Y1357603D03*
X1647340Y1381801D03*
Y1374881D03*
Y1369889D03*
X1652296Y1381801D03*
Y1374881D03*
Y1369889D03*
X1659580Y1374881D03*
Y1369889D03*
Y1381801D03*
X1647340Y1386793D03*
Y1394087D03*
Y1399079D03*
X1652296Y1386793D03*
Y1399079D03*
Y1394087D03*
X1659580D03*
Y1399079D03*
Y1386793D03*
X1647340Y1405999D03*
Y1410991D03*
X1652296Y1405999D03*
Y1410991D03*
X1659580Y1405999D03*
Y1410991D03*
X1657983Y1460782D03*
X1649322Y1456451D03*
Y1465913D03*
X1657983Y1465513D03*
X1649322Y1461182D03*
Y1476536D03*
X1657983Y1476136D03*
Y1470244D03*
X1649322Y1471805D03*
Y1481267D03*
X1657983Y1480867D03*
X1649322Y1487159D03*
Y1496621D03*
X1657983Y1496221D03*
X1649322Y1491890D03*
X1657983Y1491490D03*
Y1485598D03*
Y1500952D03*
X1649322Y1502514D03*
X1657983Y1511576D03*
X1649322Y1511976D03*
Y1507245D03*
X1657983Y1506845D03*
Y1516307D03*
X1649322Y1558813D03*
Y1563544D03*
X1657983Y1563144D03*
Y1572606D03*
X1649322Y1574167D03*
Y1568275D03*
X1657983Y1567875D03*
X1649322Y1578898D03*
X1657983Y1578498D03*
X1649322Y1583629D03*
X1657983Y1583229D03*
X1649322Y1594253D03*
X1657983Y1593853D03*
Y1587960D03*
X1649322Y1589522D03*
Y1609607D03*
X1657983Y1609207D03*
X1649322Y1598984D03*
X1657983Y1598584D03*
Y1603315D03*
X1649322Y1604876D03*
Y1614338D03*
X1657983Y1613938D03*
Y1618669D03*
X1652000Y1644980D03*
X1662442Y84140D03*
Y76140D03*
Y80140D03*
X1675817Y117261D03*
X1664887Y117557D03*
Y122513D03*
Y131731D03*
X1662986Y146461D03*
X1664887Y136687D03*
X1661888Y152367D03*
X1663588Y180572D03*
X1668271Y180527D03*
X1671994Y192421D03*
X1663588Y185165D03*
X1668226Y185121D03*
X1661780Y279208D03*
X1665884Y281307D03*
X1669767Y445908D03*
X1673717Y445787D03*
X1664536Y1350683D03*
Y1345691D03*
X1671820D03*
Y1350683D03*
X1676776Y1345691D03*
Y1350683D03*
X1664536Y1357603D03*
Y1362595D03*
X1671820Y1357603D03*
Y1362595D03*
X1676776Y1357603D03*
Y1362595D03*
X1664536Y1374881D03*
Y1369889D03*
Y1381801D03*
X1671820Y1374881D03*
Y1381801D03*
Y1369889D03*
X1676776D03*
Y1374881D03*
Y1381801D03*
X1664536Y1394087D03*
Y1399079D03*
Y1386793D03*
X1671820D03*
Y1394087D03*
Y1399079D03*
X1676776Y1386793D03*
Y1399079D03*
Y1394087D03*
X1664536Y1405999D03*
Y1410991D03*
X1671820Y1405999D03*
Y1410991D03*
X1676776Y1405999D03*
Y1410991D03*
X1666645Y1465913D03*
Y1456451D03*
Y1461182D03*
X1675306Y1465513D03*
Y1460782D03*
X1666645Y1471805D03*
Y1476536D03*
Y1481267D03*
X1675306Y1476136D03*
Y1470244D03*
Y1480867D03*
X1666645Y1487159D03*
Y1491890D03*
Y1496621D03*
X1675306Y1491490D03*
Y1485598D03*
Y1496221D03*
Y1511576D03*
X1666645Y1511976D03*
Y1507245D03*
Y1502514D03*
X1675306Y1506845D03*
Y1500952D03*
Y1516307D03*
X1666645Y1558813D03*
Y1563544D03*
X1675306Y1563144D03*
Y1578498D03*
Y1572606D03*
X1666645Y1568275D03*
X1675306Y1567875D03*
X1666645Y1574167D03*
Y1578898D03*
Y1583629D03*
X1675306Y1583229D03*
X1666645Y1589522D03*
Y1594253D03*
X1675306Y1593853D03*
Y1587960D03*
X1666645Y1604876D03*
Y1598984D03*
X1675306Y1609207D03*
Y1598584D03*
Y1603315D03*
X1666645Y1609607D03*
Y1614338D03*
X1675306Y1613938D03*
Y1618669D03*
X1672000Y1644980D03*
X1685184Y60922D03*
X1680020Y55513D03*
X1683348Y113394D03*
X1685997Y110784D03*
X1686171Y130898D03*
X1693591Y133298D03*
X1687738Y134579D03*
X1683524Y172665D03*
Y180665D03*
X1683556Y200864D03*
Y212864D03*
Y221864D03*
Y216864D03*
X1685313Y252371D03*
X1687164Y336324D03*
X1678072Y342319D03*
X1691743Y353506D03*
X1680518Y385912D03*
Y393924D03*
Y389912D03*
Y409924D03*
Y405924D03*
Y401924D03*
X1677933Y418838D03*
X1689016Y1345691D03*
Y1350683D03*
X1684060D03*
Y1345691D03*
X1689016Y1362595D03*
Y1357603D03*
X1684060D03*
Y1362595D03*
X1689016Y1369889D03*
Y1381801D03*
Y1374881D03*
X1684060Y1369889D03*
Y1381801D03*
Y1374881D03*
X1689016Y1394087D03*
Y1399079D03*
Y1386793D03*
X1684060Y1394087D03*
Y1399079D03*
Y1386793D03*
X1689016Y1405999D03*
Y1410991D03*
X1684060Y1405999D03*
Y1410991D03*
X1683968Y1465913D03*
Y1456451D03*
Y1461182D03*
X1692629Y1465513D03*
Y1460782D03*
X1683968Y1471805D03*
Y1476536D03*
Y1481267D03*
X1692629Y1476136D03*
Y1470244D03*
Y1480867D03*
X1683968Y1487159D03*
Y1491890D03*
Y1496621D03*
X1692629Y1491490D03*
Y1485598D03*
Y1496221D03*
X1683968Y1502514D03*
Y1511976D03*
X1692629Y1506845D03*
Y1500952D03*
Y1511576D03*
X1683968Y1507245D03*
X1692629Y1516307D03*
X1683968Y1558813D03*
Y1563544D03*
X1692629Y1563144D03*
Y1572606D03*
X1683968Y1568275D03*
Y1574167D03*
Y1578898D03*
X1692629Y1567875D03*
Y1578498D03*
X1683968Y1583629D03*
Y1589522D03*
Y1594253D03*
X1692629Y1583229D03*
Y1593853D03*
Y1587960D03*
X1683968Y1598984D03*
X1692629Y1609207D03*
Y1598584D03*
Y1603315D03*
X1683968Y1609607D03*
Y1604876D03*
Y1614338D03*
X1692629Y1613938D03*
Y1618669D03*
X1692000Y1644980D03*
X1698583Y109172D03*
X1701583D03*
X1700590Y106495D03*
X1709134Y116497D03*
X1704334D03*
X1709134Y123584D03*
Y130670D03*
X1704334Y123584D03*
Y130670D03*
X1700324Y146012D03*
X1702230Y141228D03*
X1709134Y137757D03*
X1704334D03*
X1705118Y150847D03*
X1707086Y247292D03*
X1699795Y253198D03*
X1701495Y289735D03*
X1695142Y303839D03*
X1708889Y1189221D03*
X1696300Y1350683D03*
Y1345691D03*
X1701256Y1350683D03*
Y1345691D03*
X1708540D03*
Y1350683D03*
X1696300Y1357603D03*
Y1362595D03*
X1701256Y1357603D03*
Y1362595D03*
X1708540D03*
Y1357603D03*
X1696300Y1374881D03*
Y1369889D03*
Y1381801D03*
X1701256Y1369889D03*
Y1381801D03*
Y1374881D03*
X1708540D03*
Y1369889D03*
Y1381801D03*
X1696300Y1386793D03*
Y1394087D03*
Y1399079D03*
X1701256Y1386793D03*
Y1394087D03*
Y1399079D03*
X1708540D03*
Y1394087D03*
Y1386793D03*
X1696300Y1405999D03*
Y1410991D03*
X1701256Y1405999D03*
Y1410991D03*
X1708540Y1405999D03*
Y1410991D03*
X1701290Y1465913D03*
Y1456451D03*
Y1461182D03*
Y1471805D03*
Y1476536D03*
Y1481267D03*
Y1487159D03*
Y1491890D03*
Y1496621D03*
Y1507245D03*
Y1502514D03*
Y1511976D03*
Y1558813D03*
Y1563544D03*
Y1568275D03*
Y1574167D03*
Y1578898D03*
Y1583629D03*
Y1589522D03*
Y1594253D03*
Y1609607D03*
Y1604876D03*
Y1598984D03*
Y1614338D03*
X1724796Y82984D03*
Y77784D03*
Y80384D03*
Y75184D03*
Y85584D03*
X1716334Y116496D03*
Y109410D03*
Y102323D03*
X1711634Y116497D03*
Y109410D03*
X1716334Y130670D03*
Y123583D03*
X1711634D03*
Y130670D03*
X1716334Y137756D03*
X1720960Y1148000D03*
X1723796Y1160168D03*
X1725660Y1193019D03*
X1721660D03*
X1711783Y1193848D03*
X1713496Y1350683D03*
Y1345691D03*
X1720780Y1350683D03*
Y1345597D03*
X1725736Y1350683D03*
Y1345597D03*
X1713496Y1357603D03*
Y1362595D03*
X1720780Y1357603D03*
Y1362595D03*
X1725736Y1357603D03*
Y1362595D03*
X1713496Y1374881D03*
Y1369889D03*
Y1381801D03*
X1720780Y1369889D03*
Y1381801D03*
Y1374881D03*
X1725736Y1381801D03*
Y1374881D03*
Y1369889D03*
X1713496Y1399079D03*
Y1394087D03*
Y1386793D03*
X1720780D03*
Y1393993D03*
Y1399079D03*
X1725736Y1386793D03*
Y1399079D03*
Y1393993D03*
X1713496Y1405999D03*
Y1410991D03*
X1720780Y1405999D03*
Y1410991D03*
X1725736Y1405999D03*
Y1410991D03*
X1709952Y1465513D03*
Y1460782D03*
X1718613Y1465914D03*
Y1456452D03*
Y1461183D03*
Y1476537D03*
Y1471806D03*
Y1481268D03*
X1709952Y1476136D03*
Y1470244D03*
Y1480867D03*
Y1491490D03*
Y1485598D03*
Y1496221D03*
X1718613Y1491891D03*
Y1487160D03*
Y1496622D03*
Y1502515D03*
Y1511977D03*
X1709952Y1506845D03*
Y1500952D03*
Y1511576D03*
X1718613Y1507246D03*
X1709952Y1516307D03*
Y1563144D03*
X1718613Y1563544D03*
Y1558813D03*
X1709952Y1567875D03*
X1718613Y1568275D03*
X1709952Y1578498D03*
Y1572606D03*
X1718613Y1578898D03*
Y1574167D03*
Y1589522D03*
X1709952Y1583229D03*
X1718613Y1583629D03*
X1709952Y1593853D03*
Y1587960D03*
X1718613Y1594253D03*
Y1609607D03*
Y1598984D03*
Y1604876D03*
X1709952Y1609207D03*
Y1598584D03*
Y1603315D03*
Y1618669D03*
X1718613Y1614338D03*
X1709952Y1613938D03*
X1712000Y1644980D03*
X1727350Y92849D03*
X1734310Y103037D03*
X1734444Y116496D03*
Y109410D03*
Y130670D03*
Y123583D03*
X1730647Y137756D03*
X1739125Y293796D03*
X1736625D03*
X1737703Y472189D03*
X1728038Y491870D03*
X1730538D03*
X1730675Y1132361D03*
X1726963Y1132319D03*
X1739917Y1146937D03*
X1729207Y1159455D03*
X1737393Y1162817D03*
X1733660Y1193019D03*
X1729660D03*
X1737660D03*
X1733695Y1212164D03*
X1735989Y1214458D03*
X1731619Y1210089D03*
X1740785Y1219254D03*
X1737976Y1350683D03*
Y1345691D03*
X1733020D03*
Y1350683D03*
X1737976Y1362595D03*
Y1357603D03*
X1733020Y1362595D03*
Y1357603D03*
X1737976Y1369889D03*
Y1374881D03*
X1733020Y1369889D03*
Y1381801D03*
Y1374881D03*
X1737976Y1381801D03*
Y1399079D03*
Y1394087D03*
Y1386793D03*
X1733020Y1399079D03*
Y1394087D03*
Y1386793D03*
X1737976Y1405999D03*
Y1410991D03*
X1733020Y1405999D03*
Y1410991D03*
X1732000Y1644980D03*
X1755727Y94017D03*
X1747727D03*
X1751727D03*
X1751855Y110445D03*
Y115401D03*
X1756847D03*
Y110445D03*
X1751855Y129574D03*
Y124618D03*
X1756847D03*
Y129574D03*
X1753418Y191941D03*
X1753285Y188727D03*
X1747242Y226141D03*
X1750042D03*
X1755112Y256535D03*
X1749939Y288190D03*
X1747139D03*
X1744639D03*
X1749939Y285690D03*
X1744639D03*
X1747139D03*
X1758165Y290755D03*
X1754165D03*
X1744524Y370010D03*
X1753474Y542699D03*
X1757402Y825111D03*
Y820155D03*
X1744937Y912517D03*
X1747937D03*
X1750751Y910785D03*
X1748081Y984379D03*
X1756192Y996132D03*
X1743224Y1119055D03*
X1752000Y1644980D03*
X1764804Y84140D03*
Y76140D03*
Y80140D03*
X1759736Y94017D03*
X1767249Y117557D03*
X1762257D03*
Y122513D03*
Y131731D03*
X1767249Y122513D03*
Y131731D03*
X1762257Y136687D03*
X1767249D03*
X1765950Y180572D03*
X1770633Y180527D03*
X1774356Y192421D03*
X1759918Y184619D03*
X1770588Y185121D03*
X1765950Y185165D03*
X1761898Y206760D03*
X1763112Y256535D03*
X1764142Y279208D03*
X1768246Y281307D03*
X1762165Y290755D03*
X1765497Y370899D03*
X1766204Y398949D03*
X1770778Y402642D03*
X1773278D03*
X1763704Y401949D03*
X1767953Y413611D03*
X1770453D03*
X1772953D03*
X1772893Y423944D03*
X1770393D03*
X1767893D03*
X1765093D03*
X1765153Y413611D03*
X1764912Y482382D03*
X1765006Y478382D03*
X1761953Y706827D03*
Y865160D03*
X1772599Y993053D03*
X1762898Y992883D03*
X1764744Y1101930D03*
Y1097879D03*
X1766899Y1121122D03*
X1769499D03*
X1772099D03*
X1774799D03*
X1766999Y1130822D03*
X1772199D03*
X1769599D03*
X1774339Y1437975D03*
X1774216Y1470165D03*
X1772000Y1644980D03*
X1788884Y59871D03*
X1782382Y55513D03*
X1778179Y117261D03*
X1785886Y172665D03*
Y180665D03*
X1785918Y200864D03*
Y212864D03*
Y216864D03*
Y221864D03*
X1790014Y468607D03*
X1784602Y564092D03*
X1782600Y874500D03*
X1774899Y1130822D03*
Y1139822D03*
X1777399D03*
Y1147822D03*
X1774899D03*
X1785961Y1224892D03*
X1791099Y1260421D03*
X1779868Y1446668D03*
X1786564Y1478858D03*
X1777131Y1604357D03*
X1791570Y74535D03*
X1793149Y662810D03*
X1798705Y718793D03*
X1805013Y1091877D03*
X1792847Y1099210D03*
X1799012Y1095893D03*
X1805013Y1096470D03*
X1792863Y1103246D03*
X1801147Y1208555D03*
X1802844Y1227695D03*
X1793976Y1440762D03*
X1807270Y1468535D03*
X1793879Y1472952D03*
X1792000Y1644980D03*
X1816322Y977215D03*
X1823074Y992833D03*
X1812296Y1075688D03*
X1809696Y1091832D03*
X1809651Y1096426D03*
X1823028Y1124289D03*
X1817728D03*
X1815128D03*
X1820328D03*
X1822928Y1114589D03*
X1820228D03*
X1815028D03*
X1817628D03*
X1815865Y1133356D03*
X1809897Y1237285D03*
Y1230385D03*
Y1232885D03*
Y1239785D03*
Y1244185D03*
Y1246685D03*
X1807393Y1436345D03*
X1812000Y1644980D03*
X1831511Y978888D03*
X1831914Y992877D03*
X1824706Y1081145D03*
Y1089145D03*
X1837933Y1636171D03*
X1832000Y1644980D03*
G54D35*
X141337Y1228542D03*
X141336Y1247242D03*
Y1239762D03*
X161909Y1129429D03*
X160039Y1228543D03*
X169389Y1121948D03*
X167519Y1198621D03*
Y1213582D03*
X174999Y1228543D03*
X182480D03*
X167519D03*
X189960D03*
X197440D03*
X210531Y1211712D03*
X212401Y1228543D03*
X204921D03*
X213969Y1453293D03*
Y1464293D03*
X218011Y1211712D03*
X227362Y1228543D03*
X219881D03*
X227249Y1464293D03*
Y1453293D03*
X294685Y1127558D03*
Y1135039D03*
Y1194881D03*
Y1202362D03*
X290944Y1191141D03*
X294685Y1209842D03*
X302165Y1108858D03*
X298425Y1112598D03*
X309645D03*
Y1120078D03*
X305905Y1116338D03*
X298425Y1120078D03*
X305905Y1123818D03*
X309645Y1135039D03*
Y1127558D03*
X311515Y1136909D03*
X304035Y1140649D03*
X305905Y1131299D03*
X296555Y1151869D03*
X304035Y1155610D03*
Y1148129D03*
X296555Y1144389D03*
X311515D03*
Y1151869D03*
X296555Y1159350D03*
Y1166830D03*
X304035Y1170570D03*
X300295D03*
X311515Y1159350D03*
X300295Y1185531D03*
Y1178051D03*
X296555Y1174310D03*
X298425Y1187401D03*
X304035Y1185531D03*
Y1178051D03*
Y1193011D03*
X302165Y1198621D03*
X305905Y1206102D03*
X302165Y1213582D03*
Y1206102D03*
X298425Y1221062D03*
Y1217322D03*
X317125Y1116338D03*
Y1123818D03*
X313385D03*
Y1116338D03*
X315255Y1136909D03*
X313384Y1131299D03*
X315255Y1144389D03*
Y1151869D03*
Y1159350D03*
Y1166830D03*
Y1181791D03*
Y1189271D03*
Y1174310D03*
X313385Y1198621D03*
Y1206102D03*
X320866Y1217322D03*
X317125Y1221062D03*
X313385Y1213582D03*
X324606Y1209842D03*
Y1217322D03*
X320866Y1221062D03*
X324606D03*
X320866Y1236023D03*
Y1224803D03*
X324606Y1232283D03*
Y1236023D03*
Y1224803D03*
Y1243503D03*
X598424Y1228542D03*
X598423Y1239762D03*
Y1247242D03*
X618996Y1129429D03*
X617126Y1228543D03*
X626476Y1121948D03*
X624606Y1198621D03*
Y1213582D03*
X632086Y1228543D03*
X624606D03*
X639567D03*
X647047D03*
X667618Y1211712D03*
X654527Y1228543D03*
X662008D03*
X669488D03*
X675098Y1211712D03*
X676968Y1228543D03*
X684449D03*
X729331Y1250984D03*
X721850D03*
Y1254724D03*
X729331D03*
X748031Y1194881D03*
X744291Y1254724D03*
Y1250984D03*
X736811Y1254724D03*
Y1250984D03*
X762992Y1116338D03*
X766732Y1120078D03*
X762992Y1123818D03*
X766732Y1112598D03*
X759252Y1108858D03*
X755512Y1120078D03*
X761122Y1140649D03*
X762992Y1131299D03*
X766732Y1135039D03*
Y1127558D03*
X751772D03*
Y1135039D03*
X753642Y1144389D03*
X761122Y1148129D03*
Y1155610D03*
X753642Y1151869D03*
X757382Y1170570D03*
X761122D03*
X753642Y1166830D03*
Y1159350D03*
Y1181791D03*
Y1174310D03*
X757382Y1178051D03*
Y1185531D03*
X761122Y1178051D03*
Y1185531D03*
X753642Y1189271D03*
X759252Y1191141D03*
X762992D03*
X755512Y1194881D03*
X759252Y1198621D03*
X751772Y1202362D03*
X755512Y1221062D03*
Y1217322D03*
X759252Y1213582D03*
X762992Y1206102D03*
X759252D03*
X751772Y1209842D03*
X770472Y1123818D03*
X774212D03*
X770472Y1116338D03*
X774212D03*
X770471Y1131299D03*
X770472Y1138779D03*
X772342Y1151869D03*
Y1144389D03*
X768602Y1151869D03*
Y1144389D03*
X772342Y1166830D03*
X768602Y1159350D03*
X772342D03*
Y1174310D03*
Y1181791D03*
Y1196751D03*
X770472Y1198621D03*
X781693Y1217322D03*
X777953D03*
X774212Y1221062D03*
X781693Y1209842D03*
X770472Y1213582D03*
Y1206102D03*
X781693Y1224803D03*
X777953D03*
X781693Y1232283D03*
X777953Y1236023D03*
X781693D03*
Y1243503D03*
X1055510Y1228542D03*
X1055509Y1239762D03*
Y1247242D03*
X1074212Y1228543D03*
X1083562Y1121948D03*
X1076082Y1129429D03*
X1081692Y1198621D03*
Y1213582D03*
Y1228543D03*
X1089172D03*
X1104133D03*
X1096653D03*
X1124704Y1211712D03*
X1119094Y1228543D03*
X1111613D03*
X1132184Y1211712D03*
X1126574Y1228543D03*
X1134054D03*
X1141535D03*
X1203247Y1193011D03*
X1216338Y1108858D03*
X1212598Y1120078D03*
X1220078Y1116338D03*
Y1123818D03*
X1218208Y1140649D03*
X1208858Y1127558D03*
X1220078Y1131299D03*
X1208858Y1135039D03*
X1210728Y1151869D03*
X1218208Y1155610D03*
Y1148129D03*
X1210728Y1144389D03*
Y1159350D03*
Y1166830D03*
X1218208Y1170570D03*
X1214468D03*
X1210728Y1181791D03*
Y1189271D03*
X1218208Y1185531D03*
Y1178051D03*
X1214468Y1185531D03*
Y1178051D03*
X1210728Y1174310D03*
X1212598Y1194881D03*
X1218208Y1193011D03*
X1214468D03*
X1216338Y1198621D03*
X1208858Y1202362D03*
X1220078Y1206102D03*
X1216338D03*
X1212598Y1221062D03*
Y1217322D03*
X1216338Y1213582D03*
X1208858Y1209842D03*
X1223818Y1112598D03*
Y1120078D03*
X1227558Y1116338D03*
X1231298D03*
X1227558Y1123818D03*
X1231298D03*
X1229428Y1136909D03*
X1223818Y1127558D03*
X1227557Y1131299D03*
X1223818Y1135039D03*
X1225688Y1144389D03*
Y1151869D03*
X1229428Y1144389D03*
Y1151869D03*
Y1159350D03*
X1225688D03*
X1229428Y1166830D03*
Y1181791D03*
Y1189271D03*
Y1174310D03*
Y1196751D03*
X1227558Y1198621D03*
Y1206102D03*
X1235039Y1217322D03*
X1231298Y1221062D03*
X1227558Y1213582D03*
X1235039Y1221062D03*
Y1224803D03*
Y1236023D03*
X1238779Y1217322D03*
Y1209842D03*
Y1221062D03*
Y1224803D03*
Y1232283D03*
Y1236023D03*
Y1243503D03*
X1514468Y1166829D03*
Y1174309D03*
Y1181790D03*
X1512597Y1228542D03*
X1512596Y1239762D03*
Y1247242D03*
X1540649Y1121948D03*
X1533169Y1129429D03*
X1538779Y1198621D03*
Y1213582D03*
X1531299Y1228543D03*
X1538779D03*
X1546259D03*
X1561220D03*
X1553740D03*
X1576181D03*
X1568700D03*
X1589271Y1211712D03*
X1581791D03*
X1583661Y1228543D03*
X1591141D03*
X1598622D03*
X1636023Y1254724D03*
Y1250984D03*
X1643504D03*
Y1254724D03*
X1660334Y1204232D03*
Y1200491D03*
Y1193011D03*
Y1196751D03*
Y1207972D03*
X1650984Y1250984D03*
Y1254724D03*
X1658464D03*
Y1250984D03*
X1673425Y1108858D03*
X1669685Y1112598D03*
Y1120078D03*
X1675295Y1140649D03*
X1665945Y1127558D03*
Y1135039D03*
X1667815Y1151869D03*
X1675295Y1155610D03*
Y1148129D03*
X1667815Y1144389D03*
Y1159350D03*
Y1166830D03*
X1675295Y1170570D03*
X1671555D03*
Y1185531D03*
Y1178051D03*
X1667815Y1174310D03*
Y1181791D03*
Y1189271D03*
X1675295Y1185531D03*
Y1178051D03*
X1669685Y1194881D03*
X1675295Y1193011D03*
X1671555D03*
X1665945Y1202362D03*
X1673425Y1198621D03*
X1669685Y1221062D03*
Y1217322D03*
X1673425Y1213582D03*
X1665945Y1209842D03*
X1673425Y1206102D03*
X1677165Y1116338D03*
X1680905Y1112598D03*
X1677165Y1123818D03*
X1680905Y1120078D03*
X1684645Y1116338D03*
X1688385D03*
X1684645Y1123818D03*
X1688385D03*
X1686515Y1136909D03*
X1682775D03*
X1680905Y1127558D03*
X1677165Y1131299D03*
X1684644D03*
X1680905Y1135039D03*
X1682775Y1144389D03*
Y1151869D03*
X1686515Y1144389D03*
Y1151869D03*
Y1159350D03*
X1682775D03*
X1686515Y1166830D03*
Y1174310D03*
Y1181791D03*
Y1189271D03*
X1684645Y1198621D03*
X1692126Y1217322D03*
X1688385Y1221062D03*
X1684645Y1213582D03*
Y1206102D03*
X1677165D03*
X1692126Y1224803D03*
Y1236023D03*
X1695866Y1217322D03*
Y1209842D03*
Y1232283D03*
Y1236023D03*
Y1224803D03*
Y1243503D03*
G54D27*
X73872Y1348187D03*
X81752D03*
X73872Y1360099D03*
X81752D03*
X73872Y1384297D03*
Y1372385D03*
X81752Y1384297D03*
Y1372385D03*
X86112Y1348187D03*
X98352D03*
X93992D03*
X86112Y1360099D03*
X98352D03*
X93992D03*
X86112Y1384297D03*
Y1372385D03*
X98352Y1384297D03*
Y1372385D03*
X93992D03*
Y1384297D03*
X86112Y1396583D03*
X93992D03*
X98352D03*
X86112Y1408495D03*
X93992D03*
X98352D03*
X110592Y1348187D03*
X106232D03*
X110592Y1360099D03*
X106232D03*
X110592Y1384297D03*
X106232D03*
Y1372385D03*
X110592D03*
Y1396583D03*
X106232D03*
X110592Y1408495D03*
X106232D03*
X118472Y1348187D03*
X122832D03*
X130712D03*
X118472Y1360099D03*
X122832D03*
X130712D03*
X118472Y1384297D03*
Y1372385D03*
X122832Y1384297D03*
Y1372385D03*
X130712Y1384297D03*
Y1372385D03*
X118472Y1396583D03*
X122832D03*
X130712D03*
X118472Y1408495D03*
X122832D03*
X130712D03*
X146948Y1080806D03*
Y1103247D03*
X143208D03*
X146948Y1133169D03*
Y1140649D03*
X139468Y1136909D03*
X143208Y1125688D03*
Y1133169D03*
Y1140649D03*
X146948Y1125688D03*
X143208Y1144389D03*
Y1151870D03*
X146948Y1144389D03*
Y1151870D03*
X140707Y1170569D03*
X143208Y1159350D03*
X146948D03*
X148818Y1183661D03*
X140707Y1178050D03*
X145078Y1187401D03*
Y1183661D03*
X148818Y1187401D03*
X146947Y1174310D03*
X141337Y1191142D03*
X145078Y1194881D03*
Y1202362D03*
X148818Y1194881D03*
Y1202362D03*
X141337Y1198622D03*
Y1206103D03*
X145078Y1209842D03*
Y1217322D03*
X148818Y1209842D03*
Y1217322D03*
X141337Y1213583D03*
Y1221063D03*
X148818Y1224803D03*
X145078Y1232283D03*
Y1236023D03*
X148818Y1232283D03*
Y1236023D03*
X145078Y1224803D03*
X148818Y1254724D03*
X135072Y1348187D03*
X142952D03*
X147312D03*
X135072Y1360099D03*
X147312D03*
X142952D03*
X135072Y1384297D03*
Y1372385D03*
X147312Y1384297D03*
Y1372385D03*
X142952Y1384297D03*
Y1372385D03*
X135072Y1396583D03*
X147312D03*
X142952D03*
X135072Y1408495D03*
X147312D03*
X142952D03*
X150688Y1077066D03*
X158169Y1106988D03*
X165649D03*
X161909D03*
X158169Y1118208D03*
Y1121948D03*
X154429D03*
X150689D03*
X165649Y1114468D03*
X161909D03*
X158169Y1133169D03*
X161909Y1140649D03*
X158169Y1125688D03*
X154429Y1129429D03*
X150689D03*
Y1136909D03*
X154429Y1140649D03*
X150689D03*
X165649D03*
Y1129429D03*
Y1136909D03*
X158169Y1140649D03*
X150689Y1151870D03*
X158169Y1155610D03*
X154429D03*
X150689D03*
X161909Y1144389D03*
Y1148129D03*
Y1151870D03*
Y1155610D03*
X150689Y1144389D03*
Y1148129D03*
Y1159350D03*
X158169Y1166830D03*
X150688D03*
X154429Y1170570D03*
X150688D03*
X161909Y1159350D03*
X160039Y1187401D03*
X156299Y1183661D03*
X152559D03*
X161909Y1174310D03*
Y1178051D03*
X165649Y1181791D03*
X161909D03*
X158169Y1174310D03*
X154429D03*
X150688Y1178051D03*
Y1174310D03*
X156299Y1179921D03*
X160039Y1183661D03*
X163779D03*
X156299Y1198621D03*
X152559D03*
X163779D03*
X160039D03*
X152559Y1191141D03*
X156299D03*
X160039D03*
X163779D03*
X160039Y1206102D03*
X156299D03*
X152559D03*
X163779D03*
X156299Y1213582D03*
X152559D03*
X160039Y1221062D03*
X156299D03*
X152559D03*
X163779D03*
X152559Y1228543D03*
X160039Y1224803D03*
X152559D03*
X156299Y1232283D03*
Y1236023D03*
X163779D03*
Y1232283D03*
X160039Y1239763D03*
X152559D03*
Y1243503D03*
X160039D03*
X163779Y1239763D03*
X152559Y1258465D03*
X160039D03*
X159552Y1348187D03*
X155192D03*
X159552Y1360099D03*
X155192D03*
X159552Y1372385D03*
Y1384297D03*
X155192D03*
Y1372385D03*
X159552Y1396583D03*
X155192D03*
X159552Y1408495D03*
X155192D03*
X174998Y1071455D03*
X182479D03*
X178740Y1090157D03*
X174999D03*
X171259D03*
X182480D03*
X178740Y1093897D03*
Y1097637D03*
X174999Y1101377D03*
X169389Y1106988D03*
X171259Y1093897D03*
X174999Y1105117D03*
X182480Y1101377D03*
Y1105117D03*
X174999Y1108858D03*
X178740D03*
X176870Y1114468D03*
Y1118208D03*
Y1121948D03*
X178740Y1112598D03*
X173129Y1110728D03*
X169389D03*
X180610Y1114468D03*
Y1118208D03*
Y1121948D03*
X182480Y1112598D03*
Y1108858D03*
X180610Y1136909D03*
X173129Y1133169D03*
X169389D03*
X176870Y1140649D03*
Y1125688D03*
Y1129429D03*
Y1133169D03*
Y1136909D03*
X173129Y1140649D03*
X169389D03*
X180610D03*
Y1125688D03*
Y1129429D03*
Y1133169D03*
Y1148129D03*
X173129Y1144389D03*
X169389D03*
X173129Y1148129D03*
Y1155610D03*
Y1151870D03*
X180610Y1155610D03*
Y1151870D03*
Y1144389D03*
X176870Y1170570D03*
X173129Y1159350D03*
Y1166830D03*
Y1170570D03*
X180610Y1166830D03*
Y1159350D03*
Y1174310D03*
Y1181791D03*
X173129Y1174310D03*
Y1178051D03*
Y1181791D03*
X171259Y1187401D03*
X174999D03*
X180610Y1178051D03*
X167519Y1183661D03*
X178740Y1187401D03*
X182480D03*
X176870Y1185531D03*
X173129D03*
X171259Y1202362D03*
Y1194881D03*
X174999Y1202362D03*
Y1194881D03*
X167519Y1191141D03*
X178740D03*
Y1194881D03*
Y1198621D03*
Y1202362D03*
X182480Y1191141D03*
Y1198621D03*
Y1202362D03*
X171259Y1209842D03*
X174999Y1217322D03*
X171259Y1221062D03*
X174999D03*
X171259Y1217322D03*
X167519Y1206102D03*
X178740D03*
Y1209842D03*
Y1213582D03*
Y1221062D03*
X182480D03*
X178740Y1217322D03*
X182480Y1206102D03*
Y1209842D03*
Y1213582D03*
Y1217322D03*
X178740Y1228543D03*
X171259Y1224803D03*
Y1228543D03*
X178740Y1224803D03*
Y1232283D03*
Y1236023D03*
X171259Y1232283D03*
X174999Y1224803D03*
X171259Y1236023D03*
X182480Y1224803D03*
X167519D03*
X182480Y1243503D03*
X171259Y1250984D03*
X174999Y1247243D03*
Y1239763D03*
X171259D03*
X167519D03*
Y1243503D03*
X175000Y1258465D03*
X182480D03*
X167519D03*
X167432Y1348187D03*
X171792D03*
X179672D03*
X167432Y1360099D03*
X171792D03*
X179672D03*
X167432Y1384297D03*
Y1372385D03*
X171792Y1384297D03*
Y1372385D03*
X179672Y1384297D03*
Y1372385D03*
X171792Y1396583D03*
X179672D03*
X167432D03*
Y1408495D03*
X171792D03*
X179672D03*
X197439Y1071455D03*
X189959D03*
X193700Y1090157D03*
X189960D03*
X186220D03*
X197440D03*
X193700Y1093897D03*
X189960Y1101377D03*
X186220Y1097637D03*
X189960Y1105117D03*
X186220Y1093897D03*
X193700Y1097637D03*
X197440Y1101377D03*
Y1105117D03*
X195570Y1121948D03*
X191830Y1118208D03*
X188090D03*
X184350D03*
X191830Y1121948D03*
X188090D03*
X184350D03*
X195570Y1118208D03*
X186220Y1108858D03*
X189960D03*
X193700D03*
X197440D03*
X191830Y1125688D03*
X188090D03*
X184350D03*
X188090Y1129429D03*
X184350D03*
X188090Y1133169D03*
X184350D03*
X188090Y1136909D03*
Y1140649D03*
X184350D03*
X195570Y1133169D03*
Y1129429D03*
Y1125688D03*
Y1136909D03*
X188090Y1144389D03*
Y1151870D03*
X191830Y1155610D03*
Y1148129D03*
X195570Y1151869D03*
Y1144389D03*
X188090Y1159350D03*
Y1170570D03*
X191830Y1166830D03*
X195570Y1159350D03*
Y1170570D03*
X188090Y1185531D03*
X195570Y1189271D03*
X191830Y1181791D03*
Y1174310D03*
X195570Y1185531D03*
Y1178051D03*
X188090Y1196751D03*
Y1200491D03*
Y1204232D03*
X191830D03*
Y1196751D03*
Y1200491D03*
X184350Y1193011D03*
Y1196751D03*
X195570Y1200491D03*
Y1196751D03*
Y1193011D03*
Y1204232D03*
X186220Y1198621D03*
X193700Y1209842D03*
X191830Y1207972D03*
X189960Y1209842D03*
X195570Y1207972D03*
X193700Y1213582D03*
X191830Y1219192D03*
X186220Y1221062D03*
X189960D03*
X193700D03*
X197440D03*
X186220Y1206102D03*
Y1209842D03*
Y1213582D03*
X197440Y1209842D03*
X186220Y1224803D03*
X193700Y1228543D03*
X197440Y1224803D03*
X193700Y1232283D03*
X186220D03*
X189960Y1224803D03*
X193700Y1236023D03*
X186220D03*
Y1228543D03*
X193700Y1224803D03*
X197440Y1239763D03*
Y1243503D03*
X193700Y1239763D03*
X186220D03*
X189960Y1243503D03*
Y1258465D03*
X197441D03*
X184032Y1348187D03*
X191912D03*
X196272D03*
X184032Y1360099D03*
X196272D03*
X191912D03*
X184032Y1384297D03*
Y1372385D03*
X196272Y1384297D03*
Y1372385D03*
X191912Y1384297D03*
Y1372385D03*
X184032Y1396583D03*
X191912D03*
X196272D03*
X184032Y1408495D03*
X191912D03*
X196272D03*
X204920Y1071455D03*
X212400D03*
X204921Y1090157D03*
X212401D03*
X208661D03*
X201181D03*
X204921Y1101377D03*
X208661Y1097637D03*
X201181D03*
X204921Y1105117D03*
X212401Y1101377D03*
Y1105117D03*
X201181Y1093897D03*
X208661D03*
X199311Y1118208D03*
Y1121948D03*
X206791Y1118208D03*
X203051D03*
Y1121948D03*
X206791D03*
X210531Y1118208D03*
X214271Y1110728D03*
X210531Y1121948D03*
X214271Y1118208D03*
Y1121948D03*
X201181Y1108858D03*
X204921D03*
X208661D03*
X212401D03*
X199311Y1140649D03*
X203051D03*
X206791D03*
X199311Y1125688D03*
X203051D03*
X206791D03*
Y1133169D03*
X203051D03*
X199311D03*
X210531D03*
Y1140649D03*
X214271D03*
Y1125688D03*
X210531D03*
X214271Y1133169D03*
X203051Y1148129D03*
X199311D03*
X206791D03*
X214271D03*
X210531D03*
X199311Y1155610D03*
X206791D03*
X214271D03*
X206791Y1166830D03*
X203051Y1159350D03*
X199311Y1166830D03*
X203051Y1170570D03*
X214271Y1166830D03*
X210531Y1159350D03*
Y1170570D03*
X206791Y1181791D03*
X203051D03*
X199311D03*
X206791Y1189271D03*
X203051D03*
X199311D03*
X214271Y1181791D03*
X210531D03*
X214271Y1189271D03*
X210531D03*
X199311Y1174310D03*
X206791D03*
X214271D03*
X206791Y1196751D03*
X203051D03*
X199311D03*
Y1204232D03*
X203051D03*
X206791D03*
X214271Y1196751D03*
X210531D03*
Y1204232D03*
X214271D03*
X206791Y1207972D03*
X203051D03*
X199311D03*
X210531D03*
X214271D03*
X212401Y1221062D03*
X208661D03*
X204921D03*
X201181D03*
Y1224803D03*
X208661Y1228543D03*
X212401Y1224803D03*
X208661Y1232283D03*
X201181D03*
X204921Y1224803D03*
X201181Y1236023D03*
X208661D03*
Y1224803D03*
X201181Y1228543D03*
X212401Y1243503D03*
X208661Y1239763D03*
X204921Y1243503D03*
X212401Y1258465D03*
X204921D03*
X204152Y1348187D03*
Y1360099D03*
Y1384297D03*
Y1372385D03*
Y1396583D03*
Y1408495D03*
X219880Y1071455D03*
X227361D03*
X227362Y1090157D03*
X223622D03*
X219881D03*
X231102D03*
X216141D03*
X223622Y1093897D03*
X231102D03*
Y1097637D03*
X227362Y1101377D03*
Y1105117D03*
X219881Y1101377D03*
Y1105117D03*
X223622Y1097637D03*
X216141D03*
Y1093897D03*
X225492Y1118208D03*
Y1121948D03*
X218011Y1118208D03*
X221751D03*
X218011Y1121948D03*
X221751D03*
X229232D03*
Y1118208D03*
Y1114468D03*
X216141Y1108858D03*
X219881D03*
X223622D03*
X227362D03*
X231102D03*
X225492Y1133169D03*
Y1140649D03*
Y1125688D03*
X218011Y1140649D03*
X221751D03*
X218011Y1125688D03*
X221751D03*
Y1133169D03*
X218011D03*
X229330Y1132677D03*
X229232Y1140649D03*
Y1125688D03*
X225492Y1148129D03*
X221751D03*
X218011D03*
X229232D03*
X221751Y1155610D03*
X229232D03*
X225492Y1170570D03*
Y1159350D03*
X218011Y1170570D03*
X221752Y1166830D03*
X218011Y1159350D03*
X229232Y1166830D03*
X225492Y1181791D03*
Y1189271D03*
X221751Y1181791D03*
X218011D03*
X221751Y1189271D03*
X218011D03*
X229232Y1181791D03*
Y1189271D03*
X221751Y1174310D03*
X229232D03*
X218011Y1204232D03*
X229232Y1196751D03*
Y1204232D03*
X225492Y1196751D03*
Y1204232D03*
X221751D03*
Y1196751D03*
X218011D03*
X225492Y1207972D03*
X221751D03*
X218011D03*
X229232D03*
X231102Y1221062D03*
X227362D03*
X219881Y1217322D03*
X223622Y1221062D03*
X219881D03*
X216141D03*
X227362Y1224803D03*
X223622Y1232283D03*
X219881Y1224803D03*
X223622Y1236023D03*
X231102Y1232283D03*
Y1236023D03*
X216141Y1232283D03*
Y1236023D03*
Y1224803D03*
X223622D03*
Y1228543D03*
X216141D03*
X223622Y1239763D03*
X231102D03*
X227362Y1243503D03*
X219881D03*
X216141Y1239763D03*
X219882Y1258465D03*
X227363D03*
X246062Y1075196D03*
X234841Y1071454D03*
X242321Y1071455D03*
X238582Y1075196D03*
X234842Y1090157D03*
X246062D03*
Y1078936D03*
X238582Y1090157D03*
X242322Y1086417D03*
X234842Y1082677D03*
Y1086417D03*
X242322Y1090157D03*
X246062Y1097637D03*
Y1093897D03*
X242322Y1105117D03*
X234842Y1101377D03*
X238582Y1093897D03*
X242322Y1101377D03*
X234842Y1105117D03*
X236712Y1121948D03*
X240452D03*
X244192D03*
X234842Y1108858D03*
X238582D03*
X242322D03*
X246062D03*
X236712Y1133464D03*
X240452Y1133169D03*
X236712Y1140649D03*
X240452D03*
X236712Y1125688D03*
X240452D03*
X244192Y1133169D03*
Y1140649D03*
Y1125688D03*
X236712Y1148129D03*
X240452D03*
X244192D03*
X240452Y1155610D03*
Y1166830D03*
X236712Y1170570D03*
Y1159350D03*
X244192Y1170570D03*
Y1159350D03*
X240452Y1181791D03*
X236712D03*
Y1189271D03*
X240452D03*
X244192Y1181791D03*
Y1189271D03*
X240452Y1174310D03*
Y1204232D03*
X236712D03*
Y1196751D03*
X240452D03*
X244192Y1204232D03*
Y1196751D03*
X240452Y1207972D03*
Y1211712D03*
X242322Y1221062D03*
X244192Y1211712D03*
Y1207972D03*
X236712D03*
X234842Y1221062D03*
X238582D03*
X246062Y1232283D03*
Y1236023D03*
X238582Y1232283D03*
X234842Y1228543D03*
Y1224803D03*
X238582Y1236023D03*
X242322Y1228543D03*
Y1224803D03*
X246062Y1239763D03*
X238582D03*
X234842Y1258465D03*
X242322D03*
X239383Y1348187D03*
X247263D03*
Y1360099D03*
X239383D03*
X247263Y1384297D03*
Y1372385D03*
X239383Y1384297D03*
Y1372385D03*
X253543Y1075196D03*
X261023D03*
X249802Y1071455D03*
X257282D03*
X253543Y1090157D03*
X249803D03*
Y1086417D03*
X253543Y1078936D03*
X257283Y1090157D03*
Y1086417D03*
X261023Y1090157D03*
Y1078936D03*
X249803Y1105117D03*
X253543Y1093897D03*
Y1097637D03*
X257283Y1105117D03*
X261023Y1093897D03*
Y1097637D03*
X255413Y1121948D03*
X251673D03*
X247933D03*
X262893D03*
X259153D03*
X249803Y1108858D03*
X253543D03*
X257283D03*
X261023D03*
X247933Y1133169D03*
X251673D03*
X255413D03*
X247933Y1140649D03*
X251673D03*
X255413D03*
X247933Y1125688D03*
X251673D03*
X255413D03*
X259153Y1133169D03*
X262893D03*
Y1140649D03*
X259153Y1125688D03*
X262893D03*
X259153Y1140649D03*
Y1148129D03*
X262893D03*
Y1155610D03*
X247933Y1148129D03*
X251673D03*
X255413D03*
X247933Y1155610D03*
X255413D03*
X262893Y1166830D03*
X251673Y1170570D03*
X255413Y1166830D03*
X247933D03*
X251673Y1159350D03*
X259153D03*
Y1170570D03*
X247933Y1181791D03*
X251673D03*
X255413D03*
X247933Y1189271D03*
X251673D03*
X255413D03*
X262893D03*
Y1174310D03*
X259153Y1181791D03*
X262893D03*
X259153Y1189271D03*
X255413Y1174310D03*
X247933D03*
Y1204232D03*
X255413D03*
X251673D03*
X247933Y1196751D03*
X251673D03*
X255413D03*
X259153Y1204232D03*
X262893D03*
X259153Y1196751D03*
X262893D03*
X247933Y1207972D03*
X251673D03*
X255413Y1211712D03*
Y1207972D03*
X262893D03*
X259153D03*
X262893Y1211712D03*
X259153D03*
X249803Y1228543D03*
X257283D03*
X249803Y1224803D03*
X253543Y1236023D03*
X257283Y1224803D03*
X261023Y1236023D03*
X253543Y1232283D03*
X261023D03*
X257283Y1239763D03*
X249803Y1258465D03*
X257283D03*
X263863Y1348187D03*
X259503D03*
X251623D03*
X263863Y1360099D03*
X259503D03*
X251623D03*
X263863Y1384297D03*
Y1372385D03*
X259503Y1384297D03*
Y1372385D03*
X251623D03*
Y1384297D03*
X263863Y1396583D03*
X259503D03*
X251623D03*
X263863Y1408495D03*
X259503D03*
X251623D03*
X279723Y1071455D03*
X264762D03*
X272243D03*
X268503Y1075196D03*
X275984D03*
X279724Y1090157D03*
X272244Y1082677D03*
X275984Y1090157D03*
X272244Y1086417D03*
X268503Y1078936D03*
Y1090157D03*
X264763Y1086417D03*
X272244Y1090157D03*
X264763D03*
X268503Y1093897D03*
Y1097637D03*
X272244Y1105117D03*
X279724D03*
X275984Y1093897D03*
X264763Y1105117D03*
X274114Y1118208D03*
X270373D03*
X266633Y1121948D03*
X270373D03*
X277854Y1118208D03*
X264763Y1108858D03*
X268503D03*
X272244D03*
X275984D03*
X279724D03*
X274114Y1125688D03*
X270373Y1136909D03*
X266633Y1133169D03*
X270373D03*
X266633Y1140649D03*
X270373Y1125688D03*
Y1129429D03*
X266633Y1125688D03*
X270373Y1140649D03*
X277854Y1136909D03*
Y1140649D03*
X274114Y1155610D03*
Y1151869D03*
Y1148129D03*
X266633D03*
X270373Y1144389D03*
Y1148129D03*
Y1151869D03*
X277854Y1144389D03*
Y1148129D03*
Y1151870D03*
X270373Y1155610D03*
X274114Y1166830D03*
Y1159350D03*
Y1170570D03*
X266633Y1181791D03*
X270373Y1189271D03*
X277854Y1178051D03*
Y1189271D03*
Y1185531D03*
X270373Y1174310D03*
X277854Y1181791D03*
X274114D03*
Y1174310D03*
X266633Y1189271D03*
X270373Y1178051D03*
Y1185531D03*
X274114Y1196751D03*
X270393Y1196732D03*
X270373Y1204232D03*
X266633D03*
X270373Y1200491D03*
X266633Y1196751D03*
X270373Y1193011D03*
X277854D03*
X274114Y1207972D03*
X270373Y1211712D03*
X266633Y1207972D03*
Y1211712D03*
X270373Y1207972D03*
X277854Y1211712D03*
X279724Y1221062D03*
X275984D03*
X272244D03*
X268503D03*
X279724Y1224803D03*
X272244D03*
X268503Y1236023D03*
Y1232283D03*
X272244Y1228543D03*
X264763Y1224803D03*
X275984Y1232283D03*
Y1236023D03*
X264763Y1228543D03*
X279724D03*
X268503Y1239763D03*
X279724Y1258465D03*
X264763D03*
X272244D03*
X276103Y1348187D03*
X271743D03*
X276103Y1360099D03*
X271743D03*
X276103Y1384297D03*
Y1372385D03*
X271743Y1384297D03*
Y1372385D03*
X276103Y1396583D03*
X271743D03*
Y1408495D03*
X276103D03*
X294684Y1071455D03*
X290944Y1075196D03*
X287203Y1071455D03*
X283464Y1075196D03*
X287204Y1090157D03*
X283464Y1078936D03*
Y1090157D03*
X290943D03*
X290944Y1093897D03*
X287204Y1101377D03*
Y1105117D03*
X294685D03*
X294684Y1120078D03*
Y1112598D03*
X283464Y1108858D03*
X287204D03*
X290944D03*
X294685D03*
X290944Y1112598D03*
Y1116338D03*
Y1120078D03*
Y1123818D03*
X281594Y1140649D03*
Y1136909D03*
X290944Y1127558D03*
Y1131299D03*
Y1135039D03*
Y1138779D03*
X281594Y1148129D03*
Y1155610D03*
Y1151869D03*
X285334D03*
X289074D03*
Y1155610D03*
X292814Y1151869D03*
Y1144389D03*
X281594Y1159350D03*
X289074Y1166830D03*
Y1170570D03*
Y1159350D03*
X281594Y1170570D03*
Y1166830D03*
X292814Y1159350D03*
Y1166830D03*
Y1181791D03*
X285334Y1185531D03*
X289074Y1174310D03*
Y1178051D03*
Y1185531D03*
X281594Y1189271D03*
Y1185531D03*
X285334Y1181791D03*
X281594Y1178051D03*
Y1174310D03*
X292814D03*
Y1189271D03*
X281594Y1196751D03*
Y1204232D03*
Y1193011D03*
X285334D03*
X290944Y1194881D03*
Y1198621D03*
Y1202362D03*
X294685Y1221062D03*
Y1217322D03*
X290944Y1221062D03*
X287204D03*
X283464D03*
X290944Y1206102D03*
Y1209842D03*
Y1213582D03*
Y1217322D03*
X294685Y1228543D03*
Y1224803D03*
X290944Y1232283D03*
Y1236023D03*
X283464Y1232283D03*
X287204Y1228543D03*
X283464Y1236023D03*
X287204Y1224803D03*
X283464Y1239763D03*
X290944D03*
X294685Y1254724D03*
Y1250984D03*
X290944Y1247243D03*
Y1243503D03*
X294685Y1258465D03*
X287204D03*
X288343Y1348187D03*
X296223D03*
X283983D03*
X288343Y1360099D03*
X296223D03*
X283983D03*
X288343Y1384297D03*
Y1372385D03*
X296223Y1384297D03*
Y1372385D03*
X283983D03*
Y1384297D03*
X288343Y1396583D03*
X296223D03*
X283983D03*
X288343Y1408495D03*
X296223D03*
X283983D03*
X309645Y1071455D03*
X302165D03*
X298425Y1075196D03*
X305906D03*
X298424Y1090157D03*
X298426Y1078936D03*
X305906D03*
X302165Y1105117D03*
X309645D03*
X298425Y1093897D03*
X305905D03*
X302165Y1123818D03*
X305904Y1108857D03*
X302165Y1116338D03*
X298425Y1108858D03*
X300295Y1140649D03*
X302165Y1131299D03*
X300295Y1148129D03*
Y1159350D03*
Y1166830D03*
X311515D03*
X307775Y1170570D03*
X300295Y1181791D03*
Y1174310D03*
Y1189271D03*
X311515Y1174310D03*
X307775Y1178051D03*
X311515Y1181791D03*
X307775Y1185531D03*
X311515Y1189271D03*
X298425Y1202362D03*
Y1194881D03*
X309645Y1198621D03*
X307775Y1193011D03*
X311515Y1196751D03*
X305905Y1198621D03*
X309645Y1202362D03*
X298425Y1209842D03*
X302165Y1221062D03*
X309645Y1217322D03*
Y1209842D03*
X305905Y1213582D03*
X309645D03*
Y1206102D03*
Y1221062D03*
X305905D03*
X298425Y1236023D03*
Y1232283D03*
X302165Y1228543D03*
Y1224803D03*
X305905Y1232283D03*
X309645Y1228543D03*
Y1224803D03*
X305905Y1236023D03*
X298425Y1239763D03*
X309645D03*
Y1254724D03*
X298425Y1247243D03*
X309645Y1250984D03*
X298425Y1243503D03*
X305905D03*
Y1247243D03*
X302165Y1254724D03*
Y1250984D03*
X309645Y1258465D03*
X302165D03*
X308463Y1348187D03*
X300583D03*
X308463Y1360099D03*
X300583D03*
X308463Y1372385D03*
X300583D03*
Y1384297D03*
X308463D03*
Y1396583D03*
X300583D03*
X308463Y1408495D03*
X300583D03*
X317125Y1071455D03*
X320866Y1075196D03*
X313386D03*
X320866Y1078936D03*
X313384Y1090157D03*
X313386Y1078936D03*
X328347Y1082677D03*
Y1090158D03*
X324606Y1078936D03*
X313385Y1093897D03*
X328347Y1101378D03*
Y1116339D03*
Y1123819D03*
Y1108859D03*
X313385Y1108858D03*
X328347Y1131300D03*
X318996Y1140649D03*
Y1155610D03*
Y1148129D03*
X322736Y1170570D03*
X318996D03*
Y1185531D03*
Y1178051D03*
X322736D03*
Y1185531D03*
X328347Y1198621D03*
X322736Y1193011D03*
X320866Y1202362D03*
X318996Y1193011D03*
X326416D03*
X324606Y1202362D03*
X328347Y1206102D03*
Y1221062D03*
Y1213582D03*
X320866Y1209842D03*
X313385Y1221062D03*
X320866Y1206102D03*
Y1232283D03*
X313385D03*
X317125Y1228543D03*
Y1224803D03*
X313385Y1236023D03*
X328347Y1228543D03*
Y1239762D03*
Y1247243D03*
X324606Y1250984D03*
X317125Y1254724D03*
X313385Y1247243D03*
X317125Y1250984D03*
X313385Y1243503D03*
X317125Y1258465D03*
X320703Y1348187D03*
X312823D03*
X325063D03*
X320703Y1360099D03*
X312823D03*
X325063D03*
X320703Y1372385D03*
Y1384297D03*
X312823Y1372385D03*
Y1384297D03*
X325063Y1372385D03*
Y1384297D03*
Y1396583D03*
X320703D03*
X312823D03*
X320703Y1408495D03*
X312823D03*
X325063D03*
X318448Y1750941D03*
Y1760941D03*
X318348Y1796941D03*
Y1806941D03*
X337303Y1348187D03*
X332943D03*
Y1360099D03*
X337303D03*
X332943Y1384297D03*
Y1372385D03*
X337303D03*
Y1384297D03*
X332943Y1396583D03*
X337303D03*
X332943Y1408495D03*
X337303D03*
X349543Y1348187D03*
X357423D03*
X345183D03*
X349543Y1360099D03*
X357423D03*
X345183D03*
Y1372385D03*
Y1384297D03*
X349543D03*
Y1372385D03*
X357423D03*
Y1384297D03*
X345183Y1396583D03*
X349543D03*
X357423D03*
X345183Y1408495D03*
X349543D03*
X357423D03*
X369663Y1348187D03*
X361783D03*
X369663Y1360099D03*
X361783D03*
X369663Y1372385D03*
Y1384297D03*
X361783D03*
Y1372385D03*
X369663Y1396583D03*
X361783D03*
X369663Y1408495D03*
X361783D03*
X458282Y1348187D03*
X446042D03*
X458282Y1360099D03*
X446042D03*
X458282Y1372385D03*
X446042D03*
X458282Y1384297D03*
X446042D03*
X458282Y1396583D03*
Y1408495D03*
X470522Y1348187D03*
Y1360099D03*
Y1384297D03*
Y1372385D03*
Y1396583D03*
Y1408495D03*
X482762Y1348187D03*
Y1360099D03*
Y1384297D03*
Y1372385D03*
Y1396583D03*
Y1408495D03*
X507242Y1348187D03*
X495002D03*
X507242Y1360099D03*
X495002D03*
Y1384297D03*
X507242D03*
X495002Y1372385D03*
X507242D03*
Y1396583D03*
X495002D03*
X507242Y1408495D03*
X495002D03*
X519482Y1348187D03*
Y1360099D03*
Y1384297D03*
Y1372385D03*
Y1396583D03*
Y1408495D03*
X531722Y1348187D03*
Y1360099D03*
Y1384297D03*
Y1372385D03*
Y1396583D03*
Y1408495D03*
X556202Y1348187D03*
X543962D03*
X556202Y1360099D03*
X543962D03*
Y1372385D03*
Y1384297D03*
X556202D03*
Y1372385D03*
Y1396583D03*
X543962D03*
X556202Y1408495D03*
X543962D03*
X568442Y1348187D03*
Y1360099D03*
Y1384297D03*
Y1372385D03*
Y1396583D03*
Y1408495D03*
X604035Y1080806D03*
Y1103247D03*
X600295D03*
Y1125688D03*
Y1133169D03*
Y1140649D03*
X604035Y1125688D03*
Y1133169D03*
Y1140649D03*
X600295Y1144389D03*
Y1151870D03*
X604035Y1144389D03*
Y1151870D03*
X600295Y1159350D03*
X604035D03*
X597795Y1170570D03*
X604034Y1174310D03*
X597795Y1178050D03*
X602165Y1183661D03*
Y1187401D03*
Y1202362D03*
Y1194881D03*
X598424Y1198622D03*
Y1191142D03*
X602165Y1217322D03*
Y1209842D03*
X598424Y1221063D03*
Y1213583D03*
Y1206103D03*
X602165Y1224803D03*
Y1236023D03*
Y1232283D03*
X605386Y1728583D03*
Y1738583D03*
X605312Y1774624D03*
Y1784624D03*
X607775Y1077066D03*
X615256Y1106988D03*
X618996D03*
X615256Y1118208D03*
Y1121948D03*
X611516D03*
X607776D03*
X618996Y1114468D03*
X615256Y1125688D03*
X611516Y1129429D03*
X607776D03*
Y1136909D03*
X615256Y1140649D03*
X611516D03*
X607776D03*
X618996D03*
Y1144389D03*
Y1148129D03*
Y1151870D03*
Y1155610D03*
X607776Y1144389D03*
Y1148129D03*
Y1151870D03*
X615256Y1155610D03*
X611516D03*
X607776D03*
Y1159350D03*
X615256Y1166830D03*
X607775D03*
X611516Y1170570D03*
X607775D03*
X618996Y1159350D03*
Y1174310D03*
Y1178051D03*
X607775Y1174310D03*
Y1178051D03*
X611516Y1174310D03*
X615256D03*
X613386Y1183661D03*
X617126Y1187401D03*
Y1183661D03*
X613386Y1179921D03*
X620866Y1183661D03*
X609646D03*
X605905D03*
Y1187401D03*
X613386Y1198621D03*
X609646Y1191141D03*
X613386D03*
X617126Y1198621D03*
X620866D03*
X617126Y1191141D03*
X620866D03*
X605905Y1202362D03*
Y1194881D03*
X609646Y1198621D03*
X613386Y1221062D03*
X609646D03*
Y1213582D03*
X613386D03*
X620866Y1206102D03*
X617126D03*
X620866Y1221062D03*
X617126D03*
X613386Y1206102D03*
X605905Y1217322D03*
Y1209842D03*
X609646Y1206102D03*
X605905Y1224803D03*
Y1232283D03*
Y1236023D03*
X620866D03*
Y1232283D03*
X617126Y1224803D03*
X609646D03*
Y1228543D03*
X613386Y1232283D03*
Y1236023D03*
X617126Y1243503D03*
Y1239763D03*
X620866D03*
X609646Y1243503D03*
Y1239763D03*
X617126Y1258465D03*
X609646D03*
X632085Y1071455D03*
X626476Y1092027D03*
X635827Y1090157D03*
X628346D03*
X632086D03*
X630216Y1099507D03*
X626476Y1106988D03*
X622736D03*
X626476Y1095767D03*
X630216Y1103247D03*
X635827Y1093897D03*
X632086Y1101377D03*
Y1105117D03*
X628346Y1093897D03*
X635827Y1097637D03*
X633957Y1110728D03*
X630216D03*
X626476D03*
X622736Y1114468D03*
X630216Y1118208D03*
X626476D03*
X633957Y1114468D03*
Y1118208D03*
Y1121948D03*
X635827Y1108858D03*
X632086D03*
X633957Y1140649D03*
Y1125688D03*
Y1129429D03*
Y1133169D03*
Y1136909D03*
X630216Y1140649D03*
X626476D03*
X622736D03*
Y1129429D03*
X630216Y1144389D03*
X626476D03*
X630216Y1148129D03*
Y1155610D03*
Y1151870D03*
Y1159350D03*
Y1166830D03*
Y1170570D03*
X633957D03*
Y1185531D03*
X628346Y1183661D03*
X630216Y1174310D03*
Y1178051D03*
Y1181791D03*
X632086Y1187401D03*
X628346D03*
X624606Y1183661D03*
X635827Y1187401D03*
X624606Y1191141D03*
X632086Y1202362D03*
X628346D03*
X632086Y1194881D03*
X628346D03*
X635827Y1191141D03*
Y1194881D03*
Y1198621D03*
Y1202362D03*
X624606Y1206102D03*
X628346Y1209842D03*
Y1217322D03*
Y1221062D03*
X632086D03*
Y1217322D03*
X635827Y1221062D03*
Y1206102D03*
Y1209842D03*
Y1213582D03*
Y1217322D03*
X632086Y1224803D03*
X624606D03*
X628346Y1236023D03*
Y1232283D03*
X635827Y1236023D03*
Y1232283D03*
X628346Y1224803D03*
Y1228543D03*
X635827D03*
Y1224803D03*
X632086Y1247243D03*
Y1239763D03*
X628346D03*
Y1250984D03*
X624606Y1243503D03*
Y1239763D03*
X632086Y1254724D03*
X635827Y1243503D03*
X632086Y1250984D03*
X635827Y1247243D03*
X628346Y1243503D03*
Y1247243D03*
X632087Y1258465D03*
X624606D03*
X631928Y1396583D03*
Y1408495D03*
X647046Y1071455D03*
X639566D03*
X643307Y1090157D03*
X639567D03*
X650787D03*
X647047D03*
X639567Y1101377D03*
Y1105117D03*
X647047D03*
Y1101377D03*
X650787Y1097637D03*
X643307D03*
Y1093897D03*
X650787D03*
X637697Y1114468D03*
X648917Y1118208D03*
X645177D03*
X641437D03*
X637697D03*
X648917Y1121948D03*
X645177D03*
X641437D03*
X637697D03*
Y1110728D03*
X652657Y1118208D03*
Y1121948D03*
X650787Y1108858D03*
X647047D03*
X643307D03*
X639567D03*
X641437Y1133169D03*
X637697D03*
X645177Y1136909D03*
X637697D03*
X645177Y1140649D03*
X641437D03*
X652657Y1133169D03*
Y1129429D03*
Y1125688D03*
Y1136909D03*
X637697Y1140649D03*
X648917Y1125688D03*
X645177D03*
X641437D03*
X637697D03*
X645177Y1129429D03*
X641437D03*
X637697D03*
X645177Y1133169D03*
X637697Y1155610D03*
Y1151870D03*
X645177Y1144389D03*
X637697D03*
Y1148129D03*
X645177Y1151870D03*
X648917Y1155610D03*
Y1148129D03*
X652657Y1151869D03*
Y1144389D03*
X645177Y1170570D03*
X637697Y1166830D03*
X645177Y1159350D03*
X637697D03*
X648917Y1166830D03*
X652657Y1159350D03*
Y1170570D03*
X637697Y1189271D03*
X645177Y1185531D03*
X637697D03*
Y1178051D03*
Y1174310D03*
Y1181791D03*
X652657Y1189271D03*
X648917Y1181791D03*
Y1174310D03*
X652657Y1185531D03*
Y1178051D03*
Y1193011D03*
Y1204232D03*
X637697Y1193011D03*
X645177Y1196751D03*
Y1200491D03*
X641437D03*
Y1204232D03*
X645177D03*
X648917D03*
Y1196751D03*
Y1200491D03*
X641437Y1193011D03*
Y1196751D03*
X652657Y1200491D03*
Y1196751D03*
Y1211712D03*
X648917Y1219192D03*
X641437D03*
Y1211712D03*
X645177D03*
X648917D03*
Y1207972D03*
X645177D03*
X641437D03*
X652657D03*
X639567Y1221062D03*
X647047D03*
X643307D03*
X650787D03*
X639567Y1224803D03*
X643307Y1236023D03*
Y1232283D03*
X650787Y1236023D03*
X647047Y1224803D03*
X650787Y1232283D03*
X643307Y1224803D03*
Y1228543D03*
X650787D03*
Y1224803D03*
X639567Y1243503D03*
X647047D03*
X650787Y1239763D03*
X643307D03*
X639567Y1250984D03*
Y1254724D03*
X650787Y1247243D03*
Y1243503D03*
X647047Y1254724D03*
Y1250984D03*
X643307Y1247243D03*
Y1243503D03*
X647047Y1258465D03*
X639567D03*
X644168Y1384297D03*
Y1372385D03*
Y1396583D03*
Y1408495D03*
X669487Y1071455D03*
X662007D03*
X654526D03*
X669488Y1090157D03*
X665748D03*
X654527D03*
X658268D03*
X662008D03*
Y1101377D03*
X665748Y1093897D03*
X658268D03*
X654527Y1105117D03*
Y1101377D03*
X662008Y1105117D03*
X658268Y1097637D03*
X669488Y1101377D03*
Y1105117D03*
X665748Y1097637D03*
X656398Y1118208D03*
Y1121948D03*
X663878Y1118208D03*
X660138D03*
Y1121948D03*
X663878D03*
X667618Y1118208D03*
Y1121948D03*
X669488Y1108858D03*
X665748D03*
X662008D03*
X658268D03*
X654527D03*
X656398Y1140649D03*
X660138D03*
X663878D03*
X656398Y1125688D03*
X660138D03*
X663878D03*
Y1133169D03*
X660138D03*
X656398D03*
X667618D03*
Y1140649D03*
Y1125688D03*
Y1148129D03*
X660138D03*
X656398D03*
X663878D03*
X656398Y1155610D03*
X663878D03*
Y1166830D03*
X660138Y1159350D03*
X656398Y1166830D03*
X660138Y1170570D03*
X667618Y1159350D03*
Y1170570D03*
X663878Y1181791D03*
X660138D03*
X656398D03*
X663878Y1189271D03*
X660138D03*
X656398D03*
X667618Y1181791D03*
Y1189271D03*
X656398Y1174310D03*
X663878D03*
Y1196751D03*
X660138D03*
X656398D03*
Y1204232D03*
X660138D03*
X663878D03*
X667618Y1196751D03*
Y1204232D03*
X663878Y1207972D03*
X660138D03*
X656398D03*
X667618D03*
X654527Y1221062D03*
X658268D03*
X662008D03*
X665748D03*
X669488D03*
X654527Y1224803D03*
X658268Y1236023D03*
Y1232283D03*
X662008Y1224803D03*
X665748Y1236023D03*
Y1232283D03*
X669488Y1224803D03*
X654527Y1239763D03*
Y1243503D03*
X665748Y1239763D03*
X669488Y1243503D03*
X662008D03*
X654527Y1254724D03*
Y1250984D03*
X662008Y1258465D03*
X669488D03*
X654528D03*
X668648Y1348187D03*
X656408D03*
X668648Y1360099D03*
X656408D03*
Y1384297D03*
Y1372385D03*
X668648D03*
Y1384297D03*
Y1396583D03*
X656408D03*
X668648Y1408495D03*
X656408D03*
X684448Y1071455D03*
X676967D03*
X680709Y1090157D03*
X676968D03*
X684449D03*
X673228D03*
X676968Y1105117D03*
X684449Y1101377D03*
Y1105117D03*
X680709Y1093897D03*
X676968Y1101377D03*
X680709Y1097637D03*
X673228D03*
Y1093897D03*
X682579Y1118208D03*
Y1121948D03*
X671358Y1118208D03*
X675098D03*
X678838D03*
X675098Y1121948D03*
X678838D03*
X671358D03*
X684449Y1108858D03*
X680709D03*
X676968D03*
X673228D03*
X682579Y1133169D03*
Y1140649D03*
Y1125688D03*
X671358Y1140649D03*
X675098D03*
X678838D03*
X675098Y1125688D03*
X671358D03*
X678838D03*
Y1133169D03*
X675098D03*
X671358D03*
X682579Y1148129D03*
X678838D03*
X675098D03*
X671358D03*
Y1155610D03*
X678838D03*
X682579Y1170570D03*
Y1159350D03*
X675098Y1170570D03*
X678839Y1166830D03*
X671358D03*
X675098Y1159350D03*
Y1181791D03*
X671358D03*
X678838Y1189271D03*
X675098D03*
X671358D03*
X682579Y1181791D03*
Y1189271D03*
X678838Y1181791D03*
X671358Y1174310D03*
X678838D03*
X682579Y1196751D03*
Y1204232D03*
X678838D03*
Y1196751D03*
X675098D03*
X671358D03*
Y1204232D03*
X675098D03*
X682579Y1207972D03*
X678838Y1219192D03*
Y1207972D03*
X675098D03*
X671358D03*
X673228Y1221062D03*
X676968D03*
X680709D03*
X684449D03*
X673228Y1236023D03*
Y1232283D03*
X676968Y1224803D03*
X680709Y1236023D03*
Y1232283D03*
X684449Y1224803D03*
X673228Y1239763D03*
X680709D03*
X676968Y1243503D03*
X684449D03*
X684450Y1258465D03*
X676969D03*
X680888Y1348187D03*
Y1360099D03*
Y1372385D03*
Y1384297D03*
Y1396583D03*
Y1408495D03*
X695669Y1075196D03*
X699408Y1071455D03*
X691928Y1071454D03*
X688189Y1090157D03*
X691929Y1082677D03*
Y1086417D03*
X695669Y1090157D03*
X699409D03*
Y1086417D03*
X691929Y1090157D03*
X688189Y1097637D03*
X695669Y1093897D03*
X688189D03*
X699409Y1105117D03*
X691929Y1101377D03*
X699409D03*
X691929Y1105117D03*
X693799Y1121948D03*
X697539D03*
X701279D03*
X686319D03*
Y1118208D03*
Y1114468D03*
X699409Y1108858D03*
X695669D03*
X691929D03*
X688189D03*
X693799Y1133464D03*
X697539Y1133169D03*
X686417Y1132677D03*
X693799Y1140649D03*
X697539D03*
X693799Y1125688D03*
X697539D03*
X701279D03*
Y1140649D03*
Y1133169D03*
X686319Y1140649D03*
Y1125688D03*
X697539Y1148129D03*
X701279D03*
X693799D03*
X697539Y1155610D03*
X686319Y1148129D03*
Y1155610D03*
X697539Y1166830D03*
X693799Y1170570D03*
Y1159350D03*
X701279D03*
Y1170570D03*
X686319Y1166830D03*
X693799Y1181791D03*
Y1189271D03*
X697539D03*
X701279D03*
Y1181791D03*
X697539D03*
Y1174310D03*
X686319Y1181791D03*
Y1189271D03*
Y1174310D03*
X697539Y1204232D03*
X693799D03*
Y1196751D03*
X697539D03*
X701279D03*
Y1204232D03*
X686319Y1196751D03*
Y1204232D03*
X693799Y1207972D03*
X697539D03*
Y1211712D03*
X701279Y1207972D03*
Y1211712D03*
X686319Y1207972D03*
X695669Y1221062D03*
X699409D03*
X691929D03*
X688189D03*
Y1236023D03*
Y1232283D03*
X691929Y1224803D03*
Y1228543D03*
X699409Y1224803D03*
Y1228543D03*
X695669Y1236023D03*
Y1232283D03*
X688189Y1239763D03*
X695669D03*
X699409Y1258465D03*
X691929D03*
X693128Y1348187D03*
Y1360099D03*
Y1372385D03*
Y1384297D03*
Y1396583D03*
Y1408495D03*
X703149Y1075196D03*
X718110D03*
X710630D03*
X714369Y1071455D03*
X706889D03*
X710630Y1078936D03*
X706890Y1086417D03*
Y1090157D03*
X718110Y1078936D03*
X714370Y1086417D03*
Y1090157D03*
X710630D03*
X718110D03*
X703149Y1078936D03*
Y1090157D03*
X706890Y1105117D03*
X714370D03*
X710630Y1097637D03*
Y1093897D03*
X718110Y1097637D03*
Y1093897D03*
X703149D03*
Y1097637D03*
X716240Y1121948D03*
X705020D03*
X708760D03*
X712500D03*
X718110Y1108858D03*
X714370D03*
X710630D03*
X706890D03*
X703149D03*
X716240Y1140649D03*
Y1125688D03*
Y1133169D03*
X712500Y1125688D03*
X708760D03*
X705020D03*
X712500Y1140649D03*
X708760D03*
X705020D03*
X712500Y1133169D03*
X708760D03*
X705020D03*
X716240Y1148129D03*
X712500D03*
X708760D03*
X705020D03*
X712500Y1155610D03*
X705020D03*
X716240Y1170570D03*
Y1159350D03*
X708760D03*
X705020Y1166830D03*
X712500D03*
X708760Y1170570D03*
X716240Y1189271D03*
Y1181791D03*
X712500Y1189271D03*
X708760D03*
X705020D03*
X712500Y1181791D03*
X708760D03*
X705020D03*
Y1174310D03*
X712500D03*
X716240Y1196751D03*
Y1204232D03*
X712500Y1196751D03*
X708760D03*
X705020D03*
X708760Y1204232D03*
X712500D03*
X705020D03*
X716240Y1211712D03*
Y1207972D03*
X712500D03*
Y1211712D03*
X708760Y1207972D03*
X705020D03*
X703149Y1221062D03*
X706890D03*
X710630D03*
X714370D03*
X718110D03*
X703149Y1236023D03*
Y1232283D03*
X710630Y1236023D03*
X718110D03*
Y1232283D03*
X710630D03*
X714370Y1224803D03*
Y1228543D03*
X706890Y1224803D03*
Y1228543D03*
X703149Y1239763D03*
X714370D03*
X718110Y1243503D03*
Y1247243D03*
X714370Y1258465D03*
X706890D03*
X705368Y1348187D03*
X717608D03*
X705368Y1360099D03*
X717608D03*
X705368Y1372385D03*
Y1384297D03*
X717608Y1372385D03*
Y1384297D03*
Y1396583D03*
X705368D03*
X717608Y1408495D03*
X705368D03*
X725590Y1075196D03*
X733071D03*
X729330Y1071455D03*
X721849D03*
X729331Y1086417D03*
Y1082677D03*
X733071Y1090157D03*
X729331D03*
X725590D03*
X721850D03*
X725590Y1078936D03*
X721850Y1086417D03*
X725590Y1097637D03*
X721850Y1105117D03*
X725590Y1093897D03*
X729331Y1105117D03*
X733071Y1093897D03*
X734941Y1118208D03*
X727460Y1121948D03*
X719980D03*
X723720D03*
X727460Y1118208D03*
X731201D03*
X733071Y1108858D03*
X729331D03*
X725590D03*
X721850D03*
X734941Y1140649D03*
Y1136909D03*
X727460Y1140649D03*
X723720Y1125688D03*
X719980D03*
X727460Y1129429D03*
Y1125688D03*
X723720Y1140649D03*
X719980D03*
X727460Y1133169D03*
X723720D03*
X719980D03*
X727460Y1136909D03*
X731201Y1125688D03*
X727460Y1151869D03*
Y1148129D03*
Y1144389D03*
X723720Y1148129D03*
X719980D03*
X731201D03*
Y1151869D03*
Y1155610D03*
X734941Y1151870D03*
Y1148129D03*
Y1144389D03*
X719980Y1155610D03*
X727460D03*
X731201Y1170570D03*
X719980Y1166830D03*
X731201Y1159350D03*
Y1166830D03*
X727460Y1185531D03*
X734941Y1181791D03*
Y1185531D03*
Y1189271D03*
Y1178051D03*
X727460Y1189271D03*
X723720Y1181791D03*
X719980D03*
Y1174310D03*
X727460Y1178051D03*
X723720Y1189271D03*
X719980D03*
X731201Y1174310D03*
Y1181791D03*
X727460Y1174310D03*
X719980Y1204232D03*
X727460D03*
X727480Y1196732D03*
X731201Y1196751D03*
X734941Y1193011D03*
X727460D03*
X723720Y1196751D03*
X719980D03*
X727460Y1200491D03*
X723720Y1204232D03*
X734941Y1211712D03*
X727460Y1207972D03*
X723720Y1211712D03*
Y1207972D03*
X719980Y1211712D03*
Y1207972D03*
X727460Y1211712D03*
X731201Y1207972D03*
X733071Y1221062D03*
X721850D03*
X725590D03*
X729331D03*
Y1224803D03*
Y1228543D03*
X733071Y1236023D03*
Y1232283D03*
X725590Y1236023D03*
Y1232283D03*
X721850Y1224803D03*
Y1228543D03*
X725590Y1239763D03*
X733071Y1247243D03*
X725590Y1243503D03*
X733071D03*
X725590Y1247243D03*
X729331Y1258465D03*
X721850D03*
X729848Y1348187D03*
Y1360099D03*
Y1372385D03*
Y1384297D03*
Y1396489D03*
Y1408401D03*
X740551Y1075196D03*
X748031D03*
X744290Y1071455D03*
X736810D03*
X748030Y1090157D03*
X744291D03*
X740551Y1078936D03*
Y1090157D03*
X736811D03*
X744291Y1101377D03*
X748031Y1093897D03*
X744291Y1105117D03*
X736811D03*
X748031Y1123818D03*
Y1120078D03*
Y1116338D03*
Y1112598D03*
Y1108858D03*
X744291D03*
X740551D03*
X736811D03*
X738681Y1136909D03*
Y1140649D03*
X748031Y1138779D03*
Y1135039D03*
Y1131299D03*
Y1127558D03*
X738681Y1155610D03*
Y1148129D03*
X749901Y1144389D03*
Y1151869D03*
X746161Y1155610D03*
Y1151869D03*
X742421D03*
X738681D03*
Y1166830D03*
X746161Y1170570D03*
Y1166830D03*
X738681Y1159350D03*
X749901Y1166830D03*
Y1159350D03*
X738681Y1170570D03*
X746161Y1159350D03*
X749901Y1181791D03*
Y1174310D03*
X738681D03*
Y1178051D03*
X742421Y1181791D03*
X738681Y1185531D03*
Y1189271D03*
X746161Y1185531D03*
Y1178051D03*
Y1174310D03*
X742421Y1185531D03*
X748031Y1191141D03*
X738681Y1204232D03*
Y1193011D03*
Y1196751D03*
X742421Y1193011D03*
X748031Y1202362D03*
Y1198621D03*
X736811Y1221062D03*
X740551D03*
X748031D03*
X744291D03*
X748031Y1217322D03*
Y1213582D03*
Y1209842D03*
Y1206102D03*
X736811Y1224803D03*
Y1228543D03*
X748031Y1236023D03*
Y1232283D03*
X740551Y1236023D03*
X744291Y1228543D03*
X740551Y1232283D03*
X744291Y1224803D03*
X748031Y1239763D03*
X740551D03*
Y1243503D03*
Y1247243D03*
X744291Y1258465D03*
X736811D03*
X742088Y1348187D03*
Y1360099D03*
Y1384297D03*
Y1372385D03*
Y1396489D03*
Y1408401D03*
X755512Y1075196D03*
X762993D03*
X766732Y1071455D03*
X759252D03*
X751771D03*
X755511Y1090157D03*
X762993Y1078936D03*
X755513D03*
X751772Y1105117D03*
X762992Y1093897D03*
X759252Y1105117D03*
X766732D03*
X755512Y1093897D03*
X762991Y1108857D03*
X755512Y1108858D03*
X751772D03*
X759252Y1116338D03*
Y1123818D03*
X751771Y1112598D03*
Y1120078D03*
X757382Y1140649D03*
X759252Y1131299D03*
X757382Y1148129D03*
X764862Y1170570D03*
X757382Y1166830D03*
Y1159350D03*
Y1174310D03*
Y1181791D03*
X764862Y1185531D03*
Y1178051D03*
X755512Y1187401D03*
X764862Y1189271D03*
X766732Y1194881D03*
X751772D03*
X755512Y1202362D03*
X766732D03*
Y1198621D03*
X762992D03*
X766732Y1221062D03*
Y1217322D03*
X762992Y1221062D03*
X759252D03*
X762992Y1213582D03*
X766732D03*
Y1209842D03*
X755512D03*
X766732Y1206102D03*
X751772Y1221062D03*
Y1217322D03*
X759252Y1224803D03*
Y1228543D03*
X755512Y1232283D03*
Y1236023D03*
X766732Y1224803D03*
Y1228543D03*
X762992Y1232283D03*
Y1236023D03*
X751772Y1224803D03*
Y1228543D03*
X755512Y1239763D03*
X766732D03*
Y1258465D03*
X759252D03*
X751772D03*
X766568Y1348187D03*
X754328D03*
X766568Y1360099D03*
X754328D03*
Y1372385D03*
Y1384297D03*
X766568Y1372385D03*
Y1384297D03*
X777953Y1075196D03*
X770473D03*
X774212Y1071455D03*
X777953Y1078936D03*
X781693D03*
X770473D03*
X770471Y1090157D03*
X770472Y1093897D03*
Y1108858D03*
X776083Y1140649D03*
Y1148129D03*
Y1155610D03*
Y1170570D03*
X768602Y1166830D03*
X779823Y1170570D03*
X776083Y1178051D03*
Y1185531D03*
X779823D03*
Y1178051D03*
X768602Y1181791D03*
Y1174310D03*
X772342Y1189271D03*
X783503Y1193011D03*
X776083D03*
X779823D03*
X781693Y1202362D03*
X777953D03*
X770472Y1221062D03*
X777953Y1209842D03*
X774212Y1224803D03*
Y1228543D03*
X770472Y1236023D03*
Y1232283D03*
X777953D03*
X781693Y1250984D03*
X774212Y1258465D03*
X778808Y1348187D03*
Y1360099D03*
X785434Y1090158D03*
Y1082677D03*
Y1101378D03*
Y1123819D03*
Y1116339D03*
Y1108859D03*
Y1131300D03*
Y1198621D03*
Y1221062D03*
Y1213582D03*
Y1206102D03*
Y1228543D03*
Y1247243D03*
Y1239762D03*
X892183Y1728286D03*
Y1738286D03*
X891761Y1775438D03*
Y1785438D03*
X1057381Y1103247D03*
Y1140649D03*
Y1133169D03*
Y1125688D03*
Y1151870D03*
Y1144389D03*
X1054881Y1170570D03*
X1057381Y1159350D03*
X1054881Y1178050D03*
X1059251Y1187401D03*
Y1183661D03*
Y1194881D03*
Y1202362D03*
X1055510Y1198622D03*
Y1191142D03*
X1059251Y1209842D03*
Y1217322D03*
X1055510Y1221063D03*
Y1213583D03*
Y1206103D03*
X1059251Y1232283D03*
Y1236023D03*
Y1224803D03*
X1052473Y1348187D03*
Y1360099D03*
Y1384297D03*
Y1372385D03*
X1064861Y1077066D03*
X1061121Y1080806D03*
X1072342Y1106988D03*
X1061121Y1103247D03*
X1072342Y1121948D03*
Y1118208D03*
X1064862Y1121948D03*
X1068602D03*
X1072342Y1140649D03*
Y1125688D03*
X1061121D03*
Y1140649D03*
X1064862D03*
X1068602D03*
X1064862Y1136909D03*
X1061121Y1133169D03*
X1064862Y1129429D03*
X1068602D03*
X1072342Y1155610D03*
X1064862D03*
X1068602D03*
X1061121Y1151870D03*
X1064862D03*
Y1148129D03*
X1061121Y1144389D03*
X1064862D03*
X1072342Y1166830D03*
X1064861Y1170570D03*
X1068602D03*
X1064861Y1166830D03*
X1061121Y1159350D03*
X1064862D03*
X1072342Y1181791D03*
Y1174310D03*
X1061120Y1181791D03*
X1064861D03*
X1068602D03*
Y1174310D03*
X1064861Y1178051D03*
X1061120Y1174310D03*
X1064861D03*
X1074212Y1187401D03*
X1062991D03*
Y1183661D03*
X1066732D03*
X1070472D03*
X1074212D03*
Y1191141D03*
Y1198621D03*
X1070472Y1191141D03*
X1066732D03*
X1070472Y1198621D03*
X1066732D03*
X1062991Y1194881D03*
Y1202362D03*
X1074212Y1206102D03*
X1066732D03*
X1070472D03*
Y1213582D03*
X1066732D03*
X1062991Y1209842D03*
Y1217322D03*
X1074212Y1221062D03*
X1066732D03*
X1070472D03*
Y1236023D03*
Y1232283D03*
X1066732Y1228543D03*
Y1224803D03*
X1074212D03*
X1062991Y1236023D03*
Y1232283D03*
Y1224803D03*
X1066732Y1239763D03*
Y1243503D03*
X1074212Y1239763D03*
Y1243503D03*
Y1258465D03*
X1066732D03*
X1072593Y1348187D03*
X1064713D03*
X1060353D03*
X1072593Y1360099D03*
X1064713D03*
X1060353D03*
X1072593Y1384297D03*
Y1372385D03*
X1064713D03*
Y1384297D03*
X1060353D03*
Y1372385D03*
X1072593Y1396583D03*
X1064713D03*
X1072593Y1408495D03*
X1064713D03*
X1089171Y1071455D03*
X1083562Y1092027D03*
X1089172Y1090157D03*
X1083562Y1095767D03*
X1087302Y1106988D03*
X1079822D03*
X1083562D03*
X1076082D03*
X1089172Y1101377D03*
Y1105117D03*
X1083562Y1118208D03*
X1087302D03*
X1079822Y1114468D03*
X1083562Y1110728D03*
X1087302D03*
X1091043D03*
Y1121948D03*
Y1118208D03*
Y1114468D03*
X1076082D03*
X1089172Y1108858D03*
X1091043Y1125688D03*
Y1140649D03*
X1079822Y1129429D03*
Y1140649D03*
X1083562D03*
X1087302D03*
X1091043Y1136909D03*
Y1133169D03*
Y1129429D03*
X1076082Y1140649D03*
X1087302Y1151870D03*
Y1155610D03*
Y1148129D03*
X1083562Y1144389D03*
X1087302D03*
X1076082Y1155610D03*
Y1151870D03*
Y1148129D03*
Y1144389D03*
X1087302Y1170570D03*
Y1166830D03*
Y1159350D03*
X1091043Y1170570D03*
X1076082Y1159350D03*
X1081692Y1179921D03*
X1083562Y1181791D03*
X1087302D03*
Y1178051D03*
Y1174310D03*
X1076082Y1181791D03*
Y1178051D03*
Y1174310D03*
X1077952Y1183661D03*
X1081692D03*
X1085432D03*
X1089172Y1187401D03*
X1085432D03*
X1091043Y1185531D03*
X1077952Y1191141D03*
Y1198621D03*
X1081692Y1191141D03*
X1085432Y1194881D03*
X1089172D03*
X1085432Y1202362D03*
X1089172D03*
X1077952Y1206102D03*
X1081692D03*
X1085432Y1209842D03*
X1077952Y1221062D03*
X1089172Y1217322D03*
Y1221062D03*
X1085432D03*
Y1217322D03*
X1077952Y1232283D03*
Y1236023D03*
X1085432Y1232283D03*
Y1236023D03*
X1081692Y1224803D03*
X1089172D03*
X1085432D03*
Y1228543D03*
X1077952Y1239763D03*
X1081692D03*
Y1243503D03*
X1085432Y1250984D03*
Y1239763D03*
X1089172D03*
Y1247243D03*
X1089173Y1258465D03*
X1081692D03*
X1089193Y1348187D03*
X1084833D03*
X1076953D03*
X1089193Y1360099D03*
X1084833D03*
X1076953D03*
X1089193Y1384297D03*
Y1372385D03*
X1084833Y1384297D03*
Y1372385D03*
X1076953Y1384297D03*
Y1372385D03*
X1089193Y1396583D03*
X1084833D03*
X1076953D03*
X1089193Y1408495D03*
X1084833D03*
X1076953D03*
X1104132Y1071455D03*
X1096652D03*
X1092913Y1090157D03*
X1104133D03*
X1107873D03*
X1100393D03*
X1096653D03*
X1092913Y1093897D03*
Y1097637D03*
X1107873Y1093897D03*
Y1097637D03*
X1104133Y1101377D03*
X1100393Y1097637D03*
Y1093897D03*
X1096653Y1101377D03*
X1104133Y1105117D03*
X1096653D03*
X1094783Y1110728D03*
Y1121948D03*
X1098523D03*
X1102263D03*
X1106003D03*
X1094783Y1118208D03*
X1098523D03*
X1102263D03*
X1106003D03*
X1094783Y1114468D03*
X1107873Y1108858D03*
X1104133D03*
X1100393D03*
X1096653D03*
X1092913D03*
X1098523Y1140649D03*
X1102263D03*
X1094783Y1136909D03*
X1102263D03*
X1094783Y1133169D03*
X1098523D03*
X1102263D03*
X1094783Y1129429D03*
X1098523D03*
X1102263D03*
X1094783Y1125688D03*
X1098523D03*
X1102263D03*
X1106003D03*
X1094783Y1140649D03*
Y1151870D03*
Y1155610D03*
X1102263Y1151870D03*
X1094783Y1148129D03*
Y1144389D03*
X1102263D03*
X1106003Y1148129D03*
Y1155610D03*
X1102263Y1170570D03*
X1094783Y1159350D03*
X1102263D03*
X1094783Y1166830D03*
X1106003D03*
X1094783Y1181791D03*
X1102263Y1185531D03*
X1094783Y1174310D03*
Y1178051D03*
X1106003Y1181791D03*
Y1174310D03*
X1092913Y1187401D03*
X1098523Y1196751D03*
Y1193011D03*
X1106003Y1200491D03*
Y1196751D03*
Y1204232D03*
X1102263D03*
X1098523D03*
Y1200491D03*
X1102263D03*
Y1196751D03*
X1092913Y1191141D03*
Y1194881D03*
Y1198621D03*
Y1202362D03*
X1098523Y1207972D03*
X1102263D03*
X1106003D03*
Y1211712D03*
X1102263D03*
X1098523D03*
Y1219192D03*
X1106003D03*
X1092913Y1206102D03*
Y1209842D03*
Y1213582D03*
Y1217322D03*
X1107873Y1221062D03*
X1104133D03*
X1100393D03*
X1096653D03*
X1092913D03*
Y1232283D03*
Y1236023D03*
X1107873Y1232283D03*
X1104133Y1224803D03*
X1107873Y1236023D03*
X1100393Y1232283D03*
Y1236023D03*
X1096653Y1224803D03*
X1100393Y1228543D03*
X1092913Y1224803D03*
X1107873D03*
X1100393D03*
X1107873Y1228543D03*
X1092913D03*
X1100393Y1239763D03*
X1107873D03*
X1104133Y1243503D03*
X1096653D03*
X1104133Y1258465D03*
X1096653D03*
X1101433Y1348187D03*
X1097073D03*
X1101433Y1360099D03*
X1097073D03*
X1101433Y1384297D03*
Y1372385D03*
X1097073D03*
Y1384297D03*
X1101433Y1396583D03*
X1097073D03*
X1101433Y1408495D03*
X1097073D03*
X1119093Y1071455D03*
X1111612D03*
X1115354Y1090157D03*
X1119094D03*
X1122834D03*
X1111613D03*
X1122834Y1093897D03*
X1115354D03*
X1122834Y1097637D03*
X1115354D03*
X1119094Y1101377D03*
X1111613D03*
X1119094Y1105117D03*
X1111613D03*
X1117224Y1121948D03*
Y1118208D03*
X1120964D03*
X1109743Y1121948D03*
X1113484D03*
X1109743Y1118208D03*
X1113484D03*
X1124704Y1121948D03*
Y1118208D03*
X1120964Y1121948D03*
X1122834Y1108858D03*
X1119094D03*
X1115354D03*
X1111613D03*
X1109743Y1136909D03*
X1124704Y1125688D03*
Y1140649D03*
Y1133169D03*
X1113484D03*
X1117224D03*
X1120964D03*
X1109743Y1125688D03*
X1120964D03*
X1117224D03*
X1113484D03*
X1120964Y1140649D03*
X1117224D03*
X1113484D03*
X1109743Y1129429D03*
Y1133169D03*
X1113484Y1155610D03*
X1109743Y1144389D03*
X1120964Y1155610D03*
X1109743Y1151869D03*
X1120964Y1148129D03*
X1113484D03*
X1117224D03*
X1124704D03*
X1117224Y1170570D03*
X1109743D03*
X1113484Y1166830D03*
X1117224Y1159350D03*
X1120964Y1166830D03*
X1109743Y1159350D03*
X1124704Y1170570D03*
Y1159350D03*
X1109743Y1189271D03*
X1113484D03*
X1117224D03*
X1120964D03*
X1113484Y1181791D03*
X1117224D03*
X1120964D03*
X1124704Y1189271D03*
Y1181791D03*
X1109743Y1178051D03*
X1120964Y1174310D03*
X1109743Y1185531D03*
X1113484Y1174310D03*
X1124704Y1204232D03*
Y1196751D03*
X1120964Y1204232D03*
X1117224D03*
X1113484D03*
X1109743D03*
Y1193011D03*
Y1196751D03*
Y1200491D03*
X1113484Y1196751D03*
X1117224D03*
X1120964D03*
X1113484Y1207972D03*
X1117224D03*
X1120964D03*
X1109743Y1211712D03*
Y1207972D03*
X1124704D03*
X1122834Y1221062D03*
X1119094D03*
X1115354D03*
X1111613D03*
X1122834Y1224803D03*
Y1232283D03*
Y1236023D03*
X1119094Y1224803D03*
X1115354Y1232283D03*
Y1236023D03*
X1111613Y1224803D03*
X1115354Y1228543D03*
Y1224803D03*
X1122834Y1228543D03*
X1119094Y1243503D03*
X1122834Y1239763D03*
X1111613Y1243503D03*
Y1239763D03*
X1119094Y1258465D03*
X1111614D03*
X1113673Y1348187D03*
X1121553D03*
X1109313D03*
X1113673Y1360099D03*
X1121553D03*
X1109313D03*
X1113673Y1372385D03*
Y1384297D03*
X1121553Y1372385D03*
Y1384297D03*
X1109313D03*
Y1372385D03*
X1113673Y1396583D03*
X1121553D03*
X1109313D03*
X1113673Y1408495D03*
X1121553D03*
X1109313D03*
X1134053Y1071455D03*
X1126573D03*
X1126574Y1090157D03*
X1130314D03*
X1134054D03*
X1137795D03*
X1126574Y1101377D03*
X1130314Y1097637D03*
Y1093897D03*
X1137795D03*
Y1097637D03*
X1134054Y1101377D03*
X1126574Y1105117D03*
X1134054D03*
X1139665Y1121948D03*
X1130314Y1112598D03*
X1128444Y1118208D03*
X1132184D03*
X1135924D03*
X1132184Y1121948D03*
X1135924D03*
X1128444D03*
X1139665Y1118208D03*
X1137795Y1108858D03*
X1134054D03*
X1130314D03*
X1126574D03*
X1139665Y1125688D03*
X1128444Y1140649D03*
X1132184D03*
X1135924D03*
X1132184Y1125688D03*
X1128444D03*
X1135924D03*
Y1133169D03*
X1132184D03*
X1128444D03*
X1139665D03*
Y1140649D03*
X1135924Y1148129D03*
X1132184D03*
X1128444D03*
X1139665D03*
X1128444Y1155610D03*
X1135924D03*
X1139665Y1170570D03*
Y1159350D03*
X1132184Y1170570D03*
X1135925Y1166830D03*
X1128444D03*
X1132184Y1159350D03*
X1135924Y1181791D03*
X1132184D03*
X1128444D03*
X1135924Y1189271D03*
X1132184D03*
X1128444D03*
Y1174310D03*
X1135924D03*
X1139665Y1181791D03*
Y1189271D03*
Y1196751D03*
Y1204232D03*
X1135924D03*
Y1196751D03*
X1132184D03*
X1128444D03*
Y1204232D03*
X1132184D03*
X1139665Y1207972D03*
X1134054Y1217322D03*
X1135924Y1207972D03*
X1132184D03*
X1128444D03*
X1137795Y1221062D03*
X1134054D03*
X1130314D03*
X1126574D03*
Y1224803D03*
X1137795Y1232283D03*
Y1236023D03*
X1134054Y1224803D03*
X1130314Y1232283D03*
Y1236023D03*
X1137795Y1228543D03*
Y1224803D03*
X1130314Y1228543D03*
Y1224803D03*
X1126574Y1243503D03*
X1134054D03*
X1137795Y1239763D03*
X1130314D03*
X1134055Y1258465D03*
X1126574D03*
X1138153Y1348187D03*
X1133793D03*
X1125913D03*
X1138153Y1360099D03*
X1133793D03*
X1125913D03*
X1138153Y1384297D03*
Y1372385D03*
X1133793Y1384297D03*
Y1372385D03*
X1125913Y1384297D03*
Y1372385D03*
X1138153Y1396583D03*
X1133793D03*
X1125913D03*
X1138153Y1408495D03*
X1133793D03*
X1125913D03*
X1152755Y1075196D03*
X1156494Y1071455D03*
X1149014Y1071454D03*
X1141534Y1071455D03*
X1141535Y1090157D03*
X1149015Y1082677D03*
Y1086417D03*
X1152755Y1090157D03*
X1156495D03*
Y1086417D03*
X1149015Y1090157D03*
X1145275D03*
X1141535Y1101377D03*
X1149015D03*
X1152755Y1093897D03*
X1156495Y1101377D03*
X1145275Y1093897D03*
Y1097637D03*
X1141535Y1105117D03*
X1149015D03*
X1156495D03*
X1150885Y1121948D03*
X1143405D03*
Y1118208D03*
Y1114468D03*
X1154625Y1121948D03*
X1156495Y1108858D03*
X1152755D03*
X1149015D03*
X1145275D03*
X1141535D03*
X1154625Y1125688D03*
X1150885Y1133464D03*
X1154625Y1133169D03*
X1143503Y1132677D03*
X1143405Y1140649D03*
Y1125688D03*
X1150885Y1140649D03*
X1154625D03*
X1150885Y1125688D03*
X1143405Y1148129D03*
X1150885D03*
X1154625D03*
X1143405Y1155610D03*
X1154625D03*
Y1166830D03*
X1150885Y1170570D03*
X1143405Y1166830D03*
X1150885Y1159350D03*
X1143405Y1181791D03*
X1154625D03*
X1150885D03*
Y1189271D03*
X1154625D03*
X1143405D03*
Y1174310D03*
X1154625D03*
X1150885Y1196751D03*
X1154625Y1204232D03*
X1150885D03*
X1154625Y1196751D03*
X1143405D03*
Y1204232D03*
X1150885Y1207972D03*
X1154625D03*
Y1211712D03*
X1143405Y1207972D03*
X1149015Y1221062D03*
X1156495D03*
X1152755D03*
X1145275D03*
X1141535D03*
Y1224803D03*
X1152755Y1232283D03*
Y1236023D03*
X1156495Y1228543D03*
Y1224803D03*
X1149015Y1228543D03*
Y1224803D03*
X1145275Y1232283D03*
Y1236023D03*
X1141535Y1243503D03*
X1152755Y1239763D03*
X1145275D03*
X1156495Y1258465D03*
X1149015D03*
X1141536D03*
X1150393Y1348187D03*
X1146033D03*
X1150393Y1360099D03*
X1146033D03*
X1150393Y1384297D03*
Y1372385D03*
X1146033D03*
Y1384297D03*
X1150393Y1396583D03*
X1146033D03*
X1150393Y1408495D03*
X1146033D03*
X1167716Y1075196D03*
X1160235D03*
X1171455Y1071455D03*
X1163975D03*
X1167716Y1078936D03*
X1163976Y1086417D03*
Y1090157D03*
X1171456Y1086417D03*
Y1090157D03*
X1167716D03*
X1160235Y1078936D03*
Y1090157D03*
X1167716Y1097637D03*
Y1093897D03*
X1160235D03*
Y1097637D03*
X1163976Y1105117D03*
X1171456D03*
X1169586Y1121948D03*
X1165846D03*
X1162106D03*
X1158365D03*
X1173326D03*
X1171456Y1108858D03*
X1167716D03*
X1163976D03*
X1160235D03*
X1162106Y1133169D03*
X1165846D03*
X1169586D03*
X1158365Y1140649D03*
X1162106D03*
X1165846D03*
X1169586D03*
X1158365Y1125688D03*
X1162106D03*
X1165846D03*
X1169586D03*
X1173326Y1133169D03*
Y1125688D03*
Y1140649D03*
X1158365Y1133169D03*
X1173326Y1148129D03*
X1158365D03*
X1162106D03*
X1165846D03*
X1169586D03*
X1162106Y1155610D03*
X1169586D03*
X1158365Y1170570D03*
X1165846D03*
X1169586Y1166830D03*
X1158365Y1159350D03*
X1162106Y1166830D03*
X1165846Y1159350D03*
X1173326D03*
Y1170570D03*
Y1189271D03*
X1158365Y1181791D03*
X1162106D03*
X1165846D03*
X1169586D03*
X1158365Y1189271D03*
X1162106D03*
X1165846D03*
X1169586D03*
X1173326Y1181791D03*
X1169586Y1174310D03*
X1162106D03*
Y1204232D03*
X1158365D03*
X1169586D03*
X1165846D03*
X1158365Y1196751D03*
X1162106D03*
X1165846D03*
X1169586D03*
X1173326Y1204232D03*
Y1196751D03*
X1158365Y1211712D03*
Y1207972D03*
X1173326D03*
Y1211712D03*
X1162106Y1207972D03*
X1165846D03*
X1169586Y1211712D03*
Y1207972D03*
X1171456Y1221062D03*
X1167716D03*
X1163976D03*
X1160235D03*
X1163976Y1228543D03*
Y1224803D03*
X1171456Y1228543D03*
Y1224803D03*
X1167716Y1232283D03*
Y1236023D03*
X1160235Y1232283D03*
Y1236023D03*
X1171456Y1239763D03*
X1160235D03*
X1171456Y1258465D03*
X1163976D03*
X1162633Y1348187D03*
X1170513D03*
X1158273D03*
X1162633Y1360099D03*
X1170513D03*
X1158273D03*
X1162633Y1372385D03*
Y1384297D03*
X1170513Y1372385D03*
Y1384297D03*
X1158273D03*
Y1372385D03*
X1162633Y1396583D03*
X1170513D03*
X1158273D03*
X1162633Y1408495D03*
X1170513D03*
X1158273D03*
X1175196Y1075196D03*
X1182676D03*
X1186416Y1071455D03*
X1178935D03*
X1175196Y1078936D03*
Y1090157D03*
X1178936D03*
X1182676Y1078936D03*
X1178936Y1086417D03*
X1182676Y1090157D03*
X1186417D03*
Y1086417D03*
Y1082677D03*
X1175196Y1097637D03*
Y1093897D03*
X1182676Y1097637D03*
Y1093897D03*
X1178936Y1105117D03*
X1186417D03*
X1188287Y1118208D03*
X1184546D03*
X1180806Y1121948D03*
X1177066D03*
X1184546D03*
X1186417Y1108858D03*
X1182676D03*
X1178936D03*
X1175196D03*
X1188287Y1125688D03*
X1184546Y1136909D03*
X1177066Y1133169D03*
X1180806D03*
X1184546D03*
X1177066Y1140649D03*
X1180806D03*
X1184546Y1125688D03*
Y1129429D03*
X1177066Y1125688D03*
X1180806D03*
X1184546Y1140649D03*
X1188287Y1155610D03*
Y1151869D03*
Y1148129D03*
X1177066D03*
X1180806D03*
X1184546Y1144389D03*
Y1148129D03*
Y1151869D03*
X1177066Y1155610D03*
X1184546D03*
X1177066Y1166830D03*
X1188287D03*
Y1159350D03*
Y1170570D03*
Y1181791D03*
Y1174310D03*
X1177066Y1189271D03*
X1180806D03*
X1184546Y1178051D03*
X1177066Y1174310D03*
X1184546Y1185531D03*
X1177066Y1181791D03*
X1180806D03*
X1184546Y1189271D03*
Y1174310D03*
Y1204232D03*
X1177066D03*
X1180806D03*
X1184546Y1200491D03*
X1177066Y1196751D03*
X1180806D03*
X1184546Y1193011D03*
X1188287Y1196751D03*
X1184566Y1196732D03*
X1188287Y1207972D03*
X1184546Y1211712D03*
X1177066Y1207972D03*
Y1211712D03*
X1180806Y1207972D03*
Y1211712D03*
X1184546Y1207972D03*
X1186417Y1221062D03*
X1182676D03*
X1178936D03*
X1175196D03*
Y1232283D03*
Y1236023D03*
X1178936Y1228543D03*
Y1224803D03*
X1182676Y1232283D03*
Y1236023D03*
X1186417Y1228543D03*
Y1224803D03*
X1182676Y1239763D03*
X1186417Y1258465D03*
X1178936D03*
X1182753Y1348187D03*
X1174873D03*
X1182753Y1360099D03*
X1174873D03*
X1182753Y1384297D03*
Y1372385D03*
X1174873Y1384297D03*
Y1372385D03*
X1182753Y1396583D03*
X1174873D03*
X1182753Y1408495D03*
X1174873D03*
X1179329Y1728990D03*
Y1738990D03*
X1179123Y1776014D03*
Y1786014D03*
X1190157Y1075196D03*
X1197637D03*
X1205117D03*
X1201376Y1071455D03*
X1193896D03*
X1190157Y1090157D03*
X1197637Y1078936D03*
Y1090157D03*
X1201377D03*
X1205116D03*
X1193897D03*
X1190157Y1093897D03*
X1201377Y1101377D03*
X1205117Y1093897D03*
X1201377Y1105117D03*
X1193897D03*
X1192027Y1118208D03*
X1205117Y1123818D03*
Y1120078D03*
Y1116338D03*
Y1108858D03*
X1201377D03*
X1197637D03*
X1193897D03*
X1190157D03*
X1192027Y1136909D03*
X1195767Y1140649D03*
X1192027D03*
X1195767Y1136909D03*
X1205117Y1135039D03*
Y1131299D03*
Y1127558D03*
X1195767Y1148129D03*
X1192027Y1144389D03*
X1195767Y1155610D03*
X1192027Y1148129D03*
X1195767Y1151869D03*
X1199507D03*
X1203247D03*
Y1155610D03*
X1192027Y1151870D03*
X1195767Y1170570D03*
Y1159350D03*
X1203247Y1166830D03*
Y1170570D03*
Y1159350D03*
X1195767Y1166830D03*
X1192027Y1181791D03*
X1199507Y1185531D03*
X1203247Y1174310D03*
Y1178051D03*
Y1185531D03*
X1192027Y1178051D03*
Y1189271D03*
X1195767D03*
X1192027Y1185531D03*
X1195767D03*
X1199507Y1181791D03*
X1195767Y1178051D03*
Y1174310D03*
Y1204232D03*
X1199507Y1193011D03*
X1195767Y1196751D03*
Y1193011D03*
X1192027D03*
X1205117Y1198621D03*
Y1202362D03*
X1192027Y1211712D03*
X1205117Y1206102D03*
Y1209842D03*
Y1213582D03*
Y1217322D03*
Y1221062D03*
X1201377D03*
X1197637D03*
X1193897D03*
X1190157D03*
Y1232283D03*
Y1236023D03*
X1197637Y1232283D03*
X1201377Y1228543D03*
X1197637Y1236023D03*
X1201377Y1224803D03*
X1205117Y1232283D03*
Y1236023D03*
X1193897Y1228543D03*
Y1224803D03*
X1197637Y1239763D03*
X1205117D03*
Y1243503D03*
Y1247243D03*
X1201377Y1258465D03*
X1193897D03*
X1212598Y1075196D03*
X1220079D03*
X1216338Y1071455D03*
X1208857D03*
X1220079Y1078936D03*
X1212599D03*
X1212597Y1090157D03*
X1212598Y1093897D03*
X1220078D03*
X1216338Y1105117D03*
X1208858D03*
X1212598Y1108858D03*
X1216338Y1116338D03*
Y1123818D03*
X1208857Y1112598D03*
Y1120078D03*
X1220077Y1108857D03*
X1208858Y1108858D03*
X1214468Y1140649D03*
X1206987Y1136909D03*
X1216338Y1131299D03*
X1206987Y1151869D03*
X1214468Y1148129D03*
X1206987Y1144389D03*
Y1159350D03*
X1214468D03*
X1206987Y1166830D03*
X1214468D03*
X1221948Y1170570D03*
X1206987Y1181791D03*
X1214468Y1189271D03*
X1221948Y1178051D03*
Y1185531D03*
X1206987Y1174310D03*
Y1189271D03*
X1214468Y1181791D03*
Y1174310D03*
X1208858Y1194881D03*
X1221948Y1193011D03*
X1212598Y1202362D03*
X1220078Y1198621D03*
Y1221062D03*
X1216338D03*
X1220078Y1213582D03*
X1212598Y1209842D03*
X1208858Y1221062D03*
Y1217322D03*
X1216338Y1224803D03*
Y1228543D03*
X1212598Y1232283D03*
Y1236023D03*
X1220078Y1232283D03*
Y1236023D03*
X1208858Y1224803D03*
Y1228543D03*
X1212598Y1239763D03*
Y1243503D03*
X1220078Y1247243D03*
Y1243503D03*
X1212598Y1247243D03*
X1208858Y1254724D03*
Y1250984D03*
X1216338Y1254724D03*
Y1250984D03*
Y1258465D03*
X1208858D03*
X1227559Y1075196D03*
X1235039D03*
X1231298Y1071455D03*
X1223818D03*
X1235039Y1078936D03*
X1227559D03*
X1227557Y1090157D03*
X1227558Y1093897D03*
X1223818Y1105117D03*
X1227558Y1108858D03*
X1233169Y1140649D03*
Y1155610D03*
Y1148129D03*
X1236909Y1170570D03*
X1225688Y1166830D03*
X1233169Y1170570D03*
X1236909Y1178051D03*
Y1185531D03*
X1233169D03*
Y1178051D03*
X1225688Y1174310D03*
Y1181791D03*
Y1189271D03*
X1233169Y1193011D03*
X1223818Y1194881D03*
X1236909Y1193011D03*
X1223818Y1202362D03*
Y1198621D03*
X1235039Y1202362D03*
X1223818Y1206102D03*
Y1221062D03*
Y1217322D03*
Y1213582D03*
Y1209842D03*
X1227558Y1221062D03*
X1235039Y1209842D03*
Y1206102D03*
X1223818Y1224803D03*
Y1228543D03*
X1231298Y1224803D03*
Y1228543D03*
X1227558Y1236023D03*
Y1232283D03*
X1235039D03*
X1225688Y1222932D03*
X1223818Y1239763D03*
X1227558Y1247243D03*
X1231298Y1254724D03*
X1223818D03*
Y1250984D03*
X1227558Y1243503D03*
X1231298Y1250984D03*
Y1258465D03*
X1223818D03*
X1235966Y1348187D03*
X1228086D03*
X1235966Y1360099D03*
X1228086D03*
X1235966Y1372385D03*
Y1384297D03*
X1228086Y1372385D03*
Y1384297D03*
X1238779Y1078936D03*
X1242520Y1090158D03*
Y1082677D03*
Y1101378D03*
Y1123819D03*
Y1116339D03*
Y1108859D03*
Y1131300D03*
X1240589Y1193011D03*
X1238779Y1202362D03*
X1242520Y1198621D03*
Y1221062D03*
Y1213582D03*
Y1206102D03*
Y1228543D03*
X1238779Y1250984D03*
X1242520Y1247243D03*
Y1239762D03*
X1252566Y1348187D03*
X1240326D03*
X1248206D03*
X1252566Y1360099D03*
X1240326D03*
X1248206D03*
X1252566Y1372385D03*
Y1384297D03*
X1240326D03*
Y1372385D03*
X1248206D03*
Y1384297D03*
X1252566Y1396583D03*
X1240326D03*
X1248206D03*
X1252566Y1408495D03*
X1240326D03*
X1248206D03*
X1264806Y1348187D03*
X1260446D03*
X1264806Y1360099D03*
X1260446D03*
X1264806Y1372385D03*
Y1384297D03*
X1260446Y1372385D03*
Y1384297D03*
X1264806Y1396583D03*
X1260446D03*
X1264806Y1408495D03*
X1260446D03*
X1284926Y1348187D03*
X1277046D03*
X1272686D03*
X1284926Y1360099D03*
X1277046D03*
X1272686D03*
X1284926Y1372385D03*
Y1384297D03*
X1277046Y1372385D03*
Y1384297D03*
X1272686D03*
Y1372385D03*
X1284926Y1396583D03*
X1277046D03*
X1272686D03*
X1284926Y1408495D03*
X1277046D03*
X1272686D03*
X1301526Y1348187D03*
X1289286D03*
X1297166D03*
X1301526Y1360099D03*
X1289286D03*
X1297166D03*
X1301526Y1372385D03*
Y1384297D03*
X1289286D03*
Y1372385D03*
X1297166Y1384297D03*
Y1372385D03*
X1301526Y1396583D03*
X1289286D03*
X1297166D03*
X1301526Y1408495D03*
X1289286D03*
X1297166D03*
X1313766Y1348187D03*
X1309406D03*
X1313766Y1360099D03*
X1309406D03*
X1313766Y1372385D03*
Y1384297D03*
X1309406Y1372385D03*
Y1384297D03*
X1313766Y1396583D03*
X1309406D03*
X1313766Y1408495D03*
X1309406D03*
X1333886Y1348187D03*
X1326006D03*
X1321646D03*
X1333886Y1360099D03*
X1326006D03*
X1321646D03*
X1333886Y1372385D03*
Y1384297D03*
X1326006Y1372385D03*
Y1384297D03*
X1321646D03*
Y1372385D03*
X1333886Y1396583D03*
X1326006D03*
X1321646D03*
X1333886Y1408495D03*
X1326006D03*
X1321646D03*
X1350486Y1348187D03*
X1338246D03*
X1346126D03*
X1350486Y1360099D03*
X1338246D03*
X1346126D03*
X1350486Y1372385D03*
Y1384297D03*
X1338246D03*
Y1372385D03*
X1346126Y1384297D03*
Y1372385D03*
X1350486Y1396583D03*
X1338246D03*
X1346126D03*
X1350486Y1408495D03*
X1338246D03*
X1346126D03*
X1358366Y1348187D03*
Y1360099D03*
Y1372385D03*
Y1384297D03*
Y1396583D03*
Y1408495D03*
X1459130Y1348187D03*
Y1360099D03*
Y1384297D03*
Y1372385D03*
X1479250Y1348187D03*
X1471370D03*
X1467010D03*
X1479250Y1360099D03*
X1471370D03*
X1467010D03*
X1479250Y1384297D03*
Y1372385D03*
X1471370D03*
Y1384297D03*
X1467010D03*
Y1372385D03*
X1479250Y1396583D03*
X1471370D03*
X1479250Y1408495D03*
X1471370D03*
X1495850Y1348187D03*
X1483610D03*
X1491490D03*
X1495850Y1360099D03*
X1483610D03*
X1491490D03*
X1483610Y1384297D03*
Y1372385D03*
X1491490Y1384297D03*
Y1372385D03*
X1495850Y1384297D03*
Y1372385D03*
Y1396583D03*
X1483610D03*
X1491490D03*
X1495850Y1408495D03*
X1483610D03*
X1491490D03*
X1514468Y1103247D03*
Y1125688D03*
Y1133169D03*
Y1140649D03*
Y1144389D03*
Y1151870D03*
Y1159350D03*
X1512597Y1198622D03*
Y1191142D03*
Y1221063D03*
Y1213583D03*
Y1206103D03*
X1508090Y1348187D03*
X1503730D03*
X1508090Y1360099D03*
X1503730D03*
X1508090Y1384297D03*
Y1372385D03*
X1503730D03*
Y1384297D03*
X1508090Y1396583D03*
X1503730D03*
X1508090Y1408495D03*
X1503730D03*
X1521948Y1077066D03*
X1518208Y1080806D03*
Y1103247D03*
X1529429Y1106988D03*
Y1118208D03*
Y1121948D03*
X1525689D03*
X1521949D03*
X1529429Y1125688D03*
X1518208D03*
X1525689Y1129429D03*
X1521949D03*
X1518208Y1133169D03*
X1521949Y1136909D03*
X1529429Y1140649D03*
X1525689D03*
X1521949D03*
X1518208D03*
X1521949Y1144389D03*
X1518208D03*
X1521949Y1148129D03*
Y1151870D03*
X1518208D03*
X1529429Y1155610D03*
X1525689D03*
X1521949D03*
Y1159350D03*
X1518208D03*
X1529429Y1166830D03*
X1521948D03*
X1525689Y1170570D03*
X1521948D03*
Y1174310D03*
X1518207D03*
X1521948Y1178051D03*
X1525689Y1174310D03*
X1529429D03*
X1527559Y1179921D03*
X1523819D03*
X1518207Y1181791D03*
X1516338Y1187401D03*
X1520078D03*
X1527559Y1183661D03*
X1523819D03*
X1520078D03*
X1516338D03*
Y1194881D03*
Y1202362D03*
X1527559Y1191141D03*
X1523819D03*
X1527559Y1198621D03*
X1523819D03*
X1520078Y1194881D03*
Y1202362D03*
X1516338Y1209842D03*
Y1217322D03*
X1523819Y1206102D03*
X1527559D03*
Y1213582D03*
X1523819D03*
X1520078Y1209842D03*
Y1217322D03*
X1523819Y1221062D03*
X1527559D03*
X1516338Y1232283D03*
Y1236023D03*
Y1224803D03*
X1527559Y1236023D03*
Y1232283D03*
X1523819Y1228543D03*
Y1224803D03*
X1520078Y1236023D03*
Y1232283D03*
Y1224803D03*
X1523819Y1239763D03*
Y1243503D03*
Y1258465D03*
X1528210Y1348187D03*
X1520330D03*
X1515970D03*
X1528210Y1360099D03*
X1520330D03*
X1515970D03*
X1528210Y1372385D03*
Y1384297D03*
X1520330Y1372385D03*
Y1384297D03*
X1515970D03*
Y1372385D03*
X1528210Y1396583D03*
X1520330D03*
X1515970D03*
X1528210Y1408495D03*
X1520330D03*
X1515970D03*
X1546258Y1071455D03*
X1540649Y1092027D03*
X1546259Y1090157D03*
X1544389Y1099507D03*
X1540649Y1106988D03*
X1536909D03*
X1533169D03*
X1544389D03*
X1540649Y1095767D03*
X1546259Y1101377D03*
Y1105117D03*
X1544389Y1118208D03*
X1540649D03*
X1544389Y1110728D03*
X1540649D03*
X1536909Y1114468D03*
X1533169D03*
X1544389Y1140649D03*
X1540649D03*
X1536909D03*
X1533169D03*
X1536909Y1129429D03*
X1544389Y1144389D03*
X1540649D03*
X1533169D03*
Y1148129D03*
Y1151870D03*
Y1155610D03*
X1544389Y1148129D03*
Y1155610D03*
Y1151870D03*
X1533169Y1159350D03*
X1544389D03*
Y1166830D03*
Y1170570D03*
X1533169Y1174310D03*
Y1178051D03*
X1544389Y1174310D03*
Y1178051D03*
Y1181791D03*
X1540649D03*
X1538779Y1179921D03*
X1531299D03*
Y1187401D03*
X1546259D03*
X1542519D03*
Y1183661D03*
X1538779D03*
X1535039D03*
X1531299D03*
X1535039Y1191141D03*
X1531299D03*
X1535039Y1198621D03*
X1531299D03*
X1538779Y1191141D03*
X1542519Y1194881D03*
X1546259D03*
X1542519Y1202362D03*
X1546259D03*
X1531299Y1206102D03*
X1535039D03*
X1538779D03*
X1542519Y1209842D03*
X1531299Y1221062D03*
X1535039D03*
X1546259Y1217322D03*
Y1221062D03*
X1542519D03*
Y1217322D03*
Y1228543D03*
X1531299Y1224803D03*
X1535039Y1232283D03*
Y1236023D03*
X1542519Y1232283D03*
Y1236023D03*
X1538779Y1224803D03*
X1546259D03*
X1542519D03*
X1535039Y1239763D03*
X1531299D03*
Y1243503D03*
X1538779Y1239763D03*
Y1243503D03*
X1542519Y1250984D03*
Y1239763D03*
X1546259D03*
Y1247243D03*
Y1250984D03*
X1542519Y1243503D03*
X1546259Y1254724D03*
X1542519Y1247243D03*
X1546260Y1258465D03*
X1538779D03*
X1531299D03*
X1544810Y1348187D03*
X1532570D03*
X1540450D03*
X1544810Y1360099D03*
X1532570D03*
X1540450D03*
X1544810Y1384297D03*
Y1372385D03*
X1532570Y1384297D03*
Y1372385D03*
X1540450Y1384297D03*
Y1372385D03*
X1544810Y1396583D03*
X1532570D03*
X1540450D03*
X1544810Y1408495D03*
X1532570D03*
X1540450D03*
X1561219Y1071455D03*
X1553739D03*
X1561220Y1090157D03*
X1557480D03*
X1553740D03*
X1550000D03*
X1561220Y1105117D03*
X1553740D03*
X1561220Y1101377D03*
X1557480Y1097637D03*
Y1093897D03*
X1553740Y1101377D03*
X1550000Y1093897D03*
Y1097637D03*
X1551870Y1114468D03*
X1548130D03*
X1563090Y1118208D03*
X1559350D03*
X1555610D03*
X1551870D03*
X1548130D03*
X1563090Y1121948D03*
X1559350D03*
X1555610D03*
X1551870D03*
X1548130D03*
Y1110728D03*
X1561220Y1108858D03*
X1557480D03*
X1553740D03*
X1550000D03*
X1551870Y1110728D03*
X1548130Y1140649D03*
X1563090Y1125688D03*
X1559350D03*
X1555610D03*
X1551870D03*
X1548130D03*
X1559350Y1129429D03*
X1555610D03*
X1551870D03*
X1548130D03*
X1559350Y1133169D03*
X1555610D03*
X1551870D03*
X1548130D03*
X1559350Y1136909D03*
X1551870D03*
X1548130D03*
X1559350Y1140649D03*
X1555610D03*
X1551870D03*
Y1155610D03*
Y1151870D03*
X1559350Y1144389D03*
X1551870D03*
Y1148129D03*
X1559350Y1151870D03*
X1563090Y1155610D03*
Y1148129D03*
X1559350Y1170570D03*
X1551870Y1166830D03*
X1559350Y1159350D03*
X1551870D03*
X1548130Y1170570D03*
X1563090Y1166830D03*
X1551870Y1189271D03*
X1559350Y1185531D03*
X1551870D03*
Y1178051D03*
Y1174310D03*
Y1181791D03*
X1563090D03*
Y1174310D03*
X1550000Y1187401D03*
X1548130Y1185531D03*
X1551870Y1193011D03*
X1559350Y1196751D03*
Y1200491D03*
X1555610D03*
Y1204232D03*
X1559350D03*
X1563090D03*
Y1196751D03*
Y1200491D03*
X1555610Y1193011D03*
Y1196751D03*
X1550000Y1191141D03*
Y1194881D03*
Y1198621D03*
Y1202362D03*
X1555610Y1211712D03*
X1559350D03*
X1563090D03*
Y1207972D03*
X1559350D03*
X1555610D03*
X1563090Y1219192D03*
X1550000Y1221062D03*
X1553740D03*
X1557480D03*
X1561220D03*
X1550000Y1206102D03*
Y1209842D03*
Y1213582D03*
Y1217322D03*
X1553740D03*
X1550000Y1228543D03*
Y1224803D03*
X1557480Y1228543D03*
X1550000Y1232283D03*
Y1236023D03*
X1561220Y1224803D03*
X1557480Y1232283D03*
Y1236023D03*
X1553740Y1224803D03*
X1557480D03*
Y1239763D03*
X1561220Y1243503D03*
X1553740D03*
X1561220Y1250984D03*
Y1254724D03*
X1550000Y1243503D03*
X1557480Y1247243D03*
X1550000D03*
X1557480Y1243503D03*
X1553740Y1250984D03*
Y1254724D03*
X1561220Y1258465D03*
X1553740D03*
X1557050Y1348187D03*
X1552690D03*
Y1360099D03*
X1557050D03*
Y1384297D03*
Y1372385D03*
X1552690D03*
Y1384297D03*
X1557050Y1396583D03*
X1552690D03*
X1557050Y1408495D03*
X1552690D03*
X1576180Y1071455D03*
X1568699D03*
X1564960Y1090157D03*
X1572441D03*
X1576181D03*
X1568700D03*
X1576181Y1105117D03*
X1568700D03*
X1564960Y1093897D03*
Y1097637D03*
X1572441Y1093897D03*
Y1097637D03*
X1576181Y1101377D03*
X1568700D03*
X1566830Y1121948D03*
X1578051Y1118208D03*
X1574311D03*
Y1121948D03*
X1578051D03*
X1570571Y1118208D03*
X1566830D03*
X1570571Y1121948D03*
X1576181Y1108858D03*
X1572441D03*
X1568700D03*
X1564960D03*
X1566830Y1133169D03*
Y1129429D03*
X1570571Y1140649D03*
X1574311D03*
X1578051D03*
X1570571Y1125688D03*
X1574311D03*
X1578051D03*
X1566830D03*
X1578051Y1133169D03*
X1574311D03*
X1570571D03*
X1566830Y1136909D03*
X1574311Y1148129D03*
X1570571D03*
X1578051D03*
X1570571Y1155610D03*
X1566830Y1151869D03*
X1578051Y1155610D03*
X1566830Y1144389D03*
Y1159350D03*
X1578051Y1166830D03*
X1574311Y1159350D03*
X1570571Y1166830D03*
X1566830Y1170570D03*
X1574311D03*
X1578051Y1181791D03*
X1574311D03*
X1570571D03*
X1578051Y1189271D03*
X1574311D03*
X1570571D03*
X1566830D03*
Y1178051D03*
X1570571Y1174310D03*
X1566830Y1185531D03*
X1578051Y1174310D03*
X1574311Y1204232D03*
X1578051D03*
Y1196751D03*
X1574311D03*
X1570571D03*
X1566830Y1200491D03*
Y1196751D03*
Y1193011D03*
Y1204232D03*
X1570571D03*
X1566830Y1207972D03*
Y1211712D03*
X1578051Y1207972D03*
X1574311D03*
X1570571D03*
X1564960Y1221062D03*
X1568700D03*
X1572441D03*
X1576181D03*
X1564960Y1224803D03*
Y1232283D03*
Y1236023D03*
X1576181Y1224803D03*
X1572441Y1232283D03*
Y1236023D03*
X1568700Y1224803D03*
X1564960Y1228543D03*
Y1239763D03*
X1576181Y1243503D03*
X1568700D03*
Y1239763D03*
Y1254724D03*
X1564960Y1243503D03*
Y1247243D03*
X1568700Y1250984D03*
X1576181Y1258465D03*
X1568701D03*
X1564930Y1348187D03*
X1569290D03*
X1577170D03*
X1569290Y1360099D03*
X1577170D03*
X1564930D03*
X1577170Y1372385D03*
Y1384297D03*
X1569290Y1372385D03*
Y1384297D03*
X1564930D03*
Y1372385D03*
X1577170Y1396583D03*
X1569290D03*
X1564930D03*
X1577170Y1408495D03*
X1569290D03*
X1564930D03*
X1591140Y1071455D03*
X1583660D03*
X1579921Y1090157D03*
X1583661D03*
X1587401D03*
X1591141D03*
X1594882D03*
X1583661Y1105117D03*
X1591141D03*
X1579921Y1093897D03*
Y1097637D03*
X1583661Y1101377D03*
X1587401Y1097637D03*
Y1093897D03*
X1594882D03*
Y1097637D03*
X1591141Y1101377D03*
X1581791Y1121948D03*
X1585531Y1118208D03*
X1589271D03*
X1593011D03*
X1589271Y1121948D03*
X1593011D03*
X1585531D03*
X1581791Y1118208D03*
X1594882Y1108858D03*
X1591141D03*
X1587401D03*
X1583661D03*
X1579921D03*
X1587401Y1112598D03*
X1581791Y1133169D03*
Y1140649D03*
X1585531D03*
X1589271D03*
X1593011D03*
X1589271Y1125688D03*
X1585531D03*
X1581791D03*
X1593011D03*
Y1133169D03*
X1589271D03*
X1585531D03*
X1593011Y1148129D03*
X1589271D03*
X1585531D03*
X1581791D03*
X1593011Y1155610D03*
X1585531D03*
X1589271Y1170570D03*
X1593012Y1166830D03*
X1585531D03*
X1581791Y1159350D03*
X1589271D03*
X1581791Y1170570D03*
X1593011Y1181791D03*
X1589271D03*
X1585531D03*
X1581791D03*
X1593011Y1189271D03*
X1589271D03*
X1585531D03*
X1581791D03*
X1585531Y1174310D03*
X1593011D03*
Y1204232D03*
Y1196751D03*
X1589271D03*
X1585531D03*
X1581791D03*
Y1204232D03*
X1585531D03*
X1589271D03*
X1593011Y1219192D03*
X1591141Y1217322D03*
X1593011Y1207972D03*
X1589271D03*
X1585531D03*
X1581791D03*
X1591141Y1221062D03*
X1587401D03*
X1579921D03*
X1583661D03*
X1594882D03*
X1583661Y1224803D03*
X1579921Y1232283D03*
Y1236023D03*
X1594882Y1232283D03*
Y1236023D03*
X1591141Y1224803D03*
X1587401Y1232283D03*
Y1236023D03*
X1583661Y1243503D03*
X1579921Y1239763D03*
X1591141Y1243503D03*
X1594882Y1239763D03*
X1587401D03*
X1591142Y1258465D03*
X1583661D03*
X1589410Y1348187D03*
X1581530D03*
X1589410Y1360099D03*
X1581530D03*
Y1384297D03*
Y1372385D03*
X1589410Y1384297D03*
Y1372385D03*
X1581530Y1396583D03*
X1589410D03*
X1581530Y1408495D03*
X1589410D03*
X1609842Y1075196D03*
X1606101Y1071454D03*
X1598621Y1071455D03*
X1598622Y1090157D03*
X1606102Y1082677D03*
Y1086417D03*
X1609842Y1090157D03*
X1606102D03*
X1602362D03*
X1598622Y1105117D03*
X1606102D03*
X1598622Y1101377D03*
X1606102D03*
X1609842Y1093897D03*
X1602362D03*
Y1097637D03*
X1596752Y1121948D03*
X1600492Y1118208D03*
Y1114468D03*
X1611712Y1121948D03*
X1607972D03*
X1596752Y1118208D03*
X1600492Y1121948D03*
X1609842Y1108858D03*
X1606102D03*
X1602362D03*
X1598622D03*
X1607972Y1125688D03*
X1611712D03*
X1607972Y1133464D03*
X1611712Y1133169D03*
X1600590Y1132677D03*
X1596752Y1133169D03*
Y1140649D03*
X1600492D03*
Y1125688D03*
X1596752D03*
X1607972Y1140649D03*
X1611712D03*
X1600492Y1148129D03*
X1596752D03*
X1607972D03*
X1611712D03*
X1600492Y1155610D03*
X1611712D03*
X1596752Y1170570D03*
Y1159350D03*
X1611712Y1166830D03*
X1607972Y1170570D03*
X1600492Y1166830D03*
X1607972Y1159350D03*
X1600492Y1181791D03*
X1611712D03*
X1607972D03*
Y1189271D03*
X1611712D03*
X1596752Y1181791D03*
X1600492Y1189271D03*
X1596752D03*
X1600492Y1174310D03*
X1611712D03*
Y1204232D03*
X1607972D03*
Y1196751D03*
X1611712D03*
X1600492D03*
X1596752D03*
Y1204232D03*
X1600492D03*
X1606102Y1221062D03*
X1596752Y1207972D03*
X1607972D03*
X1611712D03*
Y1211712D03*
X1596752Y1219192D03*
X1600492Y1207972D03*
X1598622Y1221062D03*
X1609842D03*
X1602362D03*
X1598622Y1224803D03*
X1609842Y1232283D03*
Y1236023D03*
X1606102Y1228543D03*
Y1224803D03*
X1602362Y1232283D03*
Y1236023D03*
X1598622Y1243503D03*
X1609842Y1239763D03*
X1602362D03*
X1606102Y1258465D03*
X1598623D03*
X1609158Y1348187D03*
Y1360099D03*
Y1384297D03*
Y1372385D03*
X1624803Y1075196D03*
X1617322D03*
X1621062Y1071455D03*
X1613581D03*
X1617322Y1090157D03*
Y1078936D03*
X1613582Y1090157D03*
Y1086417D03*
X1624803Y1078936D03*
X1621063Y1086417D03*
Y1090157D03*
X1624803D03*
X1617322Y1093897D03*
Y1097637D03*
X1624803Y1093897D03*
Y1097637D03*
X1621063Y1105117D03*
X1613582D03*
Y1101377D03*
X1626673Y1121948D03*
X1622933D03*
X1619193D03*
X1615452D03*
X1624803Y1108858D03*
X1621063D03*
X1617322D03*
X1613582D03*
X1615452Y1133169D03*
X1619193D03*
X1622933D03*
X1626673D03*
X1615452Y1140649D03*
X1619193D03*
X1622933D03*
X1626673D03*
X1615452Y1125688D03*
X1619193D03*
X1622933D03*
X1626673D03*
X1615452Y1148129D03*
X1619193D03*
X1622933D03*
X1626673D03*
X1619193Y1155610D03*
X1626673D03*
X1615452Y1170570D03*
X1622933D03*
X1626673Y1166830D03*
X1615452Y1159350D03*
X1619193Y1166830D03*
X1622933Y1159350D03*
X1615452Y1181791D03*
X1619193D03*
X1622933D03*
X1626673D03*
X1615452Y1189271D03*
X1619193D03*
X1622933D03*
X1626673D03*
Y1174310D03*
X1619193D03*
Y1204232D03*
X1615452D03*
X1626673D03*
X1622933D03*
X1615452Y1196751D03*
X1619193D03*
X1622933D03*
X1626673D03*
X1617322Y1221062D03*
X1619193Y1207972D03*
X1622933D03*
X1626673Y1211712D03*
Y1207972D03*
X1615452Y1211712D03*
Y1207972D03*
X1621063Y1221062D03*
X1613582D03*
X1624803D03*
X1613582Y1228543D03*
Y1224803D03*
X1621063Y1228543D03*
Y1224803D03*
X1624803Y1232283D03*
Y1236023D03*
X1617322Y1232283D03*
Y1236023D03*
Y1239763D03*
X1621063Y1258465D03*
X1613582D03*
X1617038Y1348187D03*
X1621398D03*
X1617038Y1360099D03*
X1621398D03*
X1617038Y1384297D03*
Y1372385D03*
X1621398D03*
Y1384297D03*
Y1396583D03*
Y1408495D03*
X1639763Y1075196D03*
X1632283D03*
X1643503Y1071455D03*
X1636022D03*
X1628542D03*
X1636023Y1090157D03*
X1643504Y1082677D03*
X1636023Y1086417D03*
X1643504Y1090157D03*
Y1086417D03*
X1639763Y1090157D03*
Y1078936D03*
X1632283D03*
X1628543Y1086417D03*
Y1090157D03*
X1632283D03*
Y1093897D03*
Y1097637D03*
X1639763Y1093897D03*
Y1097637D03*
X1628543Y1105117D03*
X1636023D03*
X1643504D03*
X1641633Y1118208D03*
X1637893Y1121948D03*
X1634153D03*
X1630413D03*
X1641633D03*
X1643504Y1108858D03*
X1639763D03*
X1636023D03*
X1632283D03*
X1628543D03*
X1641633Y1136909D03*
X1630413Y1133169D03*
X1634153D03*
X1637893D03*
X1641633D03*
X1634153Y1140649D03*
X1637893D03*
X1641633Y1125688D03*
Y1129429D03*
X1630413Y1125688D03*
X1634153D03*
X1637893D03*
X1641633Y1140649D03*
X1630413D03*
Y1148129D03*
X1634153D03*
X1637893D03*
X1641633Y1144389D03*
Y1148129D03*
Y1151869D03*
X1634153Y1155610D03*
X1641633D03*
X1634153Y1166830D03*
X1630413Y1159350D03*
Y1170570D03*
X1634153Y1189271D03*
X1637893D03*
X1641633Y1178051D03*
X1634153Y1174310D03*
X1641633Y1185531D03*
X1630413Y1181791D03*
X1634153D03*
X1637893D03*
X1641633Y1189271D03*
X1630413D03*
X1641633Y1174310D03*
X1641653Y1196732D03*
X1641633Y1204232D03*
X1630413D03*
X1634153D03*
X1637893D03*
X1641633Y1200491D03*
X1630413Y1196751D03*
X1634153D03*
X1637893D03*
X1641633Y1193011D03*
Y1211712D03*
X1634153Y1207972D03*
X1630413D03*
X1634153Y1211712D03*
X1637893Y1207972D03*
Y1211712D03*
X1630413D03*
X1641633Y1207972D03*
X1628543Y1221062D03*
X1632283D03*
X1636023D03*
X1639763D03*
X1643504D03*
X1628543Y1228543D03*
Y1224803D03*
X1632283Y1232283D03*
Y1236023D03*
X1636023Y1228543D03*
Y1224803D03*
X1639763Y1232283D03*
Y1236023D03*
X1643504Y1228543D03*
Y1224803D03*
X1628543Y1239763D03*
X1639763D03*
X1632283Y1243503D03*
X1639763D03*
X1632283Y1247243D03*
X1639763D03*
X1643504Y1258465D03*
X1636023D03*
X1628543D03*
X1629278Y1348187D03*
X1641518D03*
X1633638D03*
X1629278Y1360099D03*
X1641518D03*
X1633638D03*
X1629278Y1384297D03*
Y1372385D03*
X1641518Y1384297D03*
Y1372385D03*
X1633638Y1384297D03*
Y1372385D03*
X1629278Y1396583D03*
X1641518D03*
X1633638D03*
Y1408495D03*
X1629278D03*
X1641518D03*
X1647244Y1075196D03*
X1654724D03*
X1658463Y1071455D03*
X1650983D03*
X1654724Y1078936D03*
Y1090157D03*
X1658464D03*
X1650984D03*
X1647244D03*
Y1093897D03*
X1658464Y1101377D03*
Y1105117D03*
X1650984D03*
X1645374Y1118208D03*
X1649114D03*
X1658464Y1108858D03*
X1654724D03*
X1650984D03*
X1647244D03*
X1649114Y1140649D03*
X1652854Y1136909D03*
X1645374Y1125688D03*
X1649114Y1136909D03*
X1652854Y1140649D03*
X1645374Y1155610D03*
Y1151869D03*
Y1148129D03*
X1652854D03*
X1649114Y1144389D03*
X1652854Y1155610D03*
X1649114Y1148129D03*
X1652854Y1151869D03*
X1656594D03*
X1660334D03*
Y1155610D03*
X1649114Y1151870D03*
X1645374Y1166830D03*
X1652854Y1159350D03*
X1660334Y1166830D03*
Y1170570D03*
X1645374Y1159350D03*
X1660334D03*
X1645374Y1170570D03*
X1652854D03*
Y1166830D03*
Y1185531D03*
X1656594Y1181791D03*
X1652854Y1178051D03*
Y1174310D03*
X1649114Y1181791D03*
X1656594Y1185531D03*
X1660334Y1174310D03*
Y1178051D03*
Y1185531D03*
X1645374Y1181791D03*
Y1174310D03*
X1649114Y1178051D03*
Y1189271D03*
X1652854D03*
X1649114Y1185531D03*
X1656594Y1193011D03*
X1652854Y1204232D03*
Y1196751D03*
Y1193011D03*
X1649114D03*
X1645374Y1196751D03*
X1649114Y1211712D03*
X1645374Y1207972D03*
X1660334Y1215452D03*
Y1211712D03*
X1654724Y1221062D03*
X1658464D03*
X1650984D03*
X1647244D03*
Y1232283D03*
Y1236023D03*
X1654724Y1232283D03*
X1658464Y1228543D03*
X1654724Y1236023D03*
X1658464Y1224803D03*
X1650984Y1228543D03*
Y1224803D03*
X1654724Y1239763D03*
Y1243503D03*
X1647244Y1247243D03*
X1654724D03*
X1647244Y1243503D03*
X1658464Y1258465D03*
X1650984D03*
X1645878Y1348187D03*
X1653758D03*
X1658118D03*
X1645878Y1360099D03*
X1653758D03*
X1658118D03*
X1645878Y1384297D03*
Y1372385D03*
X1653758D03*
Y1384297D03*
X1658118D03*
Y1372385D03*
X1645878Y1396583D03*
X1653758D03*
X1658118D03*
X1645878Y1408495D03*
X1653758D03*
X1658118D03*
X1662204Y1075196D03*
X1669685D03*
X1673425Y1071455D03*
X1665944D03*
X1662203Y1090157D03*
X1669686Y1078936D03*
X1669684Y1090157D03*
X1662204Y1093897D03*
X1669685D03*
X1673425Y1105117D03*
X1665945D03*
X1669685Y1108858D03*
X1673425Y1116338D03*
Y1123818D03*
X1665944Y1112598D03*
Y1120078D03*
X1665945Y1108858D03*
X1662204Y1123818D03*
Y1120078D03*
Y1116338D03*
Y1108858D03*
X1671555Y1140649D03*
X1673425Y1131299D03*
X1662204Y1135039D03*
Y1131299D03*
Y1127558D03*
Y1138779D03*
X1664074Y1151869D03*
X1671555Y1148129D03*
X1664074Y1144389D03*
Y1159350D03*
X1671555D03*
X1664074Y1166830D03*
X1671555D03*
X1664074Y1189271D03*
Y1174310D03*
X1671555Y1181791D03*
Y1174310D03*
X1664074Y1181791D03*
X1671555Y1189271D03*
X1665945Y1194881D03*
X1664074Y1204232D03*
X1669685Y1202362D03*
X1673425Y1221062D03*
X1669685Y1209842D03*
X1665945Y1221062D03*
Y1217322D03*
X1662204Y1221062D03*
Y1232283D03*
Y1236023D03*
X1673425Y1224803D03*
Y1228543D03*
X1669685Y1232283D03*
Y1236023D03*
X1665945Y1224803D03*
Y1228543D03*
X1662204Y1239763D03*
X1669685D03*
X1673425Y1258465D03*
X1665945D03*
X1665998Y1348187D03*
X1670358D03*
X1665998Y1360099D03*
X1670358D03*
X1665998Y1384297D03*
Y1372385D03*
X1670358D03*
Y1384297D03*
X1665998Y1396583D03*
X1670358D03*
X1665998Y1408495D03*
X1670358D03*
X1677166Y1075196D03*
X1684646D03*
X1692126D03*
X1688385Y1071455D03*
X1680905D03*
X1677166Y1078936D03*
X1692126D03*
X1684646D03*
X1684644Y1090157D03*
X1677165Y1093897D03*
X1684645D03*
X1680905Y1105117D03*
X1677164Y1108857D03*
X1684645Y1108858D03*
X1690256Y1140649D03*
Y1155610D03*
Y1148129D03*
X1682775Y1166830D03*
X1679035Y1170570D03*
X1690256D03*
Y1178051D03*
X1682775Y1174310D03*
X1679035Y1178051D03*
X1682775Y1181791D03*
X1679035Y1185531D03*
X1682775Y1189271D03*
X1690256Y1185531D03*
X1680905Y1194881D03*
X1690256Y1193011D03*
X1679035D03*
X1692126Y1202362D03*
X1680905D03*
Y1198621D03*
X1677165D03*
X1684645Y1221062D03*
X1692126Y1209842D03*
X1680905Y1221062D03*
Y1217322D03*
X1677165Y1221062D03*
Y1213582D03*
X1680905D03*
Y1209842D03*
Y1206102D03*
X1688385Y1224803D03*
Y1228543D03*
X1684645Y1236023D03*
Y1232283D03*
X1692126D03*
X1680905Y1224803D03*
Y1228543D03*
X1677165Y1232283D03*
Y1236023D03*
X1680905Y1239763D03*
X1688385Y1258465D03*
X1680905D03*
X1678238Y1348187D03*
X1690478D03*
X1682598D03*
X1678238Y1360099D03*
X1690478D03*
X1682598D03*
X1678238Y1372385D03*
Y1384297D03*
X1690478D03*
Y1372385D03*
X1682598Y1384297D03*
Y1372385D03*
X1678238Y1396583D03*
X1690478D03*
X1682598D03*
X1678238Y1408495D03*
X1690478D03*
X1682598D03*
X1695866Y1078936D03*
X1699607Y1090158D03*
Y1082677D03*
Y1101378D03*
Y1123819D03*
Y1116339D03*
Y1108859D03*
Y1131300D03*
X1693996Y1170570D03*
Y1178051D03*
Y1185531D03*
Y1193011D03*
X1697676D03*
X1695866Y1202362D03*
X1699607Y1198621D03*
Y1221062D03*
Y1213582D03*
Y1206102D03*
Y1228543D03*
X1695866Y1250984D03*
X1699607Y1247243D03*
Y1239762D03*
X1694838Y1348187D03*
X1702718D03*
X1707078D03*
X1702718Y1360099D03*
X1707078D03*
X1694838D03*
Y1384297D03*
Y1372385D03*
X1702718D03*
Y1384297D03*
X1707078D03*
Y1372385D03*
X1694838Y1396583D03*
X1702718D03*
X1707078D03*
X1694838Y1408495D03*
X1702718D03*
X1707078D03*
X1714958Y1348187D03*
X1719318D03*
X1714958Y1360099D03*
X1719318D03*
X1714958Y1384297D03*
Y1372385D03*
X1719318D03*
Y1384297D03*
X1714958Y1396583D03*
X1719318D03*
X1714958Y1408495D03*
X1719318D03*
X1727198Y1348187D03*
X1739438D03*
X1731558D03*
X1727198Y1360099D03*
X1739438D03*
X1731558D03*
X1739438Y1372385D03*
X1731558Y1384297D03*
Y1372385D03*
X1727198D03*
Y1384297D03*
X1739438D03*
X1727198Y1396583D03*
X1739438D03*
X1731558D03*
X1727198Y1408495D03*
X1739438D03*
X1731558D03*
G54D52*
X956448Y-30304D03*
Y-33204D03*
X953192Y-25085D03*
X956445Y-25099D03*
X950167Y-26405D03*
X953207Y-27600D03*
X956460Y-27614D03*
X978036Y-64265D03*
X975011Y-65585D03*
X978051Y-66780D03*
X981289Y-64279D03*
X981292Y-69484D03*
Y-72384D03*
X981304Y-66794D03*
X1231351Y-77080D03*
X1234592Y-79984D03*
X1234604Y-77094D03*
X1234592Y-82584D03*
Y-71970D03*
X1231336Y-74565D03*
X1234589Y-74579D03*
X1231336Y-64265D03*
X1234589D03*
X1234592Y-69470D03*
X1231351Y-66780D03*
X1234604D03*
X1228311Y-65585D03*
Y-75885D03*
X1236692Y-35515D03*
X1236707Y-38030D03*
X1233667Y-36835D03*
X1236692Y-25215D03*
X1236707Y-27730D03*
X1233667Y-26535D03*
X1239948Y-32920D03*
X1239945Y-35529D03*
X1239948Y-30420D03*
Y-40934D03*
X1239960Y-38044D03*
X1239948Y-43534D03*
X1239945Y-25215D03*
X1239960Y-27730D03*
X1487851Y-77080D03*
X1491092Y-79984D03*
X1491104Y-77094D03*
X1491092Y-82584D03*
Y-71970D03*
X1487836Y-74565D03*
X1491089Y-74579D03*
X1487836Y-64265D03*
X1491089D03*
X1491092Y-69470D03*
X1487851Y-66780D03*
X1491104D03*
X1484811Y-65585D03*
Y-75885D03*
X1526448Y-33050D03*
X1523192Y-35645D03*
X1526445Y-35659D03*
X1526448Y-30550D03*
X1523207Y-38160D03*
X1526448Y-41064D03*
X1526460Y-38174D03*
X1526448Y-43664D03*
X1520167Y-36965D03*
X1523192Y-25345D03*
X1526445D03*
X1523207Y-27860D03*
X1526460D03*
X1520167Y-26665D03*
X1742336Y-74565D03*
Y-64265D03*
X1739311Y-65585D03*
Y-75885D03*
X1742351Y-77080D03*
X1745592Y-79984D03*
X1745604Y-77094D03*
X1745592Y-82584D03*
Y-71970D03*
X1745589Y-74579D03*
Y-64265D03*
X1745592Y-69470D03*
X1742351Y-66780D03*
X1745604D03*
X1804667Y-37095D03*
Y-26795D03*
X1810948Y-33180D03*
X1807692Y-35775D03*
X1810945Y-35789D03*
X1810948Y-30680D03*
X1807707Y-38290D03*
X1810948Y-41194D03*
X1810960Y-38304D03*
X1810948Y-43794D03*
X1807692Y-25475D03*
X1810945D03*
X1807707Y-27990D03*
X1810960D03*
G54D24*
X46348Y1727941D03*
Y1737941D03*
Y1773941D03*
Y1783941D03*
X333112Y1751624D03*
Y1761624D03*
X333212Y1797624D03*
Y1807624D03*
X619861Y1751765D03*
Y1761765D03*
X619475Y1798845D03*
Y1808845D03*
X907163Y1752566D03*
Y1762566D03*
X907166Y1800435D03*
Y1810435D03*
G54D41*
X266841Y421555D03*
Y550020D03*
X295856Y421555D03*
Y550020D03*
X723927Y421555D03*
Y550020D03*
X752942Y421555D03*
Y550020D03*
X1181014Y421555D03*
Y550020D03*
X1210029Y421555D03*
Y550020D03*
X1638101Y421555D03*
Y550020D03*
X1667116Y421555D03*
Y550020D03*
G54D56*
X1236871Y1715189D03*
X1236864Y1773377D03*
X1235371Y1802909D03*
G54D57*
X1236871Y1744208D03*
%LPC*%
G75*
G54D64*
G01X-20602Y-468335D02*
Y-543335D01*
X479398D01*
Y-468335D01*
X-20602D01*
G01X-8602Y-533335D02*
Y-538335D01*
G01X-10059Y-533335D02*
X-7145D01*
G01X-2235Y-538335D02*
X-4769D01*
Y-533335D01*
X-2235D01*
G01X-3249Y-535752D02*
X-4769D01*
G01X331Y-533335D02*
Y-538335D01*
X2865D01*
G01X6698Y-538502D02*
X6571Y-538418D01*
Y-538252D01*
X6698Y-538168D01*
X6825Y-538252D01*
Y-538418D01*
X6698Y-538502D01*
G01Y-536252D02*
X6571Y-536168D01*
Y-536002D01*
X6698Y-535918D01*
X6825Y-536002D01*
Y-536168D01*
X6698Y-536252D01*
G01X11481Y-540002D02*
X10848Y-539168D01*
X10531Y-538335D01*
Y-535002D01*
X10848Y-534168D01*
X11481Y-533335D01*
G01X16898D02*
X16391Y-533502D01*
X16011Y-533918D01*
X15758Y-534418D01*
X15568Y-535085D01*
X15505Y-535835D01*
X15568Y-536585D01*
X15758Y-537252D01*
X16011Y-537752D01*
X16391Y-538168D01*
X16898Y-538335D01*
X17405Y-538168D01*
X17785Y-537752D01*
X18038Y-537252D01*
X18228Y-536585D01*
X18291Y-535835D01*
X18228Y-535085D01*
X18038Y-534418D01*
X17785Y-533918D01*
X17405Y-533502D01*
X16898Y-533335D01*
G01X20605Y-537335D02*
X20985Y-537918D01*
X21491Y-538252D01*
X22061Y-538335D01*
X22568Y-538252D01*
X23075Y-537835D01*
X23391Y-537335D01*
X23455Y-536835D01*
X23328Y-536252D01*
X22885Y-535835D01*
X22441Y-535668D01*
X21871D01*
G01X22441D02*
X22821Y-535418D01*
X23138Y-535002D01*
X23265Y-534502D01*
X23138Y-534002D01*
X22821Y-533585D01*
X22251Y-533335D01*
X21681Y-533418D01*
X21111Y-533752D01*
G01X27415Y-540002D02*
X28048Y-539168D01*
X28365Y-538335D01*
Y-535002D01*
X28048Y-534168D01*
X27415Y-533335D01*
G01X30805Y-537335D02*
X31185Y-537918D01*
X31691Y-538252D01*
X32261Y-538335D01*
X32768Y-538252D01*
X33275Y-537835D01*
X33591Y-537335D01*
X33655Y-536835D01*
X33528Y-536252D01*
X33085Y-535835D01*
X32641Y-535668D01*
X32071D01*
G01X32641D02*
X33021Y-535418D01*
X33338Y-535002D01*
X33465Y-534502D01*
X33338Y-534002D01*
X33021Y-533585D01*
X32451Y-533335D01*
X31881Y-533418D01*
X31311Y-533752D01*
G01X36095Y-534168D02*
X36475Y-533668D01*
X36918Y-533418D01*
X37425Y-533335D01*
X38058Y-533502D01*
X38501Y-533918D01*
X38628Y-534418D01*
X38565Y-534918D01*
X38311Y-535335D01*
X37045Y-536168D01*
X36475Y-536752D01*
X36095Y-537585D01*
X35968Y-538335D01*
X38628D01*
G01X42271D02*
X42398Y-537252D01*
X42588Y-536335D01*
X42841Y-535502D01*
X43158Y-534585D01*
X43665Y-533335D01*
X41131D01*
G01X46675Y-536668D02*
X48321D01*
G01X51395Y-534168D02*
X51775Y-533668D01*
X52218Y-533418D01*
X52725Y-533335D01*
X53358Y-533502D01*
X53801Y-533918D01*
X53928Y-534418D01*
X53865Y-534918D01*
X53611Y-535335D01*
X52345Y-536168D01*
X51775Y-536752D01*
X51395Y-537585D01*
X51268Y-538335D01*
X53928D01*
G01X56305Y-537335D02*
X56685Y-537918D01*
X57191Y-538252D01*
X57761Y-538335D01*
X58268Y-538252D01*
X58775Y-537835D01*
X59091Y-537335D01*
X59155Y-536835D01*
X59028Y-536252D01*
X58585Y-535835D01*
X58141Y-535668D01*
X57571D01*
G01X58141D02*
X58521Y-535418D01*
X58838Y-535002D01*
X58965Y-534502D01*
X58838Y-534002D01*
X58521Y-533585D01*
X57951Y-533335D01*
X57381Y-533418D01*
X56811Y-533752D01*
G01X63558Y-538335D02*
Y-533335D01*
X61215Y-536918D01*
X64381D01*
G01X66505Y-537585D02*
X66885Y-538002D01*
X67328Y-538252D01*
X67898Y-538335D01*
X68468Y-538168D01*
X68911Y-537835D01*
X69228Y-537252D01*
X69291Y-536585D01*
X69165Y-535918D01*
X68848Y-535502D01*
X68405Y-535168D01*
X67961Y-535085D01*
X67518Y-535168D01*
X66948Y-535502D01*
X67138Y-533335D01*
X68848D01*
G01X76895Y-538335D02*
Y-533335D01*
X79301D01*
G01X78415Y-535752D02*
X76895D01*
G01X81615Y-538335D02*
X83198Y-533335D01*
X84781Y-538335D01*
G01X84211Y-536585D02*
X82185D01*
G01X86968Y-538335D02*
X89628Y-533335D01*
G01X86968D02*
X89628Y-538335D01*
G01X93398Y-538502D02*
X93271Y-538418D01*
Y-538252D01*
X93398Y-538168D01*
X93525Y-538252D01*
Y-538418D01*
X93398Y-538502D01*
G01Y-536252D02*
X93271Y-536168D01*
Y-536002D01*
X93398Y-535918D01*
X93525Y-536002D01*
Y-536168D01*
X93398Y-536252D01*
G01X98181Y-540002D02*
X97548Y-539168D01*
X97231Y-538335D01*
Y-535002D01*
X97548Y-534168D01*
X98181Y-533335D01*
G01X103598D02*
X103091Y-533502D01*
X102711Y-533918D01*
X102458Y-534418D01*
X102268Y-535085D01*
X102205Y-535835D01*
X102268Y-536585D01*
X102458Y-537252D01*
X102711Y-537752D01*
X103091Y-538168D01*
X103598Y-538335D01*
X104105Y-538168D01*
X104485Y-537752D01*
X104738Y-537252D01*
X104928Y-536585D01*
X104991Y-535835D01*
X104928Y-535085D01*
X104738Y-534418D01*
X104485Y-533918D01*
X104105Y-533502D01*
X103598Y-533335D01*
G01X107305Y-537335D02*
X107685Y-537918D01*
X108191Y-538252D01*
X108761Y-538335D01*
X109268Y-538252D01*
X109775Y-537835D01*
X110091Y-537335D01*
X110155Y-536835D01*
X110028Y-536252D01*
X109585Y-535835D01*
X109141Y-535668D01*
X108571D01*
G01X109141D02*
X109521Y-535418D01*
X109838Y-535002D01*
X109965Y-534502D01*
X109838Y-534002D01*
X109521Y-533585D01*
X108951Y-533335D01*
X108381Y-533418D01*
X107811Y-533752D01*
G01X114115Y-540002D02*
X114748Y-539168D01*
X115065Y-538335D01*
Y-535002D01*
X114748Y-534168D01*
X114115Y-533335D01*
G01X117505Y-537335D02*
X117885Y-537918D01*
X118391Y-538252D01*
X118961Y-538335D01*
X119468Y-538252D01*
X119975Y-537835D01*
X120291Y-537335D01*
X120355Y-536835D01*
X120228Y-536252D01*
X119785Y-535835D01*
X119341Y-535668D01*
X118771D01*
G01X119341D02*
X119721Y-535418D01*
X120038Y-535002D01*
X120165Y-534502D01*
X120038Y-534002D01*
X119721Y-533585D01*
X119151Y-533335D01*
X118581Y-533418D01*
X118011Y-533752D01*
G01X122921Y-537752D02*
X123365Y-538168D01*
X123871Y-538335D01*
X124378Y-538168D01*
X124821Y-537668D01*
X125138Y-536918D01*
X125265Y-536168D01*
Y-535252D01*
X125138Y-534502D01*
X124821Y-533835D01*
X124441Y-533502D01*
X123998Y-533335D01*
X123491Y-533502D01*
X123111Y-533835D01*
X122858Y-534335D01*
X122731Y-535002D01*
X122858Y-535585D01*
X123175Y-536168D01*
X123555Y-536502D01*
X123998Y-536585D01*
X124505Y-536418D01*
X124885Y-536002D01*
X125265Y-535252D01*
G01X128971Y-538335D02*
X129098Y-537252D01*
X129288Y-536335D01*
X129541Y-535502D01*
X129858Y-534585D01*
X130365Y-533335D01*
X127831D01*
G01X133375Y-536668D02*
X135021D01*
G01X137905Y-537335D02*
X138285Y-537918D01*
X138791Y-538252D01*
X139361Y-538335D01*
X139868Y-538252D01*
X140375Y-537835D01*
X140691Y-537335D01*
X140755Y-536835D01*
X140628Y-536252D01*
X140185Y-535835D01*
X139741Y-535668D01*
X139171D01*
G01X139741D02*
X140121Y-535418D01*
X140438Y-535002D01*
X140565Y-534502D01*
X140438Y-534002D01*
X140121Y-533585D01*
X139551Y-533335D01*
X138981Y-533418D01*
X138411Y-533752D01*
G01X143195Y-536252D02*
X143638Y-535668D01*
X144018Y-535335D01*
X144525Y-535168D01*
X144968Y-535335D01*
X145285Y-535668D01*
X145538Y-536168D01*
X145601Y-536752D01*
X145538Y-537252D01*
X145285Y-537752D01*
X144905Y-538168D01*
X144461Y-538335D01*
X143955Y-538168D01*
X143511Y-537668D01*
X143258Y-536918D01*
X143195Y-536085D01*
X143321Y-535002D01*
X143511Y-534418D01*
X143828Y-533835D01*
X144271Y-533418D01*
X144715Y-533335D01*
X145158Y-533502D01*
X145475Y-533918D01*
G01X149498Y-538335D02*
Y-533335D01*
X148738Y-534335D01*
G01Y-538335D02*
X150258D01*
G01X155358D02*
Y-533335D01*
X153015Y-536918D01*
X156181D01*
G01X174398Y-468335D02*
Y-543335D01*
G01Y-518335D02*
X277398D01*
Y-493335D01*
G01X174398D02*
X277398D01*
G01Y-468335D02*
Y-543335D01*
G01X279398Y-468335D02*
Y-543335D01*
G01X284905Y-528335D02*
Y-523335D01*
X286171D01*
X286678Y-523585D01*
X287058Y-523918D01*
X287375Y-524418D01*
X287628Y-525002D01*
X287691Y-525835D01*
X287628Y-526668D01*
X287375Y-527252D01*
X287058Y-527752D01*
X286678Y-528085D01*
X286171Y-528335D01*
X284905D01*
G01X289815D02*
X291398Y-523335D01*
X292981Y-528335D01*
G01X292411Y-526585D02*
X290385D01*
G01X296498Y-523335D02*
Y-528335D01*
G01X295041Y-523335D02*
X297955D01*
G01X302865Y-528335D02*
X300331D01*
Y-523335D01*
X302865D01*
G01X301851Y-525752D02*
X300331D01*
G01X306698Y-528502D02*
X306571Y-528418D01*
Y-528252D01*
X306698Y-528168D01*
X306825Y-528252D01*
Y-528418D01*
X306698Y-528502D01*
G01Y-526252D02*
X306571Y-526168D01*
Y-526002D01*
X306698Y-525918D01*
X306825Y-526002D01*
Y-526168D01*
X306698Y-526252D01*
G01X279398Y-518335D02*
X479398D01*
G01X285031Y-503335D02*
Y-498335D01*
X286551D01*
X287058Y-498585D01*
X287438Y-499168D01*
X287565Y-499835D01*
X287438Y-500502D01*
X287121Y-501002D01*
X286551Y-501252D01*
X285031D01*
G01X290258Y-503502D02*
X292538Y-498335D01*
G01X295041Y-503335D02*
Y-498335D01*
X297955Y-503335D01*
Y-498335D01*
G01X301598Y-503502D02*
X301471Y-503418D01*
Y-503252D01*
X301598Y-503168D01*
X301725Y-503252D01*
Y-503418D01*
X301598Y-503502D01*
G01Y-501252D02*
X301471Y-501168D01*
Y-501002D01*
X301598Y-500918D01*
X301725Y-501002D01*
Y-501168D01*
X301598Y-501252D01*
G01X279398Y-493335D02*
X479398D01*
G01X285031Y-478335D02*
Y-473335D01*
X286551D01*
X287058Y-473585D01*
X287438Y-474168D01*
X287565Y-474835D01*
X287438Y-475502D01*
X287121Y-476002D01*
X286551Y-476252D01*
X285031D01*
G01X290131Y-478335D02*
Y-473335D01*
X291715D01*
X292221Y-473585D01*
X292538Y-473918D01*
X292665Y-474585D01*
X292538Y-475252D01*
X292158Y-475668D01*
X291715Y-475918D01*
X290131D01*
G01X291715D02*
X292665Y-478335D01*
G01X296498D02*
X295991Y-478252D01*
X295548Y-477918D01*
X295168Y-477418D01*
X294915Y-476835D01*
X294788Y-476168D01*
Y-475502D01*
X294915Y-474835D01*
X295168Y-474252D01*
X295548Y-473752D01*
X295991Y-473418D01*
X296498Y-473335D01*
X297005Y-473418D01*
X297448Y-473752D01*
X297828Y-474252D01*
X298081Y-474835D01*
X298208Y-475502D01*
Y-476168D01*
X298081Y-476835D01*
X297828Y-477418D01*
X297448Y-477918D01*
X297005Y-478252D01*
X296498Y-478335D01*
G01X300331Y-477335D02*
X300648Y-477835D01*
X301028Y-478168D01*
X301471Y-478335D01*
X301978Y-478168D01*
X302358Y-477835D01*
X302738Y-477335D01*
X302865Y-476668D01*
Y-473335D01*
G01X307965Y-478335D02*
X305431D01*
Y-473335D01*
X307965D01*
G01X306951Y-475752D02*
X305431D01*
G01X313191Y-473752D02*
X312811Y-473502D01*
X312368Y-473335D01*
X311861D01*
X311291Y-473585D01*
X310848Y-474002D01*
X310531Y-474502D01*
X310278Y-475335D01*
X310215Y-476085D01*
X310341Y-476835D01*
X310531Y-477335D01*
X310911Y-477835D01*
X311355Y-478168D01*
X311798Y-478335D01*
X312241D01*
X312685Y-478168D01*
X313065Y-477918D01*
X313381Y-477585D01*
G01X316898Y-473335D02*
Y-478335D01*
G01X315441Y-473335D02*
X318355D01*
G01X321998Y-478502D02*
X321871Y-478418D01*
Y-478252D01*
X321998Y-478168D01*
X322125Y-478252D01*
Y-478418D01*
X321998Y-478502D01*
G01Y-476252D02*
X321871Y-476168D01*
Y-476002D01*
X321998Y-475918D01*
X322125Y-476002D01*
Y-476168D01*
X321998Y-476252D01*
G01X394258Y-543563D02*
Y-518563D01*
G01X397031Y-520835D02*
Y-525835D01*
X399565D01*
G01X402638Y-520835D02*
X404158D01*
G01X403398D02*
Y-525835D01*
G01X402638D02*
X404158D01*
G01X409005Y-523168D02*
X409258Y-522918D01*
X409448Y-522502D01*
X409575Y-521918D01*
X409448Y-521418D01*
X409195Y-521085D01*
X408751Y-520835D01*
X407041D01*
Y-525835D01*
X409131D01*
X409575Y-525502D01*
X409828Y-525002D01*
X409955Y-524418D01*
X409828Y-523835D01*
X409448Y-523335D01*
X409005Y-523168D01*
X407041D01*
G01X413598Y-526002D02*
X413471Y-525918D01*
Y-525752D01*
X413598Y-525668D01*
X413725Y-525752D01*
Y-525918D01*
X413598Y-526002D01*
G01Y-523752D02*
X413471Y-523668D01*
Y-523502D01*
X413598Y-523418D01*
X413725Y-523502D01*
Y-523668D01*
X413598Y-523752D01*
G01X437258Y-518563D02*
Y-543563D01*
G01X437398Y-518335D02*
Y-543335D01*
G01X441298Y-520835D02*
Y-525835D01*
G01X439841Y-520835D02*
X442755D01*
G01X446398Y-525835D02*
X446018Y-525752D01*
X445638Y-525418D01*
X445385Y-524835D01*
X445258Y-524168D01*
X445385Y-523502D01*
X445638Y-522918D01*
X446018Y-522585D01*
X446398Y-522502D01*
X446778Y-522585D01*
X447158Y-522918D01*
X447411Y-523502D01*
X447475Y-524168D01*
X447411Y-524835D01*
X447158Y-525418D01*
X446778Y-525752D01*
X446398Y-525835D01*
G01X451498D02*
X451118Y-525752D01*
X450738Y-525418D01*
X450485Y-524835D01*
X450358Y-524168D01*
X450485Y-523502D01*
X450738Y-522918D01*
X451118Y-522585D01*
X451498Y-522502D01*
X451878Y-522585D01*
X452258Y-522918D01*
X452511Y-523502D01*
X452575Y-524168D01*
X452511Y-524835D01*
X452258Y-525418D01*
X451878Y-525752D01*
X451498Y-525835D01*
G01X456598D02*
Y-520835D01*
G01X461698Y-526002D02*
X461571Y-525918D01*
Y-525752D01*
X461698Y-525668D01*
X461825Y-525752D01*
Y-525918D01*
X461698Y-526002D01*
G01Y-523752D02*
X461571Y-523668D01*
Y-523502D01*
X461698Y-523418D01*
X461825Y-523502D01*
Y-523668D01*
X461698Y-523752D01*
G01X437398Y-493335D02*
Y-518335D01*
G01X440031Y-500835D02*
Y-495835D01*
X441615D01*
X442121Y-496085D01*
X442438Y-496418D01*
X442565Y-497085D01*
X442438Y-497752D01*
X442058Y-498168D01*
X441615Y-498418D01*
X440031D01*
G01X441615D02*
X442565Y-500835D01*
G01X447665D02*
X445131D01*
Y-495835D01*
X447665D01*
G01X446651Y-498252D02*
X445131D01*
G01X449915Y-495835D02*
X451498Y-500835D01*
X453081Y-495835D01*
G01X456598Y-501002D02*
X456471Y-500918D01*
Y-500752D01*
X456598Y-500668D01*
X456725Y-500752D01*
Y-500918D01*
X456598Y-501002D01*
G01Y-498752D02*
X456471Y-498668D01*
Y-498502D01*
X456598Y-498418D01*
X456725Y-498502D01*
Y-498668D01*
X456598Y-498752D01*
G01X445411Y-546502D02*
X445518Y-546377D01*
X445598Y-546168D01*
X445651Y-545877D01*
X445598Y-545627D01*
X445491Y-545460D01*
X445305Y-545335D01*
X444585D01*
Y-547835D01*
X445465D01*
X445651Y-547668D01*
X445758Y-547418D01*
X445811Y-547127D01*
X445758Y-546835D01*
X445598Y-546585D01*
X445411Y-546502D01*
X444585D01*
G01X447878Y-547835D02*
Y-546168D01*
G01Y-546460D02*
X447771Y-546293D01*
X447611Y-546210D01*
X447425Y-546168D01*
X447238Y-546252D01*
X447078Y-546418D01*
X446971Y-546668D01*
X446918Y-547002D01*
X446971Y-547335D01*
X447078Y-547585D01*
X447238Y-547752D01*
X447425Y-547835D01*
X447611Y-547793D01*
X447771Y-547668D01*
X447878Y-547502D01*
G01X449198Y-547543D02*
X449331Y-547710D01*
X449518Y-547835D01*
X449678D01*
X449838Y-547752D01*
X449945Y-547627D01*
X449998Y-547460D01*
X449971Y-547210D01*
X449865Y-547085D01*
X449385Y-546835D01*
X449278Y-546543D01*
X449331Y-546335D01*
X449438Y-546210D01*
X449598Y-546168D01*
X449758Y-546210D01*
X449918Y-546335D01*
G01X451398Y-546710D02*
X452251D01*
X452171Y-546418D01*
X452038Y-546252D01*
X451851Y-546168D01*
X451665Y-546210D01*
X451505Y-546335D01*
X451398Y-546627D01*
X451345Y-546877D01*
Y-547127D01*
X451398Y-547377D01*
X451531Y-547627D01*
X451691Y-547793D01*
X451878Y-547835D01*
X452065Y-547752D01*
X452251Y-547502D01*
G01X453518Y-547835D02*
Y-545335D01*
G01Y-546585D02*
X453651Y-546335D01*
X453811Y-546210D01*
X453971Y-546168D01*
X454211Y-546252D01*
X454371Y-546418D01*
X454478Y-546710D01*
Y-547043D01*
X454425Y-547377D01*
X454318Y-547627D01*
X454131Y-547793D01*
X453971Y-547835D01*
X453811Y-547793D01*
X453651Y-547668D01*
X453518Y-547460D01*
G01X456198Y-547835D02*
X456038Y-547793D01*
X455878Y-547627D01*
X455771Y-547335D01*
X455718Y-547002D01*
X455771Y-546668D01*
X455878Y-546377D01*
X456038Y-546210D01*
X456198Y-546168D01*
X456358Y-546210D01*
X456518Y-546377D01*
X456625Y-546668D01*
X456651Y-547002D01*
X456625Y-547335D01*
X456518Y-547627D01*
X456358Y-547793D01*
X456198Y-547835D01*
G01X458878D02*
Y-546168D01*
G01Y-546460D02*
X458771Y-546293D01*
X458611Y-546210D01*
X458425Y-546168D01*
X458238Y-546252D01*
X458078Y-546418D01*
X457971Y-546668D01*
X457918Y-547002D01*
X457971Y-547335D01*
X458078Y-547585D01*
X458238Y-547752D01*
X458425Y-547835D01*
X458611Y-547793D01*
X458771Y-547668D01*
X458878Y-547502D01*
G01X460225Y-547835D02*
Y-546168D01*
G01Y-546502D02*
X460358Y-546335D01*
X460491Y-546210D01*
X460678Y-546168D01*
X460811Y-546210D01*
X460971Y-546335D01*
G01X463278Y-545335D02*
Y-547835D01*
G01Y-547460D02*
X463171Y-547668D01*
X463011Y-547793D01*
X462825Y-547835D01*
X462611Y-547752D01*
X462451Y-547543D01*
X462345Y-547293D01*
X462318Y-547002D01*
X462345Y-546710D01*
X462451Y-546460D01*
X462611Y-546252D01*
X462825Y-546168D01*
X463011Y-546210D01*
X463145Y-546293D01*
X463278Y-546460D01*
G01X466665Y-547835D02*
Y-545335D01*
X467331D01*
X467545Y-545460D01*
X467678Y-545627D01*
X467731Y-545960D01*
X467678Y-546293D01*
X467518Y-546502D01*
X467331Y-546627D01*
X466665D01*
G01X467331D02*
X467731Y-547835D01*
G01X468998Y-546710D02*
X469851D01*
X469771Y-546418D01*
X469638Y-546252D01*
X469451Y-546168D01*
X469265Y-546210D01*
X469105Y-546335D01*
X468998Y-546627D01*
X468945Y-546877D01*
Y-547127D01*
X468998Y-547377D01*
X469131Y-547627D01*
X469291Y-547793D01*
X469478Y-547835D01*
X469665Y-547752D01*
X469851Y-547502D01*
G01X471118Y-546168D02*
X471598Y-547835D01*
X472078Y-546168D01*
G01X473798Y-547918D02*
X473745Y-547877D01*
Y-547793D01*
X473798Y-547752D01*
X473851Y-547793D01*
Y-547877D01*
X473798Y-547918D01*
G01X475545Y-547543D02*
X475731Y-547752D01*
X475945Y-547835D01*
X476158Y-547752D01*
X476345Y-547502D01*
X476478Y-547127D01*
X476531Y-546752D01*
Y-546293D01*
X476478Y-545918D01*
X476345Y-545585D01*
X476185Y-545418D01*
X475998Y-545335D01*
X475785Y-545418D01*
X475625Y-545585D01*
X475518Y-545835D01*
X475465Y-546168D01*
X475518Y-546460D01*
X475651Y-546752D01*
X475811Y-546918D01*
X475998Y-546960D01*
X476211Y-546877D01*
X476371Y-546668D01*
X476531Y-546293D01*
G01X478411Y-546502D02*
X478518Y-546377D01*
X478598Y-546168D01*
X478651Y-545877D01*
X478598Y-545627D01*
X478491Y-545460D01*
X478305Y-545335D01*
X477585D01*
Y-547835D01*
X478465D01*
X478651Y-547668D01*
X478758Y-547418D01*
X478811Y-547127D01*
X478758Y-546835D01*
X478598Y-546585D01*
X478411Y-546502D01*
X477585D01*
G01X-1490433Y-1677216D02*
Y3837819D01*
X4496476D01*
Y-1677216D01*
X-1490433D01*
G01X-7782Y-515685D02*
X-6215D01*
Y-517575D01*
X-6685Y-518205D01*
X-7234Y-518625D01*
X-8017Y-518835D01*
X-8800Y-518625D01*
X-9349Y-518205D01*
X-9819Y-517575D01*
X-10132Y-516840D01*
X-10289Y-516000D01*
Y-515265D01*
X-10132Y-514635D01*
X-9819Y-513900D01*
X-9349Y-513270D01*
X-8879Y-512850D01*
X-8252Y-512535D01*
X-7704D01*
X-7077Y-512745D01*
X-6607Y-513165D01*
G01X-3675Y-512535D02*
Y-517050D01*
X-3362Y-517995D01*
X-2735Y-518625D01*
X-1952Y-518835D01*
X-1169Y-518625D01*
X-542Y-517995D01*
X-229Y-517050D01*
Y-512535D01*
G01X3408D02*
X5288D01*
G01X4348D02*
Y-518835D01*
G01X3408D02*
X5288D01*
G01X9003Y-517995D02*
X9630Y-518520D01*
X10335Y-518835D01*
X10961D01*
X11588Y-518520D01*
X12058Y-517995D01*
X12293Y-517260D01*
X12136Y-516525D01*
X11745Y-515895D01*
X11040Y-515475D01*
X10100Y-515265D01*
X9551Y-514845D01*
X9316Y-514110D01*
X9473Y-513375D01*
X9865Y-512850D01*
X10413Y-512535D01*
X10961D01*
X11510Y-512745D01*
X11980Y-513270D01*
G01X15303Y-518835D02*
Y-512535D01*
G01X18593D02*
Y-518835D01*
G01Y-515685D02*
X15303D01*
G01X21290Y-518835D02*
X23248Y-512535D01*
X25206Y-518835D01*
G01X24501Y-516630D02*
X21995D01*
G01X27746Y-518835D02*
Y-512535D01*
X31350Y-518835D01*
Y-512535D01*
G01X40425Y-518835D02*
Y-512535D01*
X41991D01*
X42618Y-512850D01*
X43088Y-513270D01*
X43480Y-513900D01*
X43793Y-514635D01*
X43871Y-515685D01*
X43793Y-516735D01*
X43480Y-517470D01*
X43088Y-518100D01*
X42618Y-518520D01*
X41991Y-518835D01*
X40425D01*
G01X47508Y-512535D02*
X49388D01*
G01X48448D02*
Y-518835D01*
G01X47508D02*
X49388D01*
G01X53103Y-517995D02*
X53730Y-518520D01*
X54435Y-518835D01*
X55061D01*
X55688Y-518520D01*
X56158Y-517995D01*
X56393Y-517260D01*
X56236Y-516525D01*
X55845Y-515895D01*
X55140Y-515475D01*
X54200Y-515265D01*
X53651Y-514845D01*
X53416Y-514110D01*
X53573Y-513375D01*
X53965Y-512850D01*
X54513Y-512535D01*
X55061D01*
X55610Y-512745D01*
X56080Y-513270D01*
G01X61048Y-512535D02*
Y-518835D01*
G01X59246Y-512535D02*
X62850D01*
G01X67348Y-519045D02*
X67191Y-518940D01*
Y-518730D01*
X67348Y-518625D01*
X67505Y-518730D01*
Y-518940D01*
X67348Y-519045D01*
G01X73491Y-519990D02*
X73805Y-518625D01*
G01X79948Y-512535D02*
Y-518835D01*
G01X78146Y-512535D02*
X81750D01*
G01X84290Y-518835D02*
X86248Y-512535D01*
X88206Y-518835D01*
G01X87501Y-516630D02*
X84995D01*
G01X92548Y-518835D02*
X91921Y-518730D01*
X91373Y-518310D01*
X90903Y-517680D01*
X90590Y-516945D01*
X90433Y-516105D01*
Y-515265D01*
X90590Y-514425D01*
X90903Y-513690D01*
X91373Y-513060D01*
X91921Y-512640D01*
X92548Y-512535D01*
X93175Y-512640D01*
X93723Y-513060D01*
X94193Y-513690D01*
X94506Y-514425D01*
X94663Y-515265D01*
Y-516105D01*
X94506Y-516945D01*
X94193Y-517680D01*
X93723Y-518310D01*
X93175Y-518730D01*
X92548Y-518835D01*
G01X98848D02*
Y-516000D01*
X97281Y-512535D01*
G01X100415D02*
X98848Y-516000D01*
G01X103425Y-512535D02*
Y-517050D01*
X103738Y-517995D01*
X104365Y-518625D01*
X105148Y-518835D01*
X105931Y-518625D01*
X106558Y-517995D01*
X106871Y-517050D01*
Y-512535D01*
G01X109490Y-518835D02*
X111448Y-512535D01*
X113406Y-518835D01*
G01X112701Y-516630D02*
X110195D01*
G01X115946Y-518835D02*
Y-512535D01*
X119550Y-518835D01*
Y-512535D01*
G01X-6529Y-523060D02*
X-6999Y-522745D01*
X-7547Y-522535D01*
X-8174D01*
X-8879Y-522850D01*
X-9427Y-523375D01*
X-9819Y-524005D01*
X-10132Y-525055D01*
X-10210Y-526000D01*
X-10054Y-526945D01*
X-9819Y-527575D01*
X-9349Y-528205D01*
X-8800Y-528625D01*
X-8252Y-528835D01*
X-7704D01*
X-7155Y-528625D01*
X-6685Y-528310D01*
X-6294Y-527890D01*
G01X-2892Y-522535D02*
X-1012D01*
G01X-1952D02*
Y-528835D01*
G01X-2892D02*
X-1012D01*
G01X4348Y-522535D02*
Y-528835D01*
G01X2546Y-522535D02*
X6150D01*
G01X10648Y-528835D02*
Y-526000D01*
X9081Y-522535D01*
G01X12215D02*
X10648Y-526000D01*
G01X21525Y-527575D02*
X21995Y-528310D01*
X22621Y-528730D01*
X23326Y-528835D01*
X23953Y-528730D01*
X24580Y-528205D01*
X24971Y-527575D01*
X25050Y-526945D01*
X24893Y-526210D01*
X24345Y-525685D01*
X23796Y-525475D01*
X23091D01*
G01X23796D02*
X24266Y-525160D01*
X24658Y-524635D01*
X24815Y-524005D01*
X24658Y-523375D01*
X24266Y-522850D01*
X23561Y-522535D01*
X22856Y-522640D01*
X22151Y-523060D01*
G01X27825Y-527575D02*
X28295Y-528310D01*
X28921Y-528730D01*
X29626Y-528835D01*
X30253Y-528730D01*
X30880Y-528205D01*
X31271Y-527575D01*
X31350Y-526945D01*
X31193Y-526210D01*
X30645Y-525685D01*
X30096Y-525475D01*
X29391D01*
G01X30096D02*
X30566Y-525160D01*
X30958Y-524635D01*
X31115Y-524005D01*
X30958Y-523375D01*
X30566Y-522850D01*
X29861Y-522535D01*
X29156Y-522640D01*
X28451Y-523060D01*
G01X34125Y-527575D02*
X34595Y-528310D01*
X35221Y-528730D01*
X35926Y-528835D01*
X36553Y-528730D01*
X37180Y-528205D01*
X37571Y-527575D01*
X37650Y-526945D01*
X37493Y-526210D01*
X36945Y-525685D01*
X36396Y-525475D01*
X35691D01*
G01X36396D02*
X36866Y-525160D01*
X37258Y-524635D01*
X37415Y-524005D01*
X37258Y-523375D01*
X36866Y-522850D01*
X36161Y-522535D01*
X35456Y-522640D01*
X34751Y-523060D01*
G01X41991Y-528835D02*
X42148Y-527470D01*
X42383Y-526315D01*
X42696Y-525265D01*
X43088Y-524110D01*
X43715Y-522535D01*
X40581D01*
G01X48291Y-528835D02*
X48448Y-527470D01*
X48683Y-526315D01*
X48996Y-525265D01*
X49388Y-524110D01*
X50015Y-522535D01*
X46881D01*
G01X54591Y-529990D02*
X54905Y-528625D01*
G01X61048Y-522535D02*
Y-528835D01*
G01X59246Y-522535D02*
X62850D01*
G01X65390Y-528835D02*
X67348Y-522535D01*
X69306Y-528835D01*
G01X68601Y-526630D02*
X66095D01*
G01X72708Y-522535D02*
X74588D01*
G01X73648D02*
Y-528835D01*
G01X72708D02*
X74588D01*
G01X77598Y-522535D02*
X78695Y-528835D01*
X79948Y-522535D01*
X81201Y-528835D01*
X82298Y-522535D01*
G01X84290Y-528835D02*
X86248Y-522535D01*
X88206Y-528835D01*
G01X87501Y-526630D02*
X84995D01*
G01X90746Y-528835D02*
Y-522535D01*
X94350Y-528835D01*
Y-522535D01*
G01X104756Y-530935D02*
X103973Y-529885D01*
X103581Y-528835D01*
Y-524635D01*
X103973Y-523585D01*
X104756Y-522535D01*
G01X116181Y-528835D02*
Y-522535D01*
X118140D01*
X118766Y-522850D01*
X119158Y-523270D01*
X119315Y-524110D01*
X119158Y-524950D01*
X118688Y-525475D01*
X118140Y-525790D01*
X116181D01*
G01X118140D02*
X119315Y-528835D01*
G01X124048Y-529045D02*
X123891Y-528940D01*
Y-528730D01*
X124048Y-528625D01*
X124205Y-528730D01*
Y-528940D01*
X124048Y-529045D01*
G01X130348Y-528835D02*
X129721Y-528730D01*
X129173Y-528310D01*
X128703Y-527680D01*
X128390Y-526945D01*
X128233Y-526105D01*
Y-525265D01*
X128390Y-524425D01*
X128703Y-523690D01*
X129173Y-523060D01*
X129721Y-522640D01*
X130348Y-522535D01*
X130975Y-522640D01*
X131523Y-523060D01*
X131993Y-523690D01*
X132306Y-524425D01*
X132463Y-525265D01*
Y-526105D01*
X132306Y-526945D01*
X131993Y-527680D01*
X131523Y-528310D01*
X130975Y-528730D01*
X130348Y-528835D01*
G01X136648Y-529045D02*
X136491Y-528940D01*
Y-528730D01*
X136648Y-528625D01*
X136805Y-528730D01*
Y-528940D01*
X136648Y-529045D01*
G01X144671Y-523060D02*
X144201Y-522745D01*
X143653Y-522535D01*
X143026D01*
X142321Y-522850D01*
X141773Y-523375D01*
X141381Y-524005D01*
X141068Y-525055D01*
X140990Y-526000D01*
X141146Y-526945D01*
X141381Y-527575D01*
X141851Y-528205D01*
X142400Y-528625D01*
X142948Y-528835D01*
X143496D01*
X144045Y-528625D01*
X144515Y-528310D01*
X144906Y-527890D01*
G01X149248Y-529045D02*
X149091Y-528940D01*
Y-528730D01*
X149248Y-528625D01*
X149405Y-528730D01*
Y-528940D01*
X149248Y-529045D01*
G01X155940Y-530935D02*
X156723Y-529885D01*
X157115Y-528835D01*
Y-524635D01*
X156723Y-523585D01*
X155940Y-522535D01*
G01X-10054Y-508835D02*
Y-502535D01*
X-6450Y-508835D01*
Y-502535D01*
G01X-1952Y-508835D02*
X-2579Y-508730D01*
X-3127Y-508310D01*
X-3597Y-507680D01*
X-3910Y-506945D01*
X-4067Y-506105D01*
Y-505265D01*
X-3910Y-504425D01*
X-3597Y-503690D01*
X-3127Y-503060D01*
X-2579Y-502640D01*
X-1952Y-502535D01*
X-1325Y-502640D01*
X-777Y-503060D01*
X-307Y-503690D01*
X6Y-504425D01*
X163Y-505265D01*
Y-506105D01*
X6Y-506945D01*
X-307Y-507680D01*
X-777Y-508310D01*
X-1325Y-508730D01*
X-1952Y-508835D01*
G01X4348Y-509045D02*
X4191Y-508940D01*
Y-508730D01*
X4348Y-508625D01*
X4505Y-508730D01*
Y-508940D01*
X4348Y-509045D01*
G01X9160Y-503585D02*
X9630Y-502955D01*
X10178Y-502640D01*
X10805Y-502535D01*
X11588Y-502745D01*
X12136Y-503270D01*
X12293Y-503900D01*
X12215Y-504530D01*
X11901Y-505055D01*
X10335Y-506105D01*
X9630Y-506840D01*
X9160Y-507890D01*
X9003Y-508835D01*
X12293D01*
G01X16948D02*
Y-502535D01*
X16008Y-503795D01*
G01Y-508835D02*
X17888D01*
G01X23248D02*
Y-502535D01*
X22308Y-503795D01*
G01Y-508835D02*
X24188D01*
G01X29391Y-509990D02*
X29705Y-508625D01*
G01X33498Y-502535D02*
X34595Y-508835D01*
X35848Y-502535D01*
X37101Y-508835D01*
X38198Y-502535D01*
G01X43715Y-508835D02*
X40581D01*
Y-502535D01*
X43715D01*
G01X42461Y-505580D02*
X40581D01*
G01X46646Y-508835D02*
Y-502535D01*
X50250Y-508835D01*
Y-502535D01*
G01X53103Y-508835D02*
Y-502535D01*
G01X56393D02*
Y-508835D01*
G01Y-505685D02*
X53103D01*
G01X59325Y-502535D02*
Y-507050D01*
X59638Y-507995D01*
X60265Y-508625D01*
X61048Y-508835D01*
X61831Y-508625D01*
X62458Y-507995D01*
X62771Y-507050D01*
Y-502535D01*
G01X65390Y-508835D02*
X67348Y-502535D01*
X69306Y-508835D01*
G01X68601Y-506630D02*
X66095D01*
G01X78460Y-503585D02*
X78930Y-502955D01*
X79478Y-502640D01*
X80105Y-502535D01*
X80888Y-502745D01*
X81436Y-503270D01*
X81593Y-503900D01*
X81515Y-504530D01*
X81201Y-505055D01*
X79635Y-506105D01*
X78930Y-506840D01*
X78460Y-507890D01*
X78303Y-508835D01*
X81593D01*
G01X84446D02*
Y-502535D01*
X88050Y-508835D01*
Y-502535D01*
G01X90825Y-508835D02*
Y-502535D01*
X92391D01*
X93018Y-502850D01*
X93488Y-503270D01*
X93880Y-503900D01*
X94193Y-504635D01*
X94271Y-505685D01*
X94193Y-506735D01*
X93880Y-507470D01*
X93488Y-508100D01*
X93018Y-508520D01*
X92391Y-508835D01*
X90825D01*
G01X103581D02*
Y-502535D01*
X105540D01*
X106166Y-502850D01*
X106558Y-503270D01*
X106715Y-504110D01*
X106558Y-504950D01*
X106088Y-505475D01*
X105540Y-505790D01*
X103581D01*
G01X105540D02*
X106715Y-508835D01*
G01X109725D02*
Y-502535D01*
X111291D01*
X111918Y-502850D01*
X112388Y-503270D01*
X112780Y-503900D01*
X113093Y-504635D01*
X113171Y-505685D01*
X113093Y-506735D01*
X112780Y-507470D01*
X112388Y-508100D01*
X111918Y-508520D01*
X111291Y-508835D01*
X109725D01*
G01X117748Y-509045D02*
X117591Y-508940D01*
Y-508730D01*
X117748Y-508625D01*
X117905Y-508730D01*
Y-508940D01*
X117748Y-509045D01*
G01X14048Y-498135D02*
X11528Y-497718D01*
X9323Y-496052D01*
X7433Y-493552D01*
X6173Y-490635D01*
X5543Y-487302D01*
Y-483968D01*
X6173Y-480635D01*
X7433Y-477718D01*
X9323Y-475219D01*
X11528Y-473552D01*
X14048Y-473135D01*
X16568Y-473552D01*
X18773Y-475219D01*
X20663Y-477718D01*
X21923Y-480635D01*
X22553Y-483968D01*
Y-487302D01*
X21923Y-490635D01*
X20663Y-493552D01*
X18773Y-496052D01*
X16568Y-497718D01*
X14048Y-498135D01*
G01X16568Y-491468D02*
X20348Y-498135D01*
G01X33893Y-481469D02*
Y-493135D01*
X35153Y-496052D01*
X37043Y-497718D01*
X39248Y-498135D01*
X41453Y-497718D01*
X43343Y-496052D01*
X44603Y-493135D01*
G01Y-498135D02*
Y-481469D01*
G01X70118Y-498135D02*
Y-481469D01*
G01Y-484385D02*
X68858Y-482719D01*
X66968Y-481885D01*
X64763Y-481469D01*
X62558Y-482302D01*
X60668Y-483968D01*
X59408Y-486469D01*
X58778Y-489802D01*
X59408Y-493135D01*
X60668Y-495636D01*
X62558Y-497302D01*
X64763Y-498135D01*
X66968Y-497718D01*
X68858Y-496469D01*
X70118Y-494802D01*
G01X84293Y-498135D02*
Y-481469D01*
G01Y-485635D02*
X85553Y-483552D01*
X87443Y-481885D01*
X89963Y-481469D01*
X92168Y-481885D01*
X94058Y-483552D01*
X95003Y-486469D01*
Y-498135D01*
G01X114848Y-473135D02*
Y-498135D01*
G01X110438Y-481469D02*
X119258D01*
G01X145718Y-498135D02*
Y-481469D01*
G01Y-484385D02*
X144458Y-482719D01*
X142568Y-481885D01*
X140363Y-481469D01*
X138158Y-482302D01*
X136268Y-483968D01*
X135008Y-486469D01*
X134378Y-489802D01*
X135008Y-493135D01*
X136268Y-495636D01*
X138158Y-497302D01*
X140363Y-498135D01*
X142568Y-497718D01*
X144458Y-496469D01*
X145718Y-494802D01*
G01X185398Y-477835D02*
Y-485835D01*
X189398D01*
G01X197198D02*
Y-480502D01*
G01Y-481435D02*
X196798Y-480902D01*
X196198Y-480635D01*
X195498Y-480502D01*
X194798Y-480768D01*
X194198Y-481302D01*
X193798Y-482102D01*
X193598Y-483168D01*
X193798Y-484235D01*
X194198Y-485035D01*
X194798Y-485568D01*
X195498Y-485835D01*
X196198Y-485702D01*
X196798Y-485302D01*
X197198Y-484769D01*
G01X201298Y-488235D02*
X201898Y-488502D01*
X202698Y-488235D01*
X203198Y-487702D01*
X203598Y-487035D01*
X204198Y-484902D01*
X205498Y-480502D01*
G01X202298D02*
X204198Y-484902D01*
G01X209898Y-482235D02*
X213098D01*
X212798Y-481302D01*
X212298Y-480768D01*
X211598Y-480502D01*
X210898Y-480635D01*
X210298Y-481035D01*
X209898Y-481968D01*
X209698Y-482769D01*
Y-483568D01*
X209898Y-484368D01*
X210398Y-485168D01*
X210998Y-485702D01*
X211698Y-485835D01*
X212398Y-485568D01*
X213098Y-484769D01*
G01X217998Y-485835D02*
Y-480502D01*
G01Y-481568D02*
X218498Y-481035D01*
X218998Y-480635D01*
X219698Y-480502D01*
X220198Y-480635D01*
X220798Y-481035D01*
G01X211398Y-535835D02*
Y-532235D01*
X209398Y-527835D01*
G01X213398D02*
X211398Y-532235D01*
G01X217698Y-530502D02*
Y-534235D01*
X218098Y-535168D01*
X218698Y-535702D01*
X219398Y-535835D01*
X220098Y-535702D01*
X220698Y-535168D01*
X221098Y-534235D01*
G01Y-535835D02*
Y-530502D01*
G01X225698Y-535835D02*
Y-530502D01*
G01Y-531835D02*
X226098Y-531168D01*
X226698Y-530635D01*
X227498Y-530502D01*
X228198Y-530635D01*
X228798Y-531168D01*
X229098Y-532102D01*
Y-535835D01*
G01X237198D02*
Y-530502D01*
G01Y-531435D02*
X236798Y-530902D01*
X236198Y-530635D01*
X235498Y-530502D01*
X234798Y-530768D01*
X234198Y-531302D01*
X233798Y-532102D01*
X233598Y-533168D01*
X233798Y-534235D01*
X234198Y-535035D01*
X234798Y-535568D01*
X235498Y-535835D01*
X236198Y-535702D01*
X236798Y-535302D01*
X237198Y-534769D01*
G01X213198Y-506235D02*
X215198D01*
Y-508635D01*
X214598Y-509435D01*
X213898Y-509968D01*
X212898Y-510235D01*
X211898Y-509968D01*
X211198Y-509435D01*
X210598Y-508635D01*
X210198Y-507702D01*
X209998Y-506635D01*
Y-505702D01*
X210198Y-504902D01*
X210598Y-503968D01*
X211198Y-503168D01*
X211798Y-502635D01*
X212598Y-502235D01*
X213298D01*
X214098Y-502502D01*
X214698Y-503035D01*
G01X218298Y-510235D02*
Y-502235D01*
X222898Y-510235D01*
Y-502235D01*
G01X226398Y-510235D02*
Y-502235D01*
X228398D01*
X229198Y-502635D01*
X229798Y-503168D01*
X230298Y-503968D01*
X230698Y-504902D01*
X230798Y-506235D01*
X230698Y-507568D01*
X230298Y-508502D01*
X229798Y-509302D01*
X229198Y-509835D01*
X228398Y-510235D01*
X226398D01*
G01X234398Y-509035D02*
X234998Y-509702D01*
X235698Y-510102D01*
X236598Y-510235D01*
X237498Y-509968D01*
X238198Y-509435D01*
X238698Y-508502D01*
X238798Y-507435D01*
X238598Y-506368D01*
X238098Y-505702D01*
X237398Y-505168D01*
X236698Y-505035D01*
X235998Y-505168D01*
X235098Y-505702D01*
X235398Y-502235D01*
X238098D01*
G01X247398Y-486535D02*
Y-478535D01*
X246198Y-480135D01*
G01Y-486535D02*
X248598D01*
G01X253198Y-484935D02*
X253798Y-485868D01*
X254598Y-486402D01*
X255498Y-486535D01*
X256298Y-486402D01*
X257098Y-485735D01*
X257598Y-484935D01*
X257698Y-484135D01*
X257498Y-483202D01*
X256798Y-482535D01*
X256098Y-482268D01*
X255198D01*
G01X256098D02*
X256698Y-481868D01*
X257198Y-481202D01*
X257398Y-480402D01*
X257198Y-479602D01*
X256698Y-478935D01*
X255798Y-478535D01*
X254898Y-478668D01*
X253998Y-479202D01*
G01X311998Y-529168D02*
X312598Y-528368D01*
X313298Y-527968D01*
X314098Y-527835D01*
X315098Y-528102D01*
X315798Y-528768D01*
X315998Y-529568D01*
X315898Y-530369D01*
X315498Y-531035D01*
X313498Y-532368D01*
X312598Y-533302D01*
X311998Y-534635D01*
X311798Y-535835D01*
X315998D01*
G01X321898Y-527835D02*
X321098Y-528102D01*
X320498Y-528768D01*
X320098Y-529568D01*
X319798Y-530635D01*
X319698Y-531835D01*
X319798Y-533035D01*
X320098Y-534102D01*
X320498Y-534902D01*
X321098Y-535568D01*
X321898Y-535835D01*
X322698Y-535568D01*
X323298Y-534902D01*
X323698Y-534102D01*
X323998Y-533035D01*
X324098Y-531835D01*
X323998Y-530635D01*
X323698Y-529568D01*
X323298Y-528768D01*
X322698Y-528102D01*
X321898Y-527835D01*
G01X327998Y-529168D02*
X328598Y-528368D01*
X329298Y-527968D01*
X330098Y-527835D01*
X331098Y-528102D01*
X331798Y-528768D01*
X331998Y-529568D01*
X331898Y-530369D01*
X331498Y-531035D01*
X329498Y-532368D01*
X328598Y-533302D01*
X327998Y-534635D01*
X327798Y-535835D01*
X331998D01*
G01X335698Y-534235D02*
X336298Y-535168D01*
X337098Y-535702D01*
X337998Y-535835D01*
X338798Y-535702D01*
X339598Y-535035D01*
X340098Y-534235D01*
X340198Y-533435D01*
X339998Y-532502D01*
X339298Y-531835D01*
X338598Y-531568D01*
X337698D01*
G01X338598D02*
X339198Y-531168D01*
X339698Y-530502D01*
X339898Y-529702D01*
X339698Y-528902D01*
X339198Y-528235D01*
X338298Y-527835D01*
X337398Y-527968D01*
X336498Y-528502D01*
G01X344098Y-536102D02*
X347698Y-527835D01*
G01X353898D02*
X353098Y-528102D01*
X352498Y-528768D01*
X352098Y-529568D01*
X351798Y-530635D01*
X351698Y-531835D01*
X351798Y-533035D01*
X352098Y-534102D01*
X352498Y-534902D01*
X353098Y-535568D01*
X353898Y-535835D01*
X354698Y-535568D01*
X355298Y-534902D01*
X355698Y-534102D01*
X355998Y-533035D01*
X356098Y-531835D01*
X355998Y-530635D01*
X355698Y-529568D01*
X355298Y-528768D01*
X354698Y-528102D01*
X353898Y-527835D01*
G01X361898Y-535835D02*
Y-527835D01*
X360698Y-529435D01*
G01Y-535835D02*
X363098D01*
G01X368098Y-536102D02*
X371698Y-527835D01*
G01X377898D02*
X377098Y-528102D01*
X376498Y-528768D01*
X376098Y-529568D01*
X375798Y-530635D01*
X375698Y-531835D01*
X375798Y-533035D01*
X376098Y-534102D01*
X376498Y-534902D01*
X377098Y-535568D01*
X377898Y-535835D01*
X378698Y-535568D01*
X379298Y-534902D01*
X379698Y-534102D01*
X379998Y-533035D01*
X380098Y-531835D01*
X379998Y-530635D01*
X379698Y-529568D01*
X379298Y-528768D01*
X378698Y-528102D01*
X377898Y-527835D01*
G01X384198Y-534902D02*
X384898Y-535568D01*
X385698Y-535835D01*
X386498Y-535568D01*
X387198Y-534769D01*
X387698Y-533568D01*
X387898Y-532368D01*
Y-530902D01*
X387698Y-529702D01*
X387198Y-528635D01*
X386598Y-528102D01*
X385898Y-527835D01*
X385098Y-528102D01*
X384498Y-528635D01*
X384098Y-529435D01*
X383898Y-530502D01*
X384098Y-531435D01*
X384598Y-532368D01*
X385198Y-532902D01*
X385898Y-533035D01*
X386698Y-532769D01*
X387298Y-532102D01*
X387898Y-530902D01*
G01X311698Y-510835D02*
Y-502835D01*
X313698D01*
X314498Y-503235D01*
X315098Y-503768D01*
X315598Y-504568D01*
X315998Y-505502D01*
X316098Y-506835D01*
X315998Y-508168D01*
X315598Y-509102D01*
X315098Y-509902D01*
X314498Y-510435D01*
X313698Y-510835D01*
X311698D01*
G01X319398D02*
X321898Y-502835D01*
X324398Y-510835D01*
G01X323498Y-508035D02*
X320298D01*
G01X329898Y-502835D02*
X329098Y-503102D01*
X328498Y-503768D01*
X328098Y-504568D01*
X327798Y-505635D01*
X327698Y-506835D01*
X327798Y-508035D01*
X328098Y-509102D01*
X328498Y-509902D01*
X329098Y-510568D01*
X329898Y-510835D01*
X330698Y-510568D01*
X331298Y-509902D01*
X331698Y-509102D01*
X331998Y-508035D01*
X332098Y-506835D01*
X331998Y-505635D01*
X331698Y-504568D01*
X331298Y-503768D01*
X330698Y-503102D01*
X329898Y-502835D01*
G01X335998Y-510835D02*
Y-502835D01*
X339798D01*
G01X338398Y-506702D02*
X335998D01*
G01X345898Y-502835D02*
X345098Y-503102D01*
X344498Y-503768D01*
X344098Y-504568D01*
X343798Y-505635D01*
X343698Y-506835D01*
X343798Y-508035D01*
X344098Y-509102D01*
X344498Y-509902D01*
X345098Y-510568D01*
X345898Y-510835D01*
X346698Y-510568D01*
X347298Y-509902D01*
X347698Y-509102D01*
X347998Y-508035D01*
X348098Y-506835D01*
X347998Y-505635D01*
X347698Y-504568D01*
X347298Y-503768D01*
X346698Y-503102D01*
X345898Y-502835D01*
G01X353898D02*
Y-510835D01*
G01X351598Y-502835D02*
X356198D01*
G01X363898Y-510835D02*
X359898D01*
Y-502835D01*
X363898D01*
G01X362298Y-506702D02*
X359898D01*
G01X370698Y-506568D02*
X371098Y-506168D01*
X371398Y-505502D01*
X371598Y-504568D01*
X371398Y-503768D01*
X370998Y-503235D01*
X370298Y-502835D01*
X367598D01*
Y-510835D01*
X370898D01*
X371598Y-510302D01*
X371998Y-509502D01*
X372198Y-508568D01*
X371998Y-507635D01*
X371398Y-506835D01*
X370698Y-506568D01*
X367598D01*
G01X376698Y-502835D02*
X379098D01*
G01X377898D02*
Y-510835D01*
G01X376698D02*
X379098D01*
G01X383998D02*
Y-502835D01*
X387798D01*
G01X386398Y-506702D02*
X383998D01*
G01X393898Y-502835D02*
X393098Y-503102D01*
X392498Y-503768D01*
X392098Y-504568D01*
X391798Y-505635D01*
X391698Y-506835D01*
X391798Y-508035D01*
X392098Y-509102D01*
X392498Y-509902D01*
X393098Y-510568D01*
X393898Y-510835D01*
X394698Y-510568D01*
X395298Y-509902D01*
X395698Y-509102D01*
X395998Y-508035D01*
X396098Y-506835D01*
X395998Y-505635D01*
X395698Y-504568D01*
X395298Y-503768D01*
X394698Y-503102D01*
X393898Y-502835D01*
G01X329498Y-485835D02*
Y-477835D01*
X333298D01*
G01X331898Y-481702D02*
X329498D01*
G01X339398Y-477835D02*
X338598Y-478102D01*
X337998Y-478768D01*
X337598Y-479568D01*
X337298Y-480635D01*
X337198Y-481835D01*
X337298Y-483035D01*
X337598Y-484102D01*
X337998Y-484902D01*
X338598Y-485568D01*
X339398Y-485835D01*
X340198Y-485568D01*
X340798Y-484902D01*
X341198Y-484102D01*
X341498Y-483035D01*
X341598Y-481835D01*
X341498Y-480635D01*
X341198Y-479568D01*
X340798Y-478768D01*
X340198Y-478102D01*
X339398Y-477835D01*
G01X347398D02*
Y-485835D01*
G01X345098Y-477835D02*
X349698D01*
G01X352398Y-488502D02*
X358398D01*
G01X361898Y-482235D02*
X365098D01*
X364798Y-481302D01*
X364298Y-480768D01*
X363598Y-480502D01*
X362898Y-480635D01*
X362298Y-481035D01*
X361898Y-481968D01*
X361698Y-482769D01*
Y-483568D01*
X361898Y-484368D01*
X362398Y-485168D01*
X362998Y-485702D01*
X363698Y-485835D01*
X364398Y-485568D01*
X365098Y-484769D01*
G01X369898Y-480502D02*
X372898Y-485835D01*
G01Y-480502D02*
X369898Y-485835D01*
G01X377598Y-488502D02*
Y-480502D01*
G01Y-481702D02*
X378098Y-481035D01*
X378598Y-480635D01*
X379398Y-480502D01*
X380098Y-480635D01*
X380798Y-481302D01*
X381098Y-482235D01*
X381198Y-483168D01*
X381098Y-484102D01*
X380798Y-485035D01*
X380198Y-485568D01*
X379398Y-485835D01*
X378698Y-485702D01*
X377998Y-485302D01*
X377598Y-484769D01*
G01X389198Y-485835D02*
Y-480502D01*
G01Y-481435D02*
X388798Y-480902D01*
X388198Y-480635D01*
X387498Y-480502D01*
X386798Y-480768D01*
X386198Y-481302D01*
X385798Y-482102D01*
X385598Y-483168D01*
X385798Y-484235D01*
X386198Y-485035D01*
X386798Y-485568D01*
X387498Y-485835D01*
X388198Y-485702D01*
X388798Y-485302D01*
X389198Y-484769D01*
G01X393698Y-485835D02*
Y-480502D01*
G01Y-481835D02*
X394098Y-481168D01*
X394698Y-480635D01*
X395498Y-480502D01*
X396198Y-480635D01*
X396798Y-481168D01*
X397098Y-482102D01*
Y-485835D01*
G01X405198Y-477835D02*
Y-485835D01*
G01Y-484635D02*
X404798Y-485302D01*
X404198Y-485702D01*
X403498Y-485835D01*
X402698Y-485568D01*
X402098Y-484902D01*
X401698Y-484102D01*
X401598Y-483168D01*
X401698Y-482235D01*
X402098Y-481435D01*
X402698Y-480768D01*
X403498Y-480502D01*
X404198Y-480635D01*
X404698Y-480902D01*
X405198Y-481435D01*
G01X409898Y-482235D02*
X413098D01*
X412798Y-481302D01*
X412298Y-480768D01*
X411598Y-480502D01*
X410898Y-480635D01*
X410298Y-481035D01*
X409898Y-481968D01*
X409698Y-482769D01*
Y-483568D01*
X409898Y-484368D01*
X410398Y-485168D01*
X410998Y-485702D01*
X411698Y-485835D01*
X412398Y-485568D01*
X413098Y-484769D01*
G01X417998Y-485835D02*
Y-480502D01*
G01Y-481568D02*
X418498Y-481035D01*
X418998Y-480635D01*
X419698Y-480502D01*
X420198Y-480635D01*
X420798Y-481035D01*
G01X424398Y-488502D02*
X430398D01*
G01X433598Y-485835D02*
Y-477835D01*
G01Y-481835D02*
X434098Y-481035D01*
X434698Y-480635D01*
X435298Y-480502D01*
X436198Y-480768D01*
X436798Y-481302D01*
X437198Y-482235D01*
Y-483302D01*
X436998Y-484368D01*
X436598Y-485168D01*
X435898Y-485702D01*
X435298Y-485835D01*
X434698Y-485702D01*
X434098Y-485302D01*
X433598Y-484635D01*
G01X445198Y-477835D02*
Y-485835D01*
G01Y-484635D02*
X444798Y-485302D01*
X444198Y-485702D01*
X443498Y-485835D01*
X442698Y-485568D01*
X442098Y-484902D01*
X441698Y-484102D01*
X441598Y-483168D01*
X441698Y-482235D01*
X442098Y-481435D01*
X442698Y-480768D01*
X443498Y-480502D01*
X444198Y-480635D01*
X444698Y-480902D01*
X445198Y-481435D01*
G01X400398Y-538835D02*
Y-530835D01*
X399198Y-532435D01*
G01Y-538835D02*
X401598D01*
G01X406498Y-535502D02*
X407198Y-534568D01*
X407798Y-534035D01*
X408598Y-533768D01*
X409298Y-534035D01*
X409798Y-534568D01*
X410198Y-535368D01*
X410298Y-536302D01*
X410198Y-537102D01*
X409798Y-537902D01*
X409198Y-538568D01*
X408498Y-538835D01*
X407698Y-538568D01*
X406998Y-537769D01*
X406598Y-536568D01*
X406498Y-535235D01*
X406698Y-533502D01*
X406998Y-532568D01*
X407498Y-531635D01*
X408198Y-530968D01*
X408898Y-530835D01*
X409598Y-531102D01*
X410098Y-531768D01*
G01X416398Y-539102D02*
X416198Y-538968D01*
Y-538702D01*
X416398Y-538568D01*
X416598Y-538702D01*
Y-538968D01*
X416398Y-539102D01*
G01X422498Y-535502D02*
X423198Y-534568D01*
X423798Y-534035D01*
X424598Y-533768D01*
X425298Y-534035D01*
X425798Y-534568D01*
X426198Y-535368D01*
X426298Y-536302D01*
X426198Y-537102D01*
X425798Y-537902D01*
X425198Y-538568D01*
X424498Y-538835D01*
X423698Y-538568D01*
X422998Y-537769D01*
X422598Y-536568D01*
X422498Y-535235D01*
X422698Y-533502D01*
X422998Y-532568D01*
X423498Y-531635D01*
X424198Y-530968D01*
X424898Y-530835D01*
X425598Y-531102D01*
X426098Y-531768D01*
G01X445398Y-538835D02*
Y-530835D01*
X444198Y-532435D01*
G01Y-538835D02*
X446598D01*
G01X453198D02*
X453398Y-537102D01*
X453698Y-535635D01*
X454098Y-534302D01*
X454598Y-532835D01*
X455398Y-530835D01*
X451398D01*
G01X461398Y-539102D02*
X461198Y-538968D01*
Y-538702D01*
X461398Y-538568D01*
X461598Y-538702D01*
Y-538968D01*
X461398Y-539102D01*
G01X467498Y-532168D02*
X468098Y-531368D01*
X468798Y-530968D01*
X469598Y-530835D01*
X470598Y-531102D01*
X471298Y-531768D01*
X471498Y-532568D01*
X471398Y-533369D01*
X470998Y-534035D01*
X468998Y-535368D01*
X468098Y-536302D01*
X467498Y-537635D01*
X467298Y-538835D01*
X471498D01*
G01X465498Y-513835D02*
Y-505835D01*
X469298D01*
G01X467898Y-509702D02*
X465498D01*
M02*
